G04 ================== begin FILE IDENTIFICATION RECORD ==================*
G04 Layout Name:  9324_DA0F0TMBIJ0_F0T_Motherboard_J_v01_20230324_0910.brd*
G04 Film Name:    gnd1*
G04 File Format:  Gerber RS274X*
G04 File Origin:  Cadence Allegro 17.2-S081*
G04 Origin Date:  Sat Mar 25 08:45:04 2023*
G04 *
G04 Layer:  DRAWING FORMAT/TITLE_BLOCK_A*
G04 Layer:  PIN/SPECIAL_DRILL*
G04 Layer:  VIA CLASS/GND1*
G04 Layer:  PIN/GND1*
G04 Layer:  MANUFACTURING/PHOTOPLOT_OUTLINE*
G04 Layer:  ETCH/GND1*
G04 Layer:  DRAWING FORMAT/TITLE_BLOCK*
G04 Layer:  DRAWING FORMAT/TITLE_DATA_GND1*
G04 *
G04 Offset:    (0.00 0.00)*
G04 Mirror:    No*
G04 Mode:      Negative*
G04 Rotation:  0*
G04 FullContactRelief:  No*
G04 UndefLineWidth:     6.00*
G04 ================== end FILE IDENTIFICATION RECORD ====================*
%FSLAX25Y25*MOIN*%
%IR0*IPPOS*OFA0.00000B0.00000*MIA0B0*SFA1.00000B1.00000*%
%ADD15C,.03*%
%ADD31C,.06*%
%ADD45C,.061*%
%ADD26C,.07*%
%AMMACRO54*
4,1,36,0.0,.01,
-.001736,.009848,
-.00342,.009397,
-.005,.00866,
-.006428,.00766,
-.00766,.006428,
-.00866,.005,
-.009397,.00342,
-.009848,.001736,
-.01,0.0,
-.009848,-.001736,
-.009397,-.00342,
-.00866,-.005,
-.00766,-.006428,
-.006428,-.00766,
-.005,-.00866,
-.00342,-.009397,
-.001736,-.009848,
0.0,-.01,
.001736,-.009848,
.00342,-.009397,
.005,-.00866,
.006428,-.00766,
.00766,-.006428,
.00866,-.005,
.009397,-.00342,
.009848,-.001736,
.01,0.0,
.009848,.001736,
.009397,.00342,
.00866,.005,
.00766,.006428,
.006428,.00766,
.005,.00866,
.00342,.009397,
.001736,.009848,
0.0,.01,
0.0*
%
%ADD54MACRO54*%
%ADD51C,.071*%
%ADD29C,.062*%
%ADD17C,.026*%
%AMMACRO70*
4,1,36,.0025,0.0,
.002462,.000434,
.002349,.000855,
.002165,.00125,
.001915,.001607,
.001607,.001915,
.00125,.002165,
.000855,.002349,
.000434,.002462,
0.0,.0025,
-.000434,.002462,
-.000855,.002349,
-.00125,.002165,
-.001607,.001915,
-.001915,.001607,
-.002165,.00125,
-.002349,.000855,
-.002462,.000434,
-.0025,0.0,
-.002462,-.000434,
-.002349,-.000855,
-.002165,-.00125,
-.001915,-.001607,
-.001607,-.001915,
-.00125,-.002165,
-.000855,-.002349,
-.000434,-.002462,
0.0,-.0025,
.000434,-.002462,
.000855,-.002349,
.00125,-.002165,
.001607,-.001915,
.001915,-.001607,
.002165,-.00125,
.002349,-.000855,
.002462,-.000434,
.0025,0.0,
135.*
%
%ADD70MACRO70*%
%ADD66C,.064*%
%AMMACRO19*
4,1,36,.0025,0.0,
.002462,.000434,
.002349,.000855,
.002165,.00125,
.001915,.001607,
.001607,.001915,
.00125,.002165,
.000855,.002349,
.000434,.002462,
0.0,.0025,
-.000434,.002462,
-.000855,.002349,
-.00125,.002165,
-.001607,.001915,
-.001915,.001607,
-.002165,.00125,
-.002349,.000855,
-.002462,.000434,
-.0025,0.0,
-.002462,-.000434,
-.002349,-.000855,
-.002165,-.00125,
-.001915,-.001607,
-.001607,-.001915,
-.00125,-.002165,
-.000855,-.002349,
-.000434,-.002462,
0.0,-.0025,
.000434,-.002462,
.000855,-.002349,
.00125,-.002165,
.001607,-.001915,
.001915,-.001607,
.002165,-.00125,
.002349,-.000855,
.002462,-.000434,
.0025,0.0,
225.*
%
%ADD19MACRO19*%
%AMMACRO14*
4,1,36,.0025,0.0,
.002462,.000434,
.002349,.000855,
.002165,.00125,
.001915,.001607,
.001607,.001915,
.00125,.002165,
.000855,.002349,
.000434,.002462,
0.0,.0025,
-.000434,.002462,
-.000855,.002349,
-.00125,.002165,
-.001607,.001915,
-.001915,.001607,
-.002165,.00125,
-.002349,.000855,
-.002462,.000434,
-.0025,0.0,
-.002462,-.000434,
-.002349,-.000855,
-.002165,-.00125,
-.001915,-.001607,
-.001607,-.001915,
-.00125,-.002165,
-.000855,-.002349,
-.000434,-.002462,
0.0,-.0025,
.000434,-.002462,
.000855,-.002349,
.00125,-.002165,
.001607,-.001915,
.001915,-.001607,
.002165,-.00125,
.002349,-.000855,
.002462,-.000434,
.0025,0.0,
180.*
%
%ADD14MACRO14*%
%AMMACRO11*
4,1,36,.0025,0.0,
.002462,.000434,
.002349,.000855,
.002165,.00125,
.001915,.001607,
.001607,.001915,
.00125,.002165,
.000855,.002349,
.000434,.002462,
0.0,.0025,
-.000434,.002462,
-.000855,.002349,
-.00125,.002165,
-.001607,.001915,
-.001915,.001607,
-.002165,.00125,
-.002349,.000855,
-.002462,.000434,
-.0025,0.0,
-.002462,-.000434,
-.002349,-.000855,
-.002165,-.00125,
-.001915,-.001607,
-.001607,-.001915,
-.00125,-.002165,
-.000855,-.002349,
-.000434,-.002462,
0.0,-.0025,
.000434,-.002462,
.000855,-.002349,
.00125,-.002165,
.001607,-.001915,
.001915,-.001607,
.002165,-.00125,
.002349,-.000855,
.002462,-.000434,
.0025,0.0,
270.*
%
%ADD11MACRO11*%
%AMMACRO52*
4,1,36,-.0025,0.0,
-.002462,.000434,
-.002349,.000855,
-.002165,.00125,
-.001915,.001607,
-.001607,.001915,
-.00125,.002165,
-.000855,.002349,
-.000434,.002462,
0.0,.0025,
.000434,.002462,
.000855,.002349,
.00125,.002165,
.001607,.001915,
.001915,.001607,
.002165,.00125,
.002349,.000855,
.002462,.000434,
.0025,0.0,
.002462,-.000434,
.002349,-.000855,
.002165,-.00125,
.001915,-.001607,
.001607,-.001915,
.00125,-.002165,
.000855,-.002349,
.000434,-.002462,
0.0,-.0025,
-.000434,-.002462,
-.000855,-.002349,
-.00125,-.002165,
-.001607,-.001915,
-.001915,-.001607,
-.002165,-.00125,
-.002349,-.000855,
-.002462,-.000434,
-.0025,0.0,
180.*
%
%ADD52MACRO52*%
%AMMACRO43*
4,1,36,.003,0.0,
.002954,.000521,
.002819,.001026,
.002598,.0015,
.002298,.001928,
.001928,.002298,
.0015,.002598,
.001026,.002819,
.000521,.002954,
0.0,.003,
-.000521,.002954,
-.001026,.002819,
-.0015,.002598,
-.001928,.002298,
-.002298,.001928,
-.002598,.0015,
-.002819,.001026,
-.002954,.000521,
-.003,0.0,
-.002954,-.000521,
-.002819,-.001026,
-.002598,-.0015,
-.002298,-.001928,
-.001928,-.002298,
-.0015,-.002598,
-.001026,-.002819,
-.000521,-.002954,
0.0,-.003,
.000521,-.002954,
.001026,-.002819,
.0015,-.002598,
.001928,-.002298,
.002298,-.001928,
.002598,-.0015,
.002819,-.001026,
.002954,-.000521,
.003,0.0,
270.*
%
%ADD43MACRO43*%
%AMMACRO41*
4,1,36,.003,0.0,
.002954,.000521,
.002819,.001026,
.002598,.0015,
.002298,.001928,
.001928,.002298,
.0015,.002598,
.001026,.002819,
.000521,.002954,
0.0,.003,
-.000521,.002954,
-.001026,.002819,
-.0015,.002598,
-.001928,.002298,
-.002298,.001928,
-.002598,.0015,
-.002819,.001026,
-.002954,.000521,
-.003,0.0,
-.002954,-.000521,
-.002819,-.001026,
-.002598,-.0015,
-.002298,-.001928,
-.001928,-.002298,
-.0015,-.002598,
-.001026,-.002819,
-.000521,-.002954,
0.0,-.003,
.000521,-.002954,
.001026,-.002819,
.0015,-.002598,
.001928,-.002298,
.002298,-.001928,
.002598,-.0015,
.002819,-.001026,
.002954,-.000521,
.003,0.0,
180.*
%
%ADD41MACRO41*%
%ADD25C,.074*%
%AMMACRO73*
4,1,36,-.003,0.0,
-.002954,.000521,
-.002819,.001026,
-.002598,.0015,
-.002298,.001928,
-.001928,.002298,
-.0015,.002598,
-.001026,.002819,
-.000521,.002954,
0.0,.003,
.000521,.002954,
.001026,.002819,
.0015,.002598,
.001928,.002298,
.002298,.001928,
.002598,.0015,
.002819,.001026,
.002954,.000521,
.003,0.0,
.002954,-.000521,
.002819,-.001026,
.002598,-.0015,
.002298,-.001928,
.001928,-.002298,
.0015,-.002598,
.001026,-.002819,
.000521,-.002954,
0.0,-.003,
-.000521,-.002954,
-.001026,-.002819,
-.0015,-.002598,
-.001928,-.002298,
-.002298,-.001928,
-.002598,-.0015,
-.002819,-.001026,
-.002954,-.000521,
-.003,0.0,
270.*
%
%ADD73MACRO73*%
%ADD72C,.0435*%
%ADD62C,.06015*%
%ADD49C,.076*%
%ADD48C,.095*%
%ADD27C,.0257*%
%ADD75C,.087*%
%ADD35C,.03417*%
%ADD40C,.0259*%
%ADD22C,.0277*%
%AMMACRO39*
4,1,15,.06231,.03403,
.067273,.022693,
.070191,.010666,
.070977,-.001684,
.069606,-.013984,
.066121,-.025858,
.06231,-.03403,
.06745,-.03917,
.073227,-.026862,
.076779,-.013739,
.077998,-.000197,
.076848,.01335,
.073362,.026492,
.067647,.038828,
.06745,.03917,
.06231,.03403,
0.0*
4,1,15,.03403,-.06231,
.022693,-.067273,
.010666,-.070191,
-.001684,-.070977,
-.013984,-.069606,
-.025858,-.066121,
-.03403,-.06231,
-.03917,-.06745,
-.026862,-.073227,
-.013739,-.076779,
-.000197,-.077998,
.01335,-.076848,
.026492,-.073362,
.038828,-.067647,
.03917,-.06745,
.03403,-.06231,
0.0*
4,1,15,-.06231,-.03403,
-.067273,-.022693,
-.070191,-.010666,
-.070977,.001684,
-.069606,.013984,
-.066121,.025858,
-.06231,.03403,
-.06745,.03917,
-.073227,.026862,
-.076779,.013739,
-.077998,.000197,
-.076848,-.01335,
-.073362,-.026492,
-.067647,-.038828,
-.06745,-.03917,
-.06231,-.03403,
0.0*
4,1,15,-.03403,.06231,
-.022693,.067273,
-.010666,.070191,
.001684,.070977,
.013984,.069606,
.025858,.066121,
.03403,.06231,
.03917,.06745,
.026862,.073227,
.013739,.076779,
.000197,.077998,
-.01335,.076848,
-.026492,.073362,
-.038828,.067647,
-.03917,.06745,
-.03403,.06231,
0.0*
%
%ADD39MACRO39*%
%AMMACRO10*
4,1,18,.09673,.06845,
.107147,.050613,
.114308,.031238,
.117996,.010914,
.118098,-.009741,
.114613,-.030101,
.107644,-.049546,
.097406,-.067485,
.09673,-.06845,
.10175,-.07347,
.112962,-.054685,
.120742,-.034239,
.124853,-.012752,
.125171,.009122,
.121685,.030719,
.114502,.051383,
.10384,.070486,
.10175,.07347,
.09673,.06845,
0.0*
4,1,18,.06845,-.09673,
.050613,-.107147,
.031238,-.114308,
.010914,-.117996,
-.009741,-.118098,
-.030101,-.114613,
-.049546,-.107644,
-.067485,-.097406,
-.06845,-.09673,
-.07347,-.10175,
-.054685,-.112962,
-.034239,-.120742,
-.012752,-.124853,
.009122,-.125171,
.030719,-.121685,
.051383,-.114502,
.070486,-.10384,
.07347,-.10175,
.06845,-.09673,
0.0*
4,1,18,-.09673,-.06845,
-.107147,-.050613,
-.114308,-.031238,
-.117996,-.010914,
-.118098,.009741,
-.114613,.030101,
-.107644,.049546,
-.097406,.067485,
-.09673,.06845,
-.10175,.07347,
-.112962,.054685,
-.120742,.034239,
-.124853,.012752,
-.125171,-.009122,
-.121685,-.030719,
-.114502,-.051383,
-.10384,-.070486,
-.10175,-.07347,
-.09673,-.06845,
0.0*
4,1,18,-.06845,.09673,
-.050613,.107147,
-.031238,.114308,
-.010914,.117996,
.009741,.118098,
.030101,.114613,
.049546,.107644,
.067485,.097406,
.06845,.09673,
.07347,.10175,
.054685,.112962,
.034239,.120742,
.012752,.124853,
-.009122,.125171,
-.030719,.121685,
-.051383,.114502,
-.070486,.10384,
-.07347,.10175,
-.06845,.09673,
0.0*
%
%ADD10MACRO10*%
%AMMACRO36*
4,1,16,.0711,.04282,
.077455,.029823,
.081457,.01592,
.082984,.001533,
.08199,-.0129,
.078504,-.026942,
.072633,-.040164,
.0711,-.04282,
.07619,-.04791,
.083352,-.033952,
.087981,-.018962,
.089937,-.003396,
.089161,.012273,
.085675,.027569,
.079586,.042027,
.07619,.04791,
.0711,.04282,
0.0*
4,1,16,.04282,-.0711,
.029823,-.077455,
.01592,-.081457,
.001533,-.082984,
-.0129,-.08199,
-.026942,-.078504,
-.040164,-.072633,
-.04282,-.0711,
-.04791,-.07619,
-.033952,-.083352,
-.018962,-.087981,
-.003396,-.089937,
.012273,-.089161,
.027569,-.085675,
.042027,-.079586,
.04791,-.07619,
.04282,-.0711,
0.0*
4,1,16,-.0711,-.04282,
-.077455,-.029823,
-.081457,-.01592,
-.082984,-.001533,
-.08199,.0129,
-.078504,.026942,
-.072633,.040164,
-.0711,.04282,
-.07619,.04791,
-.083352,.033952,
-.087981,.018962,
-.089937,.003396,
-.089161,-.012273,
-.085675,-.027569,
-.079586,-.042027,
-.07619,-.04791,
-.0711,-.04282,
0.0*
4,1,16,-.04282,.0711,
-.029823,.077455,
-.01592,.081457,
-.001533,.082984,
.0129,.08199,
.026942,.078504,
.040164,.072633,
.04282,.0711,
.04791,.07619,
.033952,.083352,
.018962,.087981,
.003396,.089937,
-.012273,.089161,
-.027569,.085675,
-.042027,.079586,
-.04791,.07619,
-.04282,.0711,
0.0*
%
%ADD36MACRO36*%
%AMMACRO32*
4,1,15,.02438,.01377,
.026401,.009327,
.027619,.004601,
.027999,-.000265,
.027527,-.005123,
.02622,-.009825,
.02438,-.01377,
.02948,-.01887,
.032309,-.013464,
.034156,-.007649,
.034965,-.001602,
.034712,.004494,
.033405,.010454,
.031082,.016095,
.02948,.01887,
.02438,.01377,
90.*
4,1,15,.01377,-.02438,
.009327,-.026401,
.004601,-.027619,
-.000265,-.027999,
-.005123,-.027527,
-.009825,-.02622,
-.01377,-.02438,
-.01887,-.02948,
-.013464,-.032309,
-.007649,-.034156,
-.001602,-.034965,
.004494,-.034712,
.010454,-.033405,
.016095,-.031082,
.01887,-.02948,
.01377,-.02438,
90.*
4,1,15,-.02438,-.01377,
-.026401,-.009327,
-.027619,-.004601,
-.027999,.000265,
-.027527,.005123,
-.02622,.009825,
-.02438,.01377,
-.02948,.01887,
-.032309,.013464,
-.034156,.007649,
-.034965,.001602,
-.034712,-.004494,
-.033405,-.010454,
-.031082,-.016095,
-.02948,-.01887,
-.02438,-.01377,
90.*
4,1,15,-.01377,.02438,
-.009327,.026401,
-.004601,.027619,
.000265,.027999,
.005123,.027527,
.009825,.02622,
.01377,.02438,
.01887,.02948,
.013464,.032309,
.007649,.034156,
.001602,.034965,
-.004494,.034712,
-.010454,.033405,
-.016095,.031082,
-.01887,.02948,
-.01377,.02438,
90.*
%
%ADD32MACRO32*%
%AMMACRO30*
4,1,15,.02438,.01377,
.026401,.009327,
.027619,.004601,
.027999,-.000265,
.027527,-.005123,
.02622,-.009825,
.02438,-.01377,
.02948,-.01887,
.032309,-.013464,
.034156,-.007649,
.034965,-.001602,
.034712,.004494,
.033405,.010454,
.031082,.016095,
.02948,.01887,
.02438,.01377,
0.0*
4,1,15,.01377,-.02438,
.009327,-.026401,
.004601,-.027619,
-.000265,-.027999,
-.005123,-.027527,
-.009825,-.02622,
-.01377,-.02438,
-.01887,-.02948,
-.013464,-.032309,
-.007649,-.034156,
-.001602,-.034965,
.004494,-.034712,
.010454,-.033405,
.016095,-.031082,
.01887,-.02948,
.01377,-.02438,
0.0*
4,1,15,-.02438,-.01377,
-.026401,-.009327,
-.027619,-.004601,
-.027999,.000265,
-.027527,.005123,
-.02622,.009825,
-.02438,.01377,
-.02948,.01887,
-.032309,.013464,
-.034156,.007649,
-.034965,.001602,
-.034712,-.004494,
-.033405,-.010454,
-.031082,-.016095,
-.02948,-.01887,
-.02438,-.01377,
0.0*
4,1,15,-.01377,.02438,
-.009327,.026401,
-.004601,.027619,
.000265,.027999,
.005123,.027527,
.009825,.02622,
.01377,.02438,
.01887,.02948,
.013464,.032309,
.007649,.034156,
.001602,.034965,
-.004494,.034712,
-.010454,.033405,
-.016095,.031082,
-.01887,.02948,
-.01377,.02438,
0.0*
%
%ADD30MACRO30*%
%AMMACRO47*
4,1,15,.02475,.01414,
.026829,.009627,
.028094,.004822,
.028504,-.000129,
.028049,-.005077,
.026741,-.009871,
.02475,-.01414,
.02984,-.01923,
.032726,-.013756,
.034617,-.007864,
.035457,-.001734,
.03522,.00445,
.033912,.010498,
.031574,.016227,
.02984,.01923,
.02475,.01414,
90.*
4,1,15,.01414,-.02475,
.009627,-.026829,
.004822,-.028094,
-.000129,-.028504,
-.005077,-.028049,
-.009871,-.026741,
-.01414,-.02475,
-.01923,-.02984,
-.013756,-.032726,
-.007864,-.034617,
-.001734,-.035457,
.00445,-.03522,
.010498,-.033912,
.016227,-.031574,
.01923,-.02984,
.01414,-.02475,
90.*
4,1,15,-.02475,-.01414,
-.026829,-.009627,
-.028094,-.004822,
-.028504,.000129,
-.028049,.005077,
-.026741,.009871,
-.02475,.01414,
-.02984,.01923,
-.032726,.013756,
-.034617,.007864,
-.035457,.001734,
-.03522,-.00445,
-.033912,-.010498,
-.031574,-.016227,
-.02984,-.01923,
-.02475,-.01414,
90.*
4,1,15,-.01414,.02475,
-.009627,.026829,
-.004822,.028094,
.000129,.028504,
.005077,.028049,
.009871,.026741,
.01414,.02475,
.01923,.02984,
.013756,.032726,
.007864,.034617,
.001734,.035457,
-.00445,.03522,
-.010498,.033912,
-.016227,.031574,
-.01923,.02984,
-.01414,.02475,
90.*
%
%ADD47MACRO47*%
%AMMACRO65*
4,1,18,.07103,.05689,
.07983,.043691,
.086204,.029165,
.089959,.013753,
.09098,-.002077,
.089237,-.017844,
.084783,-.033069,
.077753,-.047289,
.07103,-.05689,
.07601,-.06186,
.085597,-.047721,
.092583,-.032132,
.096757,-.015567,
.09799,.001471,
.096246,.018464,
.091577,.034897,
.084126,.050269,
.07601,.06186,
.07103,.05689,
0.0*
4,1,18,.05689,-.07103,
.043691,-.07983,
.029165,-.086204,
.013753,-.089959,
-.002077,-.09098,
-.017844,-.089237,
-.033069,-.084783,
-.047289,-.077753,
-.05689,-.07103,
-.06186,-.07601,
-.047721,-.085597,
-.032132,-.092583,
-.015567,-.096757,
.001471,-.09799,
.018464,-.096246,
.034897,-.091577,
.050269,-.084126,
.06186,-.07601,
.05689,-.07103,
0.0*
4,1,18,-.07103,-.05689,
-.07983,-.043691,
-.086204,-.029165,
-.089959,-.013753,
-.09098,.002077,
-.089237,.017844,
-.084783,.033069,
-.077753,.047289,
-.07103,.05689,
-.07601,.06186,
-.085597,.047721,
-.092583,.032132,
-.096757,.015567,
-.09799,-.001471,
-.096246,-.018464,
-.091577,-.034897,
-.084126,-.050269,
-.07601,-.06186,
-.07103,-.05689,
0.0*
4,1,18,-.05689,.07103,
-.043691,.07983,
-.029165,.086204,
-.013753,.089959,
.002077,.09098,
.017844,.089237,
.033069,.084783,
.047289,.077753,
.05689,.07103,
.06186,.07601,
.047721,.085597,
.032132,.092583,
.015567,.096757,
-.001471,.09799,
-.018464,.096246,
-.034897,.091577,
-.050269,.084126,
-.06186,.07601,
-.05689,.07103,
0.0*
%
%ADD65MACRO65*%
%AMMACRO50*
4,1,15,.02475,.01414,
.026829,.009627,
.028094,.004822,
.028504,-.000129,
.028049,-.005077,
.026741,-.009871,
.02475,-.01414,
.02984,-.01923,
.032726,-.013756,
.034617,-.007864,
.035457,-.001734,
.03522,.00445,
.033912,.010498,
.031574,.016227,
.02984,.01923,
.02475,.01414,
0.0*
4,1,15,.01414,-.02475,
.009627,-.026829,
.004822,-.028094,
-.000129,-.028504,
-.005077,-.028049,
-.009871,-.026741,
-.01414,-.02475,
-.01923,-.02984,
-.013756,-.032726,
-.007864,-.034617,
-.001734,-.035457,
.00445,-.03522,
.010498,-.033912,
.016227,-.031574,
.01923,-.02984,
.01414,-.02475,
0.0*
4,1,15,-.02475,-.01414,
-.026829,-.009627,
-.028094,-.004822,
-.028504,.000129,
-.028049,.005077,
-.026741,.009871,
-.02475,.01414,
-.02984,.01923,
-.032726,.013756,
-.034617,.007864,
-.035457,.001734,
-.03522,-.00445,
-.033912,-.010498,
-.031574,-.016227,
-.02984,-.01923,
-.02475,-.01414,
0.0*
4,1,15,-.01414,.02475,
-.009627,.026829,
-.004822,.028094,
.000129,.028504,
.005077,.028049,
.009871,.026741,
.01414,.02475,
.01923,.02984,
.013756,.032726,
.007864,.034617,
.001734,.035457,
-.00445,.03522,
-.010498,.033912,
-.016227,.031574,
-.01923,.02984,
-.01414,.02475,
0.0*
%
%ADD50MACRO50*%
%AMMACRO37*
4,1,16,.02511,.01451,
.027248,.009929,
.028558,.005047,
.029001,.000011,
.028562,-.005025,
.027256,-.009909,
.025121,-.014491,
.02511,-.01451,
.0302,-.01959,
.033143,-.014048,
.035079,-.00808,
.035949,-.001865,
.035727,.004405,
.034419,.010542,
.032065,.016359,
.0302,.01959,
.02511,.01451,
90.*
4,1,16,.01451,-.02511,
.009929,-.027248,
.005047,-.028558,
.000011,-.029001,
-.005025,-.028562,
-.009909,-.027256,
-.014491,-.025121,
-.01451,-.02511,
-.01959,-.0302,
-.014048,-.033143,
-.00808,-.035079,
-.001865,-.035949,
.004405,-.035727,
.010542,-.034419,
.016359,-.032065,
.01959,-.0302,
.01451,-.02511,
90.*
4,1,16,-.02511,-.01451,
-.027248,-.009929,
-.028558,-.005047,
-.029001,-.000011,
-.028562,.005025,
-.027256,.009909,
-.025121,.014491,
-.02511,.01451,
-.0302,.01959,
-.033143,.014048,
-.035079,.00808,
-.035949,.001865,
-.035727,-.004405,
-.034419,-.010542,
-.032065,-.016359,
-.0302,-.01959,
-.02511,-.01451,
90.*
4,1,16,-.01451,.02511,
-.009929,.027248,
-.005047,.028558,
-.000011,.029001,
.005025,.028562,
.009909,.027256,
.014491,.025121,
.01451,.02511,
.01959,.0302,
.014048,.033143,
.00808,.035079,
.001865,.035949,
-.004405,.035727,
-.010542,.034419,
-.016359,.032065,
-.01959,.0302,
-.01451,.02511,
90.*
%
%ADD37MACRO37*%
%AMMACRO28*
4,1,16,.02511,.01451,
.027248,.009929,
.028558,.005047,
.029001,.000011,
.028562,-.005025,
.027256,-.009909,
.025121,-.014491,
.02511,-.01451,
.0302,-.01959,
.033143,-.014048,
.035079,-.00808,
.035949,-.001865,
.035727,.004405,
.034419,.010542,
.032065,.016359,
.0302,.01959,
.02511,.01451,
0.0*
4,1,16,.01451,-.02511,
.009929,-.027248,
.005047,-.028558,
.000011,-.029001,
-.005025,-.028562,
-.009909,-.027256,
-.014491,-.025121,
-.01451,-.02511,
-.01959,-.0302,
-.014048,-.033143,
-.00808,-.035079,
-.001865,-.035949,
.004405,-.035727,
.010542,-.034419,
.016359,-.032065,
.01959,-.0302,
.01451,-.02511,
0.0*
4,1,16,-.02511,-.01451,
-.027248,-.009929,
-.028558,-.005047,
-.029001,-.000011,
-.028562,.005025,
-.027256,.009909,
-.025121,.014491,
-.02511,.01451,
-.0302,.01959,
-.033143,.014048,
-.035079,.00808,
-.035949,.001865,
-.035727,-.004405,
-.034419,-.010542,
-.032065,-.016359,
-.0302,-.01959,
-.02511,-.01451,
0.0*
4,1,16,-.01451,.02511,
-.009929,.027248,
-.005047,.028558,
-.000011,.029001,
.005025,.028562,
.009909,.027256,
.014491,.025121,
.01451,.02511,
.01959,.0302,
.014048,.033143,
.00808,.035079,
.001865,.035949,
-.004405,.035727,
-.010542,.034419,
-.016359,.032065,
-.01959,.0302,
-.01451,.02511,
0.0*
%
%ADD28MACRO28*%
%AMMACRO77*
4,1,15,.03682,.01914,
.039584,.012455,
.041146,.005393,
.041457,-.001834,
.040509,-.009005,
.03833,-.015903,
.03682,-.01914,
.04197,-.0243,
.045552,-.016643,
.04775,-.00848,
.048497,-.000059,
.047771,.008363,
.045593,.016531,
.042029,.024197,
.04197,.0243,
.03682,.01914,
0.0*
4,1,15,.01914,-.03682,
.012455,-.039584,
.005393,-.041146,
-.001834,-.041457,
-.009005,-.040509,
-.015903,-.03833,
-.01914,-.03682,
-.0243,-.04197,
-.016643,-.045552,
-.00848,-.04775,
-.000059,-.048497,
.008363,-.047771,
.016531,-.045593,
.024197,-.042029,
.0243,-.04197,
.01914,-.03682,
0.0*
4,1,15,-.03682,-.01914,
-.039584,-.012455,
-.041146,-.005393,
-.041457,.001834,
-.040509,.009005,
-.03833,.015903,
-.03682,.01914,
-.04197,.0243,
-.045552,.016643,
-.04775,.00848,
-.048497,.000059,
-.047771,-.008363,
-.045593,-.016531,
-.042029,-.024197,
-.04197,-.0243,
-.03682,-.01914,
0.0*
4,1,15,-.01914,.03682,
-.012455,.039584,
-.005393,.041146,
.001834,.041457,
.009005,.040509,
.015903,.03833,
.01914,.03682,
.0243,.04197,
.016643,.045552,
.00848,.04775,
.000059,.048497,
-.008363,.047771,
-.016531,.045593,
-.024197,.042029,
-.0243,.04197,
-.01914,.03682,
0.0*
%
%ADD77MACRO77*%
%AMMACRO74*
4,1,15,-.03682,.01914,
-.039584,.012455,
-.041146,.005393,
-.041457,-.001834,
-.040509,-.009005,
-.03833,-.015903,
-.03682,-.01914,
-.04197,-.0243,
-.045552,-.016643,
-.04775,-.00848,
-.048497,-.000059,
-.047771,.008363,
-.045593,.016531,
-.042029,.024197,
-.04197,.0243,
-.03682,.01914,
0.0*
4,1,15,-.01914,-.03682,
-.012455,-.039584,
-.005393,-.041146,
.001834,-.041457,
.009005,-.040509,
.015903,-.03833,
.01914,-.03682,
.0243,-.04197,
.016643,-.045552,
.00848,-.04775,
.000059,-.048497,
-.008363,-.047771,
-.016531,-.045593,
-.024197,-.042029,
-.0243,-.04197,
-.01914,-.03682,
0.0*
4,1,15,.03682,-.01914,
.039584,-.012455,
.041146,-.005393,
.041457,.001834,
.040509,.009005,
.03833,.015903,
.03682,.01914,
.04197,.0243,
.045552,.016643,
.04775,.00848,
.048497,.000059,
.047771,-.008363,
.045593,-.016531,
.042029,-.024197,
.04197,-.0243,
.03682,-.01914,
0.0*
4,1,15,.01914,.03682,
.012455,.039584,
.005393,.041146,
-.001834,.041457,
-.009005,.040509,
-.015903,.03833,
-.01914,.03682,
-.0243,.04197,
-.016643,.045552,
-.00848,.04775,
-.000059,.048497,
.008363,.047771,
.016531,.045593,
.024197,.042029,
.0243,.04197,
.01914,.03682,
0.0*
%
%ADD74MACRO74*%
%AMMACRO23*
4,1,25,-.0605,.00499,
-.05909,.011105,
-.05664,.016881,
-.053224,.022145,
-.048946,.026736,
-.043935,.030513,
-.038345,.033364,
-.032345,.0352,
-.02985,.03564,
-.025195,.035958,
-.02422,.03599,
-.005,.03599,
-.005,.03099,
-.02474,.03099,
-.026534,.030943,
-.028322,.030793,
-.02985,.03058,
-.035086,.029247,
-.040011,.027025,
-.044475,.023982,
-.048343,.020209,
-.051497,.015823,
-.053842,.010955,
-.055305,.005754,
-.05544,.00499,
-.0605,.00499,
0.0*
4,1,27,.005,.03599,
.02451,.03599,
.026071,.035998,
.027631,.035916,
.029183,.035743,
.02985,.03564,
.035965,.03423,
.041741,.03178,
.047005,.028364,
.051596,.024086,
.055373,.019075,
.058224,.013485,
.06006,.007485,
.0605,.00499,
.05544,.00499,
.054107,.010226,
.051885,.015151,
.048842,.019615,
.045069,.023483,
.040683,.026637,
.035815,.028982,
.030614,.030445,
.02985,.03058,
.0281,.030818,
.02634,.030955,
.02482,.03099,
.005,.03099,
.005,.03599,
0.0*
4,1,25,-.0605,-.00501,
-.05544,-.00501,
-.054107,-.010246,
-.051885,-.015171,
-.048842,-.019635,
-.045069,-.023503,
-.040683,-.026657,
-.035815,-.029002,
-.030614,-.030465,
-.02985,-.0306,
-.028079,-.03084,
-.026298,-.030976,
-.02487,-.03101,
-.005,-.03101,
-.005,-.03601,
-.02375,-.03601,
-.028562,-.035772,
-.02985,-.03566,
-.035965,-.03425,
-.041741,-.0318,
-.047005,-.028384,
-.051596,-.024106,
-.055373,-.019095,
-.058224,-.013505,
-.06006,-.007505,
-.0605,-.00501,
0.0*
4,1,27,.005,-.03101,
.02485,-.03101,
.02659,-.030963,
.028324,-.030815,
.02985,-.0306,
.035086,-.029267,
.040011,-.027045,
.044475,-.024002,
.048343,-.020229,
.051497,-.015843,
.053842,-.010975,
.055305,-.005774,
.05544,-.00501,
.0605,-.00501,
.05909,-.011125,
.05664,-.016901,
.053224,-.022165,
.048946,-.026756,
.043935,-.030533,
.038345,-.033384,
.032345,-.03522,
.02985,-.03566,
.028758,-.035841,
.027658,-.035958,
.026553,-.036011,
.02578,-.03601,
.005,-.03601,
.005,-.03101,
0.0*
%
%ADD23MACRO23*%
%ADD60R,.285X.23*%
%ADD67C,.142*%
%AMMACRO61*
4,1,36,0.0,.01,
-.001736,.009848,
-.00342,.009397,
-.005,.00866,
-.006428,.00766,
-.00766,.006428,
-.00866,.005,
-.009397,.00342,
-.009848,.001736,
-.01,0.0,
-.009848,-.001736,
-.009397,-.00342,
-.00866,-.005,
-.00766,-.006428,
-.006428,-.00766,
-.005,-.00866,
-.00342,-.009397,
-.001736,-.009848,
0.0,-.01,
.001736,-.009848,
.00342,-.009397,
.005,-.00866,
.006428,-.00766,
.00766,-.006428,
.00866,-.005,
.009397,-.00342,
.009848,-.001736,
.01,0.0,
.009848,.001736,
.009397,.00342,
.00866,.005,
.00766,.006428,
.006428,.00766,
.005,.00866,
.00342,.009397,
.001736,.009848,
0.0,.01,
180.*
%
%ADD61MACRO61*%
%ADD33O,.219X.156*%
%ADD13C,.125*%
%AMMACRO68*
4,1,36,.0025,0.0,
.002462,.000434,
.002349,.000855,
.002165,.00125,
.001915,.001607,
.001607,.001915,
.00125,.002165,
.000855,.002349,
.000434,.002462,
0.0,.0025,
-.000434,.002462,
-.000855,.002349,
-.00125,.002165,
-.001607,.001915,
-.001915,.001607,
-.002165,.00125,
-.002349,.000855,
-.002462,.000434,
-.0025,0.0,
-.002462,-.000434,
-.002349,-.000855,
-.002165,-.00125,
-.001915,-.001607,
-.001607,-.001915,
-.00125,-.002165,
-.000855,-.002349,
-.000434,-.002462,
0.0,-.0025,
.000434,-.002462,
.000855,-.002349,
.00125,-.002165,
.001607,-.001915,
.001915,-.001607,
.002165,-.00125,
.002349,-.000855,
.002462,-.000434,
.0025,0.0,
30.*
%
%ADD68MACRO68*%
%ADD18C,.424*%
%ADD21C,.155*%
%ADD53C,.291*%
%ADD38C,.165*%
%ADD55C,.247*%
%ADD44C,.256*%
%AMMACRO34*
4,1,36,0.0,.0085,
.001476,.008371,
.002907,.007987,
.00425,.007361,
.005464,.006511,
.006511,.005464,
.007361,.00425,
.007987,.002907,
.008371,.001476,
.0085,0.0,
.008371,-.001476,
.007987,-.002907,
.007361,-.00425,
.006511,-.005464,
.005464,-.006511,
.00425,-.007361,
.002907,-.007987,
.001476,-.008371,
0.0,-.0085,
-.001476,-.008371,
-.002907,-.007987,
-.00425,-.007361,
-.005464,-.006511,
-.006511,-.005464,
-.007361,-.00425,
-.007987,-.002907,
-.008371,-.001476,
-.0085,0.0,
-.008371,.001476,
-.007987,.002907,
-.007361,.00425,
-.006511,.005464,
-.005464,.006511,
-.00425,.007361,
-.002907,.007987,
-.001476,.008371,
0.0,.0085,
180.*
%
%ADD34MACRO34*%
%AMMACRO59*
4,1,20,-.0075,-.05555,
-.0075,-.06273,
-.013677,-.060878,
-.019439,-.057981,
-.024611,-.054127,
-.029034,-.049434,
-.032576,-.044045,
-.035127,-.038122,
-.036612,-.031846,
-.037,-.0265,
-.037,-.0075,
-.03,-.0075,
-.03,-.0265,
-.029544,-.03171,
-.028191,-.036762,
-.02598,-.041502,
-.022981,-.045786,
-.019282,-.049484,
-.014998,-.052484,
-.010258,-.054694,
-.0075,-.05555,
90.*
4,1,20,.0075,-.06273,
.0075,-.05555,
.01243,-.053806,
.016983,-.051232,
.02102,-.047906,
.024418,-.043931,
.027073,-.039425,
.028906,-.034527,
.029861,-.029385,
.03,-.0265,
.03,-.0075,
.037,-.0075,
.037,-.0265,
.036438,-.032925,
.034769,-.039154,
.032043,-.044999,
.028344,-.050282,
.023784,-.054842,
.018501,-.058541,
.012656,-.061266,
.0075,-.06273,
90.*
4,1,20,-.0075,.06273,
-.0075,.05555,
-.01243,.053806,
-.016983,.051232,
-.02102,.047906,
-.024418,.043931,
-.027073,.039425,
-.028906,.034527,
-.029861,.029385,
-.03,.0265,
-.03,.0075,
-.037,.0075,
-.037,.0265,
-.036438,.032925,
-.034769,.039154,
-.032043,.044999,
-.028344,.050282,
-.023784,.054842,
-.018501,.058541,
-.012656,.061266,
-.0075,.06273,
90.*
4,1,20,.0075,.05555,
.0075,.06273,
.013677,.060878,
.019439,.057981,
.024611,.054127,
.029034,.049434,
.032576,.044045,
.035127,.038122,
.036612,.031846,
.037,.0265,
.037,.0075,
.03,.0075,
.03,.0265,
.029544,.03171,
.028191,.036762,
.02598,.041502,
.022981,.045786,
.019282,.049484,
.014998,.052484,
.010258,.054694,
.0075,.05555,
90.*
%
%ADD59MACRO59*%
%AMMACRO20*
4,1,36,.0025,0.0,
.002462,.000434,
.002349,.000855,
.002165,.00125,
.001915,.001607,
.001607,.001915,
.00125,.002165,
.000855,.002349,
.000434,.002462,
0.0,.0025,
-.000434,.002462,
-.000855,.002349,
-.00125,.002165,
-.001607,.001915,
-.001915,.001607,
-.002165,.00125,
-.002349,.000855,
-.002462,.000434,
-.0025,0.0,
-.002462,-.000434,
-.002349,-.000855,
-.002165,-.00125,
-.001915,-.001607,
-.001607,-.001915,
-.00125,-.002165,
-.000855,-.002349,
-.000434,-.002462,
0.0,-.0025,
.000434,-.002462,
.000855,-.002349,
.00125,-.002165,
.001607,-.001915,
.001915,-.001607,
.002165,-.00125,
.002349,-.000855,
.002462,-.000434,
.0025,0.0,
90.*
%
%ADD20MACRO20*%
%AMMACRO56*
4,1,36,0.0,.019,
-.003299,.018711,
-.006498,.017854,
-.0095,.016454,
-.012213,.014555,
-.014555,.012213,
-.016454,.0095,
-.017854,.006498,
-.018711,.003299,
-.019,0.0,
-.018711,-.003299,
-.017854,-.006498,
-.016454,-.0095,
-.014555,-.012213,
-.012213,-.014555,
-.0095,-.016454,
-.006498,-.017854,
-.003299,-.018711,
0.0,-.019,
.003299,-.018711,
.006498,-.017854,
.0095,-.016454,
.012213,-.014555,
.014555,-.012213,
.016454,-.0095,
.017854,-.006498,
.018711,-.003299,
.019,0.0,
.018711,.003299,
.017854,.006498,
.016454,.0095,
.014555,.012213,
.012213,.014555,
.0095,.016454,
.006498,.017854,
.003299,.018711,
0.0,.019,
270.*
%
%ADD56MACRO56*%
%AMMACRO42*
4,1,36,.003,0.0,
.002954,.000521,
.002819,.001026,
.002598,.0015,
.002298,.001928,
.001928,.002298,
.0015,.002598,
.001026,.002819,
.000521,.002954,
0.0,.003,
-.000521,.002954,
-.001026,.002819,
-.0015,.002598,
-.001928,.002298,
-.002298,.001928,
-.002598,.0015,
-.002819,.001026,
-.002954,.000521,
-.003,0.0,
-.002954,-.000521,
-.002819,-.001026,
-.002598,-.0015,
-.002298,-.001928,
-.001928,-.002298,
-.0015,-.002598,
-.001026,-.002819,
-.000521,-.002954,
0.0,-.003,
.000521,-.002954,
.001026,-.002819,
.0015,-.002598,
.001928,-.002298,
.002298,-.001928,
.002598,-.0015,
.002819,-.001026,
.002954,-.000521,
.003,0.0,
90.*
%
%ADD42MACRO42*%
%AMMACRO12*
4,1,36,.0025,0.0,
.002462,.000434,
.002349,.000855,
.002165,.00125,
.001915,.001607,
.001607,.001915,
.00125,.002165,
.000855,.002349,
.000434,.002462,
0.0,.0025,
-.000434,.002462,
-.000855,.002349,
-.00125,.002165,
-.001607,.001915,
-.001915,.001607,
-.002165,.00125,
-.002349,.000855,
-.002462,.000434,
-.0025,0.0,
-.002462,-.000434,
-.002349,-.000855,
-.002165,-.00125,
-.001915,-.001607,
-.001607,-.001915,
-.00125,-.002165,
-.000855,-.002349,
-.000434,-.002462,
0.0,-.0025,
.000434,-.002462,
.000855,-.002349,
.00125,-.002165,
.001607,-.001915,
.001915,-.001607,
.002165,-.00125,
.002349,-.000855,
.002462,-.000434,
.0025,0.0,
0.0*
%
%ADD12MACRO12*%
%AMMACRO71*
4,1,36,-.003,0.0,
-.002954,.000521,
-.002819,.001026,
-.002598,.0015,
-.002298,.001928,
-.001928,.002298,
-.0015,.002598,
-.001026,.002819,
-.000521,.002954,
0.0,.003,
.000521,.002954,
.001026,.002819,
.0015,.002598,
.001928,.002298,
.002298,.001928,
.002598,.0015,
.002819,.001026,
.002954,.000521,
.003,0.0,
.002954,-.000521,
.002819,-.001026,
.002598,-.0015,
.002298,-.001928,
.001928,-.002298,
.0015,-.002598,
.001026,-.002819,
.000521,-.002954,
0.0,-.003,
-.000521,-.002954,
-.001026,-.002819,
-.0015,-.002598,
-.001928,-.002298,
-.002298,-.001928,
-.002598,-.0015,
-.002819,-.001026,
-.002954,-.000521,
-.003,0.0,
90.*
%
%ADD71MACRO71*%
%AMMACRO63*
4,1,36,-.0025,0.0,
-.002462,.000434,
-.002349,.000855,
-.002165,.00125,
-.001915,.001607,
-.001607,.001915,
-.00125,.002165,
-.000855,.002349,
-.000434,.002462,
0.0,.0025,
.000434,.002462,
.000855,.002349,
.00125,.002165,
.001607,.001915,
.001915,.001607,
.002165,.00125,
.002349,.000855,
.002462,.000434,
.0025,0.0,
.002462,-.000434,
.002349,-.000855,
.002165,-.00125,
.001915,-.001607,
.001607,-.001915,
.00125,-.002165,
.000855,-.002349,
.000434,-.002462,
0.0,-.0025,
-.000434,-.002462,
-.000855,-.002349,
-.00125,-.002165,
-.001607,-.001915,
-.001915,-.001607,
-.002165,-.00125,
-.002349,-.000855,
-.002462,-.000434,
-.0025,0.0,
0.0*
%
%ADD63MACRO63*%
%ADD57C,.188*%
%AMMACRO16*
4,1,36,.003,0.0,
.002954,.000521,
.002819,.001026,
.002598,.0015,
.002298,.001928,
.001928,.002298,
.0015,.002598,
.001026,.002819,
.000521,.002954,
0.0,.003,
-.000521,.002954,
-.001026,.002819,
-.0015,.002598,
-.001928,.002298,
-.002298,.001928,
-.002598,.0015,
-.002819,.001026,
-.002954,.000521,
-.003,0.0,
-.002954,-.000521,
-.002819,-.001026,
-.002598,-.0015,
-.002298,-.001928,
-.001928,-.002298,
-.0015,-.002598,
-.001026,-.002819,
-.000521,-.002954,
0.0,-.003,
.000521,-.002954,
.001026,-.002819,
.0015,-.002598,
.001928,-.002298,
.002298,-.001928,
.002598,-.0015,
.002819,-.001026,
.002954,-.000521,
.003,0.0,
0.0*
%
%ADD16MACRO16*%
%AMMACRO24*
4,1,16,.02584,.01524,
.028094,.010521,
.029494,.005483,
.029998,.000278,
.029591,-.004935,
.028284,-.009999,
.026118,-.014758,
.02584,-.01524,
.03092,-.02032,
.033979,-.014642,
.036005,-.008519,
.036938,-.002138,
.036748,.004309,
.035441,.010625,
.033058,.016618,
.03092,.02032,
.02584,.01524,
180.*
4,1,16,.01524,-.02584,
.010521,-.028094,
.005483,-.029494,
.000278,-.029998,
-.004935,-.029591,
-.009999,-.028284,
-.014758,-.026118,
-.01524,-.02584,
-.02032,-.03092,
-.014642,-.033979,
-.008519,-.036005,
-.002138,-.036938,
.004309,-.036748,
.010625,-.035441,
.016618,-.033058,
.02032,-.03092,
.01524,-.02584,
180.*
4,1,16,-.02584,-.01524,
-.028094,-.010521,
-.029494,-.005483,
-.029998,-.000278,
-.029591,.004935,
-.028284,.009999,
-.026118,.014758,
-.02584,.01524,
-.03092,.02032,
-.033979,.014642,
-.036005,.008519,
-.036938,.002138,
-.036748,-.004309,
-.035441,-.010625,
-.033058,-.016618,
-.03092,-.02032,
-.02584,-.01524,
180.*
4,1,16,-.01524,.02584,
-.010521,.028094,
-.005483,.029494,
-.000278,.029998,
.004935,.029591,
.009999,.028284,
.014758,.026118,
.01524,.02584,
.02032,.03092,
.014642,.033979,
.008519,.036005,
.002138,.036938,
-.004309,.036748,
-.010625,.035441,
-.016618,.033058,
-.02032,.03092,
-.01524,.02584,
180.*
%
%ADD24MACRO24*%
%AMMACRO64*
4,1,15,.02438,.01377,
.026401,.009327,
.027619,.004601,
.027999,-.000265,
.027527,-.005123,
.02622,-.009825,
.02438,-.01377,
.02948,-.01887,
.032309,-.013464,
.034156,-.007649,
.034965,-.001602,
.034712,.004494,
.033405,.010454,
.031082,.016095,
.02948,.01887,
.02438,.01377,
270.*
4,1,15,.01377,-.02438,
.009327,-.026401,
.004601,-.027619,
-.000265,-.027999,
-.005123,-.027527,
-.009825,-.02622,
-.01377,-.02438,
-.01887,-.02948,
-.013464,-.032309,
-.007649,-.034156,
-.001602,-.034965,
.004494,-.034712,
.010454,-.033405,
.016095,-.031082,
.01887,-.02948,
.01377,-.02438,
270.*
4,1,15,-.02438,-.01377,
-.026401,-.009327,
-.027619,-.004601,
-.027999,.000265,
-.027527,.005123,
-.02622,.009825,
-.02438,.01377,
-.02948,.01887,
-.032309,.013464,
-.034156,.007649,
-.034965,.001602,
-.034712,-.004494,
-.033405,-.010454,
-.031082,-.016095,
-.02948,-.01887,
-.02438,-.01377,
270.*
4,1,15,-.01377,.02438,
-.009327,.026401,
-.004601,.027619,
.000265,.027999,
.005123,.027527,
.009825,.02622,
.01377,.02438,
.01887,.02948,
.013464,.032309,
.007649,.034156,
.001602,.034965,
-.004494,.034712,
-.010454,.033405,
-.016095,.031082,
-.01887,.02948,
-.01377,.02438,
270.*
%
%ADD64MACRO64*%
%AMMACRO69*
4,1,15,.02475,.01414,
.026829,.009627,
.028094,.004822,
.028504,-.000129,
.028049,-.005077,
.026741,-.009871,
.02475,-.01414,
.02984,-.01923,
.032726,-.013756,
.034617,-.007864,
.035457,-.001734,
.03522,.00445,
.033912,.010498,
.031574,.016227,
.02984,.01923,
.02475,.01414,
180.*
4,1,15,.01414,-.02475,
.009627,-.026829,
.004822,-.028094,
-.000129,-.028504,
-.005077,-.028049,
-.009871,-.026741,
-.01414,-.02475,
-.01923,-.02984,
-.013756,-.032726,
-.007864,-.034617,
-.001734,-.035457,
.00445,-.03522,
.010498,-.033912,
.016227,-.031574,
.01923,-.02984,
.01414,-.02475,
180.*
4,1,15,-.02475,-.01414,
-.026829,-.009627,
-.028094,-.004822,
-.028504,.000129,
-.028049,.005077,
-.026741,.009871,
-.02475,.01414,
-.02984,.01923,
-.032726,.013756,
-.034617,.007864,
-.035457,.001734,
-.03522,-.00445,
-.033912,-.010498,
-.031574,-.016227,
-.02984,-.01923,
-.02475,-.01414,
180.*
4,1,15,-.01414,.02475,
-.009627,.026829,
-.004822,.028094,
.000129,.028504,
.005077,.028049,
.009871,.026741,
.01414,.02475,
.01923,.02984,
.013756,.032726,
.007864,.034617,
.001734,.035457,
-.00445,.03522,
-.010498,.033912,
-.016227,.031574,
-.01923,.02984,
-.01414,.02475,
180.*
%
%ADD69MACRO69*%
%AMMACRO46*
4,1,15,.02475,.01414,
.026829,.009627,
.028094,.004822,
.028504,-.000129,
.028049,-.005077,
.026741,-.009871,
.02475,-.01414,
.02984,-.01923,
.032726,-.013756,
.034617,-.007864,
.035457,-.001734,
.03522,.00445,
.033912,.010498,
.031574,.016227,
.02984,.01923,
.02475,.01414,
270.*
4,1,15,.01414,-.02475,
.009627,-.026829,
.004822,-.028094,
-.000129,-.028504,
-.005077,-.028049,
-.009871,-.026741,
-.01414,-.02475,
-.01923,-.02984,
-.013756,-.032726,
-.007864,-.034617,
-.001734,-.035457,
.00445,-.03522,
.010498,-.033912,
.016227,-.031574,
.01923,-.02984,
.01414,-.02475,
270.*
4,1,15,-.02475,-.01414,
-.026829,-.009627,
-.028094,-.004822,
-.028504,.000129,
-.028049,.005077,
-.026741,.009871,
-.02475,.01414,
-.02984,.01923,
-.032726,.013756,
-.034617,.007864,
-.035457,.001734,
-.03522,-.00445,
-.033912,-.010498,
-.031574,-.016227,
-.02984,-.01923,
-.02475,-.01414,
270.*
4,1,15,-.01414,.02475,
-.009627,.026829,
-.004822,.028094,
.000129,.028504,
.005077,.028049,
.009871,.026741,
.01414,.02475,
.01923,.02984,
.013756,.032726,
.007864,.034617,
.001734,.035457,
-.00445,.03522,
-.010498,.033912,
-.016227,.031574,
-.01923,.02984,
-.01414,.02475,
270.*
%
%ADD46MACRO46*%
%AMMACRO58*
4,1,15,.04124,.02356,
.044705,.016041,
.046811,.008034,
.047495,-.000216,
.046736,-.008461,
.044557,-.016448,
.04124,-.02356,
.04635,-.02867,
.050624,-.020186,
.05336,-.011088,
.054475,-.001654,
.053935,.007831,
.051756,.017077,
.048004,.025805,
.04635,.02867,
.04124,.02356,
0.0*
4,1,15,.02356,-.04124,
.016041,-.044705,
.008034,-.046811,
-.000216,-.047495,
-.008461,-.046736,
-.016448,-.044557,
-.02356,-.04124,
-.02867,-.04635,
-.020186,-.050624,
-.011088,-.05336,
-.001654,-.054475,
.007831,-.053935,
.017077,-.051756,
.025805,-.048004,
.02867,-.04635,
.02356,-.04124,
0.0*
4,1,15,-.04124,-.02356,
-.044705,-.016041,
-.046811,-.008034,
-.047495,.000216,
-.046736,.008461,
-.044557,.016448,
-.04124,.02356,
-.04635,.02867,
-.050624,.020186,
-.05336,.011088,
-.054475,.001654,
-.053935,-.007831,
-.051756,-.017077,
-.048004,-.025805,
-.04635,-.02867,
-.04124,-.02356,
0.0*
4,1,15,-.02356,.04124,
-.016041,.044705,
-.008034,.046811,
.000216,.047495,
.008461,.046736,
.016448,.044557,
.02356,.04124,
.02867,.04635,
.020186,.050624,
.011088,.05336,
.001654,.054475,
-.007831,.053935,
-.017077,.051756,
-.025805,.048004,
-.02867,.04635,
-.02356,.04124,
0.0*
%
%ADD58MACRO58*%
%AMMACRO78*
4,1,15,.03682,.01914,
.039584,.012455,
.041146,.005393,
.041457,-.001834,
.040509,-.009005,
.03833,-.015903,
.03682,-.01914,
.04197,-.0243,
.045552,-.016643,
.04775,-.00848,
.048497,-.000059,
.047771,.008363,
.045593,.016531,
.042029,.024197,
.04197,.0243,
.03682,.01914,
180.*
4,1,15,.01914,-.03682,
.012455,-.039584,
.005393,-.041146,
-.001834,-.041457,
-.009005,-.040509,
-.015903,-.03833,
-.01914,-.03682,
-.0243,-.04197,
-.016643,-.045552,
-.00848,-.04775,
-.000059,-.048497,
.008363,-.047771,
.016531,-.045593,
.024197,-.042029,
.0243,-.04197,
.01914,-.03682,
180.*
4,1,15,-.03682,-.01914,
-.039584,-.012455,
-.041146,-.005393,
-.041457,.001834,
-.040509,.009005,
-.03833,.015903,
-.03682,.01914,
-.04197,.0243,
-.045552,.016643,
-.04775,.00848,
-.048497,.000059,
-.047771,-.008363,
-.045593,-.016531,
-.042029,-.024197,
-.04197,-.0243,
-.03682,-.01914,
180.*
4,1,15,-.01914,.03682,
-.012455,.039584,
-.005393,.041146,
.001834,.041457,
.009005,.040509,
.015903,.03833,
.01914,.03682,
.0243,.04197,
.016643,.045552,
.00848,.04775,
.000059,.048497,
-.008363,.047771,
-.016531,.045593,
-.024197,.042029,
-.0243,.04197,
-.01914,.03682,
180.*
%
%ADD78MACRO78*%
%AMMACRO76*
4,1,15,-.03682,.01914,
-.039584,.012455,
-.041146,.005393,
-.041457,-.001834,
-.040509,-.009005,
-.03833,-.015903,
-.03682,-.01914,
-.04197,-.0243,
-.045552,-.016643,
-.04775,-.00848,
-.048497,-.000059,
-.047771,.008363,
-.045593,.016531,
-.042029,.024197,
-.04197,.0243,
-.03682,.01914,
180.*
4,1,15,-.01914,-.03682,
-.012455,-.039584,
-.005393,-.041146,
.001834,-.041457,
.009005,-.040509,
.015903,-.03833,
.01914,-.03682,
.0243,-.04197,
.016643,-.045552,
.00848,-.04775,
.000059,-.048497,
-.008363,-.047771,
-.016531,-.045593,
-.024197,-.042029,
-.0243,-.04197,
-.01914,-.03682,
180.*
4,1,15,.03682,-.01914,
.039584,-.012455,
.041146,-.005393,
.041457,.001834,
.040509,.009005,
.03833,.015903,
.03682,.01914,
.04197,.0243,
.045552,.016643,
.04775,.00848,
.048497,.000059,
.047771,-.008363,
.045593,-.016531,
.042029,-.024197,
.04197,-.0243,
.03682,-.01914,
180.*
4,1,15,.01914,.03682,
.012455,.039584,
.005393,.041146,
-.001834,.041457,
-.009005,.040509,
-.015903,.03833,
-.01914,.03682,
-.0243,.04197,
-.016643,.045552,
-.00848,.04775,
-.000059,.048497,
.008363,.047771,
.016531,.045593,
.024197,.042029,
.0243,.04197,
.01914,.03682,
180.*
%
%ADD76MACRO76*%
%ADD79C,.006*%
%ADD104C,.04006*%
%ADD101C,.03016*%
%ADD97C,.03018*%
%ADD102C,.07008*%
%ADD82C,.07306*%
%ADD89C,.07208*%
%ADD93C,.07308*%
%ADD94C,.07608*%
%ADD92C,.07808*%
%ADD91C,.09708*%
%ADD88O,.1621X.2251*%
%ADD84C,.311*%
%ADD99C,.1621*%
%ADD81O,.03004X.06404*%
%ADD100C,.16211*%
%ADD96C,.1751*%
%ADD80O,.03006X.06406*%
%ADD95C,.43406*%
%ADD83C,.16506*%
%ADD90C,.25806*%
%ADD98C,.43376*%
%ADD103C,.19786*%
%ADD87O,.43374X.77626*%
%ADD85O,.43374X.69752*%
%ADD86O,.43376X.69754*%
G75*
%LPD*%
G75*
G36*
G01X-984580Y-698988D02*
X5868320D01*
Y4193602D01*
X-984580D01*
Y-698988D01*
G37*
%LPC*%
G75*
G36*
G01X1828062Y36504D02*
X1828081Y36500D01*
G03X1828470Y36462I388J1962D01*
G03X1828859Y36500I1J2000D01*
G01X1828878Y36504D01*
X1849606D01*
G02X1855480Y30630I0J-5874D01*
G01Y-40945D01*
G02X1849606Y-46819I-5874J0D01*
G01X7874D01*
G02X2000Y-40945I0J5874D01*
G01Y30630D01*
G02X7874Y36504I5874J0D01*
G01X35835D01*
G02X41709Y30630I0J-5874D01*
G01Y-3937D01*
G03X51583Y-13811I9874J0D01*
G01X321661D01*
G03X331535Y-3937I0J9874D01*
G01Y30630D01*
G02X337409Y36504I5874J0D01*
G01X480717D01*
G02X486591Y30630I0J-5874D01*
G01Y16850D01*
G03X496465Y6976I9874J0D01*
G01X766543D01*
G03X776417Y16850I0J9874D01*
G01Y30630D01*
G02X782291Y36504I5874J0D01*
G01X879134D01*
G03X889008Y46378I0J9874D01*
G01Y122824D01*
X895188Y129004D01*
X1002542D01*
X1009024Y122522D01*
Y46378D01*
G03X1018898Y36504I9874J0D01*
G01X1510244D01*
G02X1516118Y30630I0J-5874D01*
G01Y-3937D01*
G03X1525992Y-13811I9874J0D01*
G01X1796071D01*
G03X1805945Y-3937I0J9874D01*
G01Y30630D01*
G02X1811819Y36504I5874J0D01*
G01X1828062D01*
G37*
G36*
G01X1829886Y1650538D02*
X1829890D01*
Y1650237D01*
X1829888Y1650228D01*
G03X1829820Y1649712I1932J-517D01*
G03X1829886Y1649203I2000J1D01*
G01Y1612316D01*
G03X1832779Y1605332I9877J0D01*
G01X1839978Y1598133D01*
G02X1841697Y1593983I-4151J-4151D01*
G01Y326095D01*
G03X1844590Y319111I9878J1D01*
G01X1853757Y309944D01*
G02X1855476Y305794I-4151J-4151D01*
G01Y54252D01*
G02X1849606Y48382I-5870J0D01*
G01X1829186D01*
Y48378D01*
X1827844D01*
Y48382D01*
X1803945D01*
G03X1794067Y38504I0J-9878D01*
G01Y3937D01*
G02X1792134Y2004I-1933J0D01*
G01X1529929D01*
G02X1527996Y3937I0J1933D01*
G01Y38504D01*
G03X1518118Y48382I-9878J0D01*
G01X1026772D01*
G02X1020902Y54252I0J5870D01*
G01Y131004D01*
G03X1011024Y140882I-9878J0D01*
G01X887008D01*
G03X877130Y131004I0J-9878D01*
G01Y54252D01*
G02X871260Y48382I-5870J0D01*
G01X774417D01*
G03X764539Y38504I0J-9878D01*
G01Y24724D01*
G02X762606Y22791I-1933J0D01*
G01X500402D01*
G02X498469Y24724I0J1933D01*
G01Y38504D01*
G03X488591Y48382I-9878J0D01*
G01X329535D01*
G03X319657Y38504I0J-9878D01*
G01Y3937D01*
G02X317724Y2004I-1933J0D01*
G01X55520D01*
G02X53587Y3937I0J1933D01*
G01Y38504D01*
G03X43709Y48382I-9878J0D01*
G01X7874D01*
G02X2004Y54252I0J5870D01*
G01Y305794D01*
G02X3723Y309944I5870J-1D01*
G01X6985Y313206D01*
G03X9878Y320190I-6984J6984D01*
G01Y1588078D01*
G02X11597Y1592228I5870J-1D01*
G01X24701Y1605332D01*
G03X27595Y1612316I-6983J6985D01*
G01Y1732244D01*
G02X33465Y1738114I5870J0D01*
G01X765732D01*
Y1736890D01*
G03X769705Y1732917I3973J0D01*
G01X1087854D01*
G03X1091827Y1736890I0J3973D01*
G01Y1738114D01*
X1824016D01*
G02X1829886Y1732244I0J-5870D01*
G01Y1650538D01*
G37*
G36*
G01X1867354Y305795D02*
G03X1862156Y318343I-17746J-1D01*
G01X1855296Y325203D01*
G02X1853575Y329357I4153J4154D01*
G01Y1593984D01*
G03X1848377Y1606532I-17746J-1D01*
G01X1843484Y1611425D01*
G02X1841764Y1615579I4156J4154D01*
G01Y1732244D01*
G02X1847638Y1738118I5874J0D01*
G01X1857480D01*
G03X1867354Y1747992I0J9874D01*
G01Y1815072D01*
G02X1873228Y1820946I5874J0D01*
G01X2093700D01*
G02X2099574Y1815072I0J-5874D01*
G01Y1791450D01*
G02X2093700Y1785576I-5874J0D01*
G01X2031574D01*
G03X2021700Y1775702I0J-9874D01*
G01Y1229954D01*
G03X2031574Y1220080I9874J0D01*
G01X2093700D01*
G02X2099574Y1214206I0J-5874D01*
G01Y-40945D01*
G02X2093700Y-46819I-5874J0D01*
G01X1873228D01*
G02X1867354Y-40945I0J5874D01*
G01Y305795D01*
G37*
%LPD*%
G75*
G36*
G01X1758669Y52153D02*
G02X1760173Y50649I0J-1504D01*
G01Y50648D01*
G02X1760172Y50593I-1504J0D01*
G02X1758669Y49100I-1503J10D01*
G01X1755269D01*
G02X1753766Y50593I0J1503D01*
G02X1753765Y50648I1503J55D01*
G01Y50649D01*
G02X1755269Y52153I1504J0D01*
G02X1755620Y52112I2J-1504D01*
G01X1755643Y52106D01*
X1758295D01*
X1758318Y52112D01*
G02X1758669Y52153I349J-1463D01*
G37*
G36*
G01X1394374Y172851D02*
G02X1395334Y173198I960J-1154D01*
G01X1398734D01*
G02X1400236Y171696I0J-1502D01*
G02X1398743Y170194I-1502J0D01*
G02X1398182Y170076I-561J1276D01*
G02X1397656Y170179I0J1394D01*
G01X1397620Y170194D01*
X1395334D01*
G02X1394882Y170264I1J1502D01*
G02X1394184Y170076I-699J1206D01*
G01X1394182D01*
G02Y172864I0J1394D01*
G02X1394374Y172851I2J-1394D01*
G37*
G36*
G01X880168Y504762D02*
Y508162D01*
G02X881670Y509664I1502J0D01*
G02X882945Y508955I0J-1501D01*
G02X883184Y508142I-1265J-813D01*
G01Y508141D01*
G02X883173Y507963I-1504J4D01*
G01X883172Y507952D01*
Y504897D01*
X883173Y504888D01*
G02X883180Y504743I-1493J-145D01*
G01Y504742D01*
G02X881680Y503242I-1500J0D01*
G02X880398Y503963I0J1500D01*
G02X880168Y504762I1273J799D01*
G37*
G36*
G01X963269Y1556947D02*
G03X963539I135J148D01*
G02X965904Y1557866I2365J-2584D01*
G02X969115Y1555762I0J-3502D01*
G02X970504Y1554262I-115J-1500D01*
G02X969016Y1552758I-1504J0D01*
G02X965904Y1550862I-3112J1606D01*
G02X963539Y1551781I0J3503D01*
G03X963269I-135J-148D01*
G02X960904Y1550862I-2365J2584D01*
G02Y1557866I0J3502D01*
G02X963269Y1556947I0J-3503D01*
G37*
G36*
G01X1010001D02*
G03X1010271I135J148D01*
G02X1012636Y1557866I2365J-2584D01*
G02X1015849Y1555757I0J-3502D01*
G02X1016012Y1555766I164J-1495D01*
G02Y1552758I0J-1504D01*
G02X1015759Y1552779I-3J1504D01*
G02X1012636Y1550862I-3123J1585D01*
G02X1010271Y1551781I0J3503D01*
G03X1010001I-135J-148D01*
G02X1007636Y1550862I-2365J2584D01*
G02Y1557866I0J3502D01*
G02X1010001Y1556947I0J-3503D01*
G37*
G36*
G01X1056733D02*
G03X1057003I135J148D01*
G02X1059368Y1557866I2365J-2584D01*
G02X1062579Y1555762I0J-3502D01*
G02X1063968Y1554262I-115J-1500D01*
G02X1062480Y1552758I-1504J0D01*
G02X1059368Y1550862I-3112J1606D01*
G02X1057003Y1551781I0J3503D01*
G03X1056733I-135J-148D01*
G02X1054368Y1550862I-2365J2584D01*
G02Y1557866I0J3502D01*
G02X1056733Y1556947I0J-3503D01*
G37*
G36*
G01X1080099D02*
G03X1080369I135J148D01*
G02X1082734Y1557866I2365J-2584D01*
G02X1085945Y1555762I0J-3502D01*
G02X1087334Y1554262I-115J-1500D01*
G02X1085846Y1552758I-1504J0D01*
G02X1082734Y1550862I-3112J1606D01*
G02X1080369Y1551781I0J3503D01*
G03X1080099I-135J-148D01*
G02X1077734Y1550862I-2365J2584D01*
G02Y1557866I0J3502D01*
G02X1080099Y1556947I0J-3503D01*
G37*
G36*
G01X986635D02*
G03X986905I135J148D01*
G02X989270Y1557866I2365J-2584D01*
G02X992481Y1555762I0J-3502D01*
G02X993966Y1554262I-15J-1500D01*
G02X992466Y1552762I-1500J0D01*
G02X992385Y1552764I-3J1500D01*
G02X989270Y1550862I-3115J1600D01*
G02X986905Y1551781I0J3503D01*
G03X986635I-135J-148D01*
G02X984270Y1550862I-2365J2584D01*
G02Y1557866I0J3502D01*
G02X986635Y1556947I0J-3503D01*
G37*
G36*
G01X1033367D02*
G03X1033637I135J148D01*
G02X1036002Y1557866I2365J-2584D01*
G02X1039214Y1555760I0J-3502D01*
G02X1039298Y1555762I78J-1498D01*
G02Y1552762I0J-1500D01*
G02X1039121Y1552772I-4J1500D01*
G02X1036002Y1550862I-3119J1592D01*
G02X1033637Y1551781I0J3503D01*
G03X1033367I-135J-148D01*
G02X1031002Y1550862I-2365J2584D01*
G02Y1557866I0J3502D01*
G02X1033367Y1556947I0J-3503D01*
G37*
G36*
G01X229206Y1656840D02*
X232906D01*
G02X233208Y1656537I-1J-303D01*
G01Y1646531D01*
G02X232906Y1646228I-302J-1D01*
G01X229206D01*
G02X228904Y1646531I1J303D01*
G01Y1648936D01*
G02X228890Y1649173I2002J237D01*
G02X228904Y1649410I2016J0D01*
G01Y1653660D01*
G02X228890Y1653897I2002J237D01*
G02X228904Y1654134I2016J0D01*
G01Y1656537D01*
G02X229206Y1656840I302J1D01*
G37*
G36*
G01X276450D02*
X280150D01*
G02X280452Y1656537I-1J-303D01*
G01Y1646531D01*
G02X280150Y1646228I-302J-1D01*
G01X276450D01*
G02X276148Y1646531I1J303D01*
G01Y1648936D01*
G02X276134Y1649173I2002J237D01*
G02X276148Y1649410I2016J0D01*
G01Y1653660D01*
G02X276134Y1653897I2002J237D01*
G02X276148Y1654134I2016J0D01*
G01Y1656537D01*
G02X276450Y1656840I302J1D01*
G37*
G36*
G01X237080Y1660776D02*
X240780D01*
G02X241082Y1660474I0J-302D01*
G01Y1650468D01*
G02X240780Y1650166I-302J0D01*
G01X237080D01*
G02X236778Y1650468I0J302D01*
G01Y1652873D01*
G02X236764Y1653110I2002J237D01*
G02X236778Y1653347I2016J0D01*
G01Y1657597D01*
G02X236764Y1657834I2002J237D01*
G02X236778Y1658071I2016J0D01*
G01Y1660474D01*
G02X237080Y1660776I302J0D01*
G37*
G36*
G01X268576D02*
X272276D01*
G02X272578Y1660474I0J-302D01*
G01Y1650468D01*
G02X272276Y1650166I-302J0D01*
G01X268576D01*
G02X268274Y1650468I0J302D01*
G01Y1652873D01*
G02X268260Y1653110I2002J237D01*
G02X268274Y1653347I2016J0D01*
G01Y1657597D01*
G02X268260Y1657834I2002J237D01*
G02X268274Y1658071I2016J0D01*
G01Y1660474D01*
G02X268576Y1660776I302J0D01*
G37*
G36*
G01X284324D02*
X288024D01*
G02X288326Y1660474I0J-302D01*
G01Y1650468D01*
G02X288024Y1650166I-302J0D01*
G01X284324D01*
G02X284022Y1650468I0J302D01*
G01Y1652873D01*
G02X284008Y1653110I2002J237D01*
G02X284022Y1653347I2016J0D01*
G01Y1657597D01*
G02X284008Y1657834I2002J237D01*
G02X284022Y1658071I2016J0D01*
G01Y1660474D01*
G02X284324Y1660776I302J0D01*
G37*
G36*
G01X229206Y1671014D02*
X232906D01*
G02X233208Y1670711I-1J-303D01*
G01Y1660705D01*
G02X232906Y1660402I-302J-1D01*
G01X229206D01*
G02X228904Y1660705I1J303D01*
G01Y1663109D01*
G02X228890Y1663346I2002J237D01*
G02X228904Y1663583I2016J0D01*
G01Y1667833D01*
G02X228890Y1668070I2002J237D01*
G02X228904Y1668307I2016J0D01*
G01Y1670711D01*
G02X229206Y1671014I302J1D01*
G37*
G36*
G01X244954D02*
X248654D01*
G02X248956Y1670711I-1J-303D01*
G01Y1660705D01*
G02X248654Y1660402I-302J-1D01*
G01X244954D01*
G02X244652Y1660705I1J303D01*
G01Y1663109D01*
G02X244638Y1663346I2002J237D01*
G02X244652Y1663583I2016J0D01*
G01Y1667833D01*
G02X244638Y1668070I2002J237D01*
G02X244652Y1668307I2016J0D01*
G01Y1670711D01*
G02X244954Y1671014I302J1D01*
G37*
G36*
G01X276450D02*
X280150D01*
G02X280452Y1670711I-1J-303D01*
G01Y1660705D01*
G02X280150Y1660402I-302J-1D01*
G01X276450D01*
G02X276148Y1660705I1J303D01*
G01Y1663109D01*
G02X276134Y1663346I2002J237D01*
G02X276148Y1663583I2016J0D01*
G01Y1667833D01*
G02X276134Y1668070I2002J237D01*
G02X276148Y1668307I2016J0D01*
G01Y1670711D01*
G02X276450Y1671014I302J1D01*
G37*
G36*
G01X252828Y1674950D02*
X256528D01*
G02X256830Y1674648I0J-302D01*
G01Y1664642D01*
G02X256528Y1664340I-302J0D01*
G01X252828D01*
G02X252526Y1664642I0J302D01*
G01Y1667046D01*
G02X252512Y1667283I2002J237D01*
G02X252526Y1667520I2016J0D01*
G01Y1671770D01*
G02X252512Y1672007I2002J237D01*
G02X252526Y1672244I2016J0D01*
G01Y1674648D01*
G02X252828Y1674950I302J0D01*
G37*
G36*
G01X268576D02*
X272276D01*
G02X272578Y1674648I0J-302D01*
G01Y1664642D01*
G02X272276Y1664340I-302J0D01*
G01X268576D01*
G02X268274Y1664642I0J302D01*
G01Y1667046D01*
G02X268260Y1667283I2002J237D01*
G02X268274Y1667520I2016J0D01*
G01Y1671770D01*
G02X268260Y1672007I2002J237D01*
G02X268274Y1672244I2016J0D01*
G01Y1674648D01*
G02X268576Y1674950I302J0D01*
G37*
G36*
G01X284324D02*
X288024D01*
G02X288326Y1674648I0J-302D01*
G01Y1664642D01*
G02X288024Y1664340I-302J0D01*
G01X284324D01*
G02X284022Y1664642I0J302D01*
G01Y1667046D01*
G02X284008Y1667283I2002J237D01*
G02X284022Y1667520I2016J0D01*
G01Y1671770D01*
G02X284008Y1672007I2002J237D01*
G02X284022Y1672244I2016J0D01*
G01Y1674648D01*
G02X284324Y1674950I302J0D01*
G37*
G36*
G01X229206Y1685186D02*
X232906D01*
G02X233208Y1684884I0J-302D01*
G01Y1674878D01*
G02X232906Y1674576I-302J0D01*
G01X229206D01*
G02X228904Y1674878I0J302D01*
G01Y1677282D01*
G02X228890Y1677519I2002J237D01*
G02X228904Y1677756I2016J0D01*
G01Y1682007D01*
G02X228890Y1682244I2002J237D01*
G02X228904Y1682481I2016J0D01*
G01Y1684884D01*
G02X229206Y1685186I302J0D01*
G37*
G36*
G01X244954D02*
X248654D01*
G02X248956Y1684884I0J-302D01*
G01Y1674878D01*
G02X248654Y1674576I-302J0D01*
G01X244954D01*
G02X244652Y1674878I0J302D01*
G01Y1677282D01*
G02X244638Y1677519I2002J237D01*
G02X244652Y1677756I2016J0D01*
G01Y1682007D01*
G02X244638Y1682244I2002J237D01*
G02X244652Y1682481I2016J0D01*
G01Y1684884D01*
G02X244954Y1685186I302J0D01*
G37*
G36*
G01X260702D02*
X264402D01*
G02X264704Y1684884I0J-302D01*
G01Y1674878D01*
G02X264402Y1674576I-302J0D01*
G01X260702D01*
G02X260400Y1674878I0J302D01*
G01Y1677282D01*
G02X260386Y1677519I2002J237D01*
G02X260400Y1677756I2016J0D01*
G01Y1682007D01*
G02X260386Y1682244I2002J237D01*
G02X260400Y1682481I2016J0D01*
G01Y1684884D01*
G02X260702Y1685186I302J0D01*
G37*
G36*
G01X276450D02*
X280150D01*
G02X280452Y1684884I0J-302D01*
G01Y1674878D01*
G02X280150Y1674576I-302J0D01*
G01X276450D01*
G02X276148Y1674878I0J302D01*
G01Y1677282D01*
G02X276134Y1677519I2002J237D01*
G02X276148Y1677756I2016J0D01*
G01Y1682007D01*
G02X276134Y1682244I2002J237D01*
G02X276148Y1682481I2016J0D01*
G01Y1684884D01*
G02X276450Y1685186I302J0D01*
G37*
G36*
G01X560308D02*
X564008D01*
G02X564310Y1684884I0J-302D01*
G01Y1674878D01*
G02X564008Y1674576I-302J0D01*
G01X560308D01*
G02X560006Y1674878I0J302D01*
G01Y1677282D01*
G02X559992Y1677519I2002J237D01*
G02X560006Y1677756I2016J0D01*
G01Y1682007D01*
G02X559992Y1682244I2002J237D01*
G02X560006Y1682481I2016J0D01*
G01Y1684884D01*
G02X560308Y1685186I302J0D01*
G37*
G36*
G01X576056D02*
X579756D01*
G02X580058Y1684884I0J-302D01*
G01Y1674878D01*
G02X579756Y1674576I-302J0D01*
G01X576056D01*
G02X575754Y1674878I0J302D01*
G01Y1677282D01*
G02X575740Y1677519I2002J237D01*
G02X575754Y1677756I2016J0D01*
G01Y1682007D01*
G02X575740Y1682244I2002J237D01*
G02X575754Y1682481I2016J0D01*
G01Y1684884D01*
G02X576056Y1685186I302J0D01*
G37*
G36*
G01X591804D02*
X595504D01*
G02X595806Y1684884I0J-302D01*
G01Y1674878D01*
G02X595504Y1674576I-302J0D01*
G01X591804D01*
G02X591502Y1674878I0J302D01*
G01Y1677282D01*
G02X591488Y1677519I2002J237D01*
G02X591502Y1677756I2016J0D01*
G01Y1682007D01*
G02X591488Y1682244I2002J237D01*
G02X591502Y1682481I2016J0D01*
G01Y1684884D01*
G02X591804Y1685186I302J0D01*
G37*
G36*
G01X607552D02*
X611252D01*
G02X611554Y1684884I0J-302D01*
G01Y1674878D01*
G02X611252Y1674576I-302J0D01*
G01X607552D01*
G02X607250Y1674878I0J302D01*
G01Y1677282D01*
G02X607236Y1677519I2002J237D01*
G02X607250Y1677756I2016J0D01*
G01Y1682007D01*
G02X607236Y1682244I2002J237D01*
G02X607250Y1682481I2016J0D01*
G01Y1684884D01*
G02X607552Y1685186I302J0D01*
G37*
G36*
G01X1237080D02*
X1240780D01*
G02X1241082Y1684884I0J-302D01*
G01Y1674878D01*
G02X1240780Y1674576I-302J0D01*
G01X1237080D01*
G02X1236778Y1674878I0J302D01*
G01Y1677282D01*
G02X1236764Y1677519I2002J237D01*
G02X1236778Y1677756I2016J0D01*
G01Y1682007D01*
G02X1236764Y1682244I2002J237D01*
G02X1236778Y1682481I2016J0D01*
G01Y1684884D01*
G02X1237080Y1685186I302J0D01*
G37*
G36*
G01X1252828D02*
X1256528D01*
G02X1256830Y1684884I0J-302D01*
G01Y1674878D01*
G02X1256528Y1674576I-302J0D01*
G01X1252828D01*
G02X1252526Y1674878I0J302D01*
G01Y1677282D01*
G02X1252512Y1677519I2002J237D01*
G02X1252526Y1677756I2016J0D01*
G01Y1682007D01*
G02X1252512Y1682244I2002J237D01*
G02X1252526Y1682481I2016J0D01*
G01Y1684884D01*
G02X1252828Y1685186I302J0D01*
G37*
G36*
G01X1268576D02*
X1272276D01*
G02X1272578Y1684884I0J-302D01*
G01Y1674878D01*
G02X1272276Y1674576I-302J0D01*
G01X1268576D01*
G02X1268274Y1674878I0J302D01*
G01Y1677282D01*
G02X1268260Y1677519I2002J237D01*
G02X1268274Y1677756I2016J0D01*
G01Y1682007D01*
G02X1268260Y1682244I2002J237D01*
G02X1268274Y1682481I2016J0D01*
G01Y1684884D01*
G02X1268576Y1685186I302J0D01*
G37*
G36*
G01X1284324D02*
X1288024D01*
G02X1288326Y1684884I0J-302D01*
G01Y1674878D01*
G02X1288024Y1674576I-302J0D01*
G01X1284324D01*
G02X1284022Y1674878I0J302D01*
G01Y1677282D01*
G02X1284008Y1677519I2002J237D01*
G02X1284022Y1677756I2016J0D01*
G01Y1682007D01*
G02X1284008Y1682244I2002J237D01*
G02X1284022Y1682481I2016J0D01*
G01Y1684884D01*
G02X1284324Y1685186I302J0D01*
G37*
G36*
G01X1568182D02*
X1571882D01*
G02X1572184Y1684884I0J-302D01*
G01Y1674878D01*
G02X1571882Y1674576I-302J0D01*
G01X1568182D01*
G02X1567880Y1674878I0J302D01*
G01Y1677282D01*
G02X1567866Y1677519I2002J237D01*
G02X1567880Y1677756I2016J0D01*
G01Y1682007D01*
G02X1567866Y1682244I2002J237D01*
G02X1567880Y1682481I2016J0D01*
G01Y1684884D01*
G02X1568182Y1685186I302J0D01*
G37*
G36*
G01X1583930D02*
X1587630D01*
G02X1587932Y1684884I0J-302D01*
G01Y1674878D01*
G02X1587630Y1674576I-302J0D01*
G01X1583930D01*
G02X1583628Y1674878I0J302D01*
G01Y1677282D01*
G02X1583614Y1677519I2002J237D01*
G02X1583628Y1677756I2016J0D01*
G01Y1682007D01*
G02X1583614Y1682244I2002J237D01*
G02X1583628Y1682481I2016J0D01*
G01Y1684884D01*
G02X1583930Y1685186I302J0D01*
G37*
G36*
G01X1599678D02*
X1603378D01*
G02X1603680Y1684884I0J-302D01*
G01Y1674878D01*
G02X1603378Y1674576I-302J0D01*
G01X1599678D01*
G02X1599376Y1674878I0J302D01*
G01Y1677282D01*
G02X1599362Y1677519I2002J237D01*
G02X1599376Y1677756I2016J0D01*
G01Y1682007D01*
G02X1599362Y1682244I2002J237D01*
G02X1599376Y1682481I2016J0D01*
G01Y1684884D01*
G02X1599678Y1685186I302J0D01*
G37*
G36*
G01X1615426D02*
X1619126D01*
G02X1619428Y1684884I0J-302D01*
G01Y1674878D01*
G02X1619126Y1674576I-302J0D01*
G01X1615426D01*
G02X1615124Y1674878I0J302D01*
G01Y1677282D01*
G02X1615110Y1677519I2002J237D01*
G02X1615124Y1677756I2016J0D01*
G01Y1682007D01*
G02X1615110Y1682244I2002J237D01*
G02X1615124Y1682481I2016J0D01*
G01Y1684884D01*
G02X1615426Y1685186I302J0D01*
G37*
G36*
G01X296135D02*
X299835D01*
G02X300138Y1684884I1J-302D01*
G01Y1674878D01*
G02X299835Y1674576I-303J1D01*
G01X296135D01*
G02X295832Y1674878I-1J302D01*
G01Y1677290D01*
G02X295819Y1677519I2003J229D01*
G02X295832Y1677748I2016J0D01*
G01Y1682015D01*
G02X295819Y1682244I2003J229D01*
G02X295832Y1682473I2016J0D01*
G01Y1684884D01*
G02X296135Y1685186I303J-1D01*
G37*
G36*
G01X311883D02*
X315583D01*
G02X315886Y1684884I1J-302D01*
G01Y1674878D01*
G02X315583Y1674576I-303J1D01*
G01X311883D01*
G02X311580Y1674878I-1J302D01*
G01Y1677290D01*
G02X311567Y1677519I2003J229D01*
G02X311580Y1677748I2016J0D01*
G01Y1682015D01*
G02X311567Y1682244I2003J229D01*
G02X311580Y1682473I2016J0D01*
G01Y1684884D01*
G02X311883Y1685186I303J-1D01*
G37*
G36*
G01X327631D02*
X331331D01*
G02X331634Y1684884I1J-302D01*
G01Y1674878D01*
G02X331331Y1674576I-303J1D01*
G01X327631D01*
G02X327328Y1674878I-1J302D01*
G01Y1677290D01*
G02X327315Y1677519I2003J229D01*
G02X327328Y1677748I2016J0D01*
G01Y1682015D01*
G02X327315Y1682244I2003J229D01*
G02X327328Y1682473I2016J0D01*
G01Y1684884D01*
G02X327631Y1685186I303J-1D01*
G37*
G36*
G01X343379D02*
X347079D01*
G02X347382Y1684884I1J-302D01*
G01Y1674878D01*
G02X347079Y1674576I-303J1D01*
G01X343379D01*
G02X343076Y1674878I-1J302D01*
G01Y1677290D01*
G02X343063Y1677519I2003J229D01*
G02X343076Y1677748I2016J0D01*
G01Y1682015D01*
G02X343063Y1682244I2003J229D01*
G02X343076Y1682473I2016J0D01*
G01Y1684884D01*
G02X343379Y1685186I303J-1D01*
G37*
G36*
G01X493379D02*
X497079D01*
G02X497382Y1684884I1J-302D01*
G01Y1674878D01*
G02X497079Y1674576I-303J1D01*
G01X493379D01*
G02X493076Y1674878I-1J302D01*
G01Y1677290D01*
G02X493063Y1677519I2003J229D01*
G02X493076Y1677748I2016J0D01*
G01Y1682015D01*
G02X493063Y1682244I2003J229D01*
G02X493076Y1682473I2016J0D01*
G01Y1684884D01*
G02X493379Y1685186I303J-1D01*
G37*
G36*
G01X509127D02*
X512827D01*
G02X513130Y1684884I1J-302D01*
G01Y1674878D01*
G02X512827Y1674576I-303J1D01*
G01X509127D01*
G02X508824Y1674878I-1J302D01*
G01Y1677290D01*
G02X508811Y1677519I2003J229D01*
G02X508824Y1677748I2016J0D01*
G01Y1682015D01*
G02X508811Y1682244I2003J229D01*
G02X508824Y1682473I2016J0D01*
G01Y1684884D01*
G02X509127Y1685186I303J-1D01*
G37*
G36*
G01X524875D02*
X528575D01*
G02X528878Y1684884I1J-302D01*
G01Y1674878D01*
G02X528575Y1674576I-303J1D01*
G01X524875D01*
G02X524572Y1674878I-1J302D01*
G01Y1677290D01*
G02X524559Y1677519I2003J229D01*
G02X524572Y1677748I2016J0D01*
G01Y1682015D01*
G02X524559Y1682244I2003J229D01*
G02X524572Y1682473I2016J0D01*
G01Y1684884D01*
G02X524875Y1685186I303J-1D01*
G37*
G36*
G01X540623D02*
X544323D01*
G02X544626Y1684884I1J-302D01*
G01Y1674878D01*
G02X544323Y1674576I-303J1D01*
G01X540623D01*
G02X540320Y1674878I-1J302D01*
G01Y1677290D01*
G02X540307Y1677519I2003J229D01*
G02X540320Y1677748I2016J0D01*
G01Y1682015D01*
G02X540307Y1682244I2003J229D01*
G02X540320Y1682473I2016J0D01*
G01Y1684884D01*
G02X540623Y1685186I303J-1D01*
G37*
G36*
G01X1304009D02*
X1307709D01*
G02X1308012Y1684884I1J-302D01*
G01Y1674878D01*
G02X1307709Y1674576I-303J1D01*
G01X1304009D01*
G02X1303706Y1674878I-1J302D01*
G01Y1677290D01*
G02X1303693Y1677519I2003J229D01*
G02X1303706Y1677748I2016J0D01*
G01Y1682015D01*
G02X1303693Y1682244I2003J229D01*
G02X1303706Y1682473I2016J0D01*
G01Y1684884D01*
G02X1304009Y1685186I303J-1D01*
G37*
G36*
G01X1319757D02*
X1323457D01*
G02X1323760Y1684884I1J-302D01*
G01Y1674878D01*
G02X1323457Y1674576I-303J1D01*
G01X1319757D01*
G02X1319454Y1674878I-1J302D01*
G01Y1677290D01*
G02X1319441Y1677519I2003J229D01*
G02X1319454Y1677748I2016J0D01*
G01Y1682015D01*
G02X1319441Y1682244I2003J229D01*
G02X1319454Y1682473I2016J0D01*
G01Y1684884D01*
G02X1319757Y1685186I303J-1D01*
G37*
G36*
G01X1335505D02*
X1339205D01*
G02X1339508Y1684884I1J-302D01*
G01Y1674878D01*
G02X1339205Y1674576I-303J1D01*
G01X1335505D01*
G02X1335202Y1674878I-1J302D01*
G01Y1677290D01*
G02X1335189Y1677519I2003J229D01*
G02X1335202Y1677748I2016J0D01*
G01Y1682015D01*
G02X1335189Y1682244I2003J229D01*
G02X1335202Y1682473I2016J0D01*
G01Y1684884D01*
G02X1335505Y1685186I303J-1D01*
G37*
G36*
G01X1351253D02*
X1354953D01*
G02X1355256Y1684884I1J-302D01*
G01Y1674878D01*
G02X1354953Y1674576I-303J1D01*
G01X1351253D01*
G02X1350950Y1674878I-1J302D01*
G01Y1677290D01*
G02X1350937Y1677519I2003J229D01*
G02X1350950Y1677748I2016J0D01*
G01Y1682015D01*
G02X1350937Y1682244I2003J229D01*
G02X1350950Y1682473I2016J0D01*
G01Y1684884D01*
G02X1351253Y1685186I303J-1D01*
G37*
G36*
G01X1501253D02*
X1504953D01*
G02X1505256Y1684884I1J-302D01*
G01Y1674878D01*
G02X1504953Y1674576I-303J1D01*
G01X1501253D01*
G02X1500950Y1674878I-1J302D01*
G01Y1677290D01*
G02X1500937Y1677519I2003J229D01*
G02X1500950Y1677748I2016J0D01*
G01Y1682015D01*
G02X1500937Y1682244I2003J229D01*
G02X1500950Y1682473I2016J0D01*
G01Y1684884D01*
G02X1501253Y1685186I303J-1D01*
G37*
G36*
G01X1517001D02*
X1520701D01*
G02X1521004Y1684884I1J-302D01*
G01Y1674878D01*
G02X1520701Y1674576I-303J1D01*
G01X1517001D01*
G02X1516698Y1674878I-1J302D01*
G01Y1677290D01*
G02X1516685Y1677519I2003J229D01*
G02X1516698Y1677748I2016J0D01*
G01Y1682015D01*
G02X1516685Y1682244I2003J229D01*
G02X1516698Y1682473I2016J0D01*
G01Y1684884D01*
G02X1517001Y1685186I303J-1D01*
G37*
G36*
G01X1532749D02*
X1536449D01*
G02X1536752Y1684884I1J-302D01*
G01Y1674878D01*
G02X1536449Y1674576I-303J1D01*
G01X1532749D01*
G02X1532446Y1674878I-1J302D01*
G01Y1677290D01*
G02X1532433Y1677519I2003J229D01*
G02X1532446Y1677748I2016J0D01*
G01Y1682015D01*
G02X1532433Y1682244I2003J229D01*
G02X1532446Y1682473I2016J0D01*
G01Y1684884D01*
G02X1532749Y1685186I303J-1D01*
G37*
G36*
G01X1548497D02*
X1552197D01*
G02X1552500Y1684884I1J-302D01*
G01Y1674878D01*
G02X1552197Y1674576I-303J1D01*
G01X1548497D01*
G02X1548194Y1674878I-1J302D01*
G01Y1677290D01*
G02X1548181Y1677519I2003J229D01*
G02X1548194Y1677748I2016J0D01*
G01Y1682015D01*
G02X1548181Y1682244I2003J229D01*
G02X1548194Y1682473I2016J0D01*
G01Y1684884D01*
G02X1548497Y1685186I303J-1D01*
G37*
G36*
G01X237080Y1689124D02*
X240780D01*
G02X241082Y1688821I-1J-303D01*
G01Y1678815D01*
G02X240780Y1678512I-302J-1D01*
G01X237080D01*
G02X236778Y1678815I1J303D01*
G01Y1681219D01*
G02X236764Y1681456I2002J237D01*
G02X236778Y1681693I2016J0D01*
G01Y1685943D01*
G02X236764Y1686180I2002J237D01*
G02X236778Y1686417I2016J0D01*
G01Y1688821D01*
G02X237080Y1689124I302J1D01*
G37*
G36*
G01X252828D02*
X256528D01*
G02X256830Y1688821I-1J-303D01*
G01Y1678815D01*
G02X256528Y1678512I-302J-1D01*
G01X252828D01*
G02X252526Y1678815I1J303D01*
G01Y1681219D01*
G02X252512Y1681456I2002J237D01*
G02X252526Y1681693I2016J0D01*
G01Y1685943D01*
G02X252512Y1686180I2002J237D01*
G02X252526Y1686417I2016J0D01*
G01Y1688821D01*
G02X252828Y1689124I302J1D01*
G37*
G36*
G01X268576D02*
X272276D01*
G02X272578Y1688821I-1J-303D01*
G01Y1678815D01*
G02X272276Y1678512I-302J-1D01*
G01X268576D01*
G02X268274Y1678815I1J303D01*
G01Y1681219D01*
G02X268260Y1681456I2002J237D01*
G02X268274Y1681693I2016J0D01*
G01Y1685943D01*
G02X268260Y1686180I2002J237D01*
G02X268274Y1686417I2016J0D01*
G01Y1688821D01*
G02X268576Y1689124I302J1D01*
G37*
G36*
G01X284324D02*
X288024D01*
G02X288326Y1688821I-1J-303D01*
G01Y1678815D01*
G02X288024Y1678512I-302J-1D01*
G01X284324D01*
G02X284022Y1678815I1J303D01*
G01Y1681219D01*
G02X284008Y1681456I2002J237D01*
G02X284022Y1681693I2016J0D01*
G01Y1685943D01*
G02X284008Y1686180I2002J237D01*
G02X284022Y1686417I2016J0D01*
G01Y1688821D01*
G02X284324Y1689124I302J1D01*
G37*
G36*
G01X304009D02*
X307709D01*
G02X308012Y1688821I0J-303D01*
G01Y1678815D01*
G02X307709Y1678512I-303J0D01*
G01X304009D01*
G02X303706Y1678815I0J303D01*
G01Y1681227D01*
G02X303693Y1681456I2003J229D01*
G02X303706Y1681685I2016J0D01*
G01Y1685951D01*
G02X303693Y1686180I2003J229D01*
G02X303706Y1686409I2016J0D01*
G01Y1688821D01*
G02X304009Y1689124I303J0D01*
G37*
G36*
G01X319757D02*
X323457D01*
G02X323760Y1688821I0J-303D01*
G01Y1678815D01*
G02X323457Y1678512I-303J0D01*
G01X319757D01*
G02X319454Y1678815I0J303D01*
G01Y1681227D01*
G02X319441Y1681456I2003J229D01*
G02X319454Y1681685I2016J0D01*
G01Y1685951D01*
G02X319441Y1686180I2003J229D01*
G02X319454Y1686409I2016J0D01*
G01Y1688821D01*
G02X319757Y1689124I303J0D01*
G37*
G36*
G01X335505D02*
X339205D01*
G02X339508Y1688821I0J-303D01*
G01Y1678815D01*
G02X339205Y1678512I-303J0D01*
G01X335505D01*
G02X335202Y1678815I0J303D01*
G01Y1681227D01*
G02X335189Y1681456I2003J229D01*
G02X335202Y1681685I2016J0D01*
G01Y1685951D01*
G02X335189Y1686180I2003J229D01*
G02X335202Y1686409I2016J0D01*
G01Y1688821D01*
G02X335505Y1689124I303J0D01*
G37*
G36*
G01X351253D02*
X354953D01*
G02X355256Y1688821I0J-303D01*
G01Y1678815D01*
G02X354953Y1678512I-303J0D01*
G01X351253D01*
G02X350950Y1678815I0J303D01*
G01Y1681227D01*
G02X350937Y1681456I2003J229D01*
G02X350950Y1681685I2016J0D01*
G01Y1685951D01*
G02X350937Y1686180I2003J229D01*
G02X350950Y1686409I2016J0D01*
G01Y1688821D01*
G02X351253Y1689124I303J0D01*
G37*
G36*
G01X501253D02*
X504953D01*
G02X505256Y1688821I0J-303D01*
G01Y1678815D01*
G02X504953Y1678512I-303J0D01*
G01X501253D01*
G02X500950Y1678815I0J303D01*
G01Y1681227D01*
G02X500937Y1681456I2003J229D01*
G02X500950Y1681685I2016J0D01*
G01Y1685951D01*
G02X500937Y1686180I2003J229D01*
G02X500950Y1686409I2016J0D01*
G01Y1688821D01*
G02X501253Y1689124I303J0D01*
G37*
G36*
G01X517001D02*
X520701D01*
G02X521004Y1688821I0J-303D01*
G01Y1678815D01*
G02X520701Y1678512I-303J0D01*
G01X517001D01*
G02X516698Y1678815I0J303D01*
G01Y1681227D01*
G02X516685Y1681456I2003J229D01*
G02X516698Y1681685I2016J0D01*
G01Y1685951D01*
G02X516685Y1686180I2003J229D01*
G02X516698Y1686409I2016J0D01*
G01Y1688821D01*
G02X517001Y1689124I303J0D01*
G37*
G36*
G01X532749D02*
X536449D01*
G02X536752Y1688821I0J-303D01*
G01Y1678815D01*
G02X536449Y1678512I-303J0D01*
G01X532749D01*
G02X532446Y1678815I0J303D01*
G01Y1681227D01*
G02X532433Y1681456I2003J229D01*
G02X532446Y1681685I2016J0D01*
G01Y1685951D01*
G02X532433Y1686180I2003J229D01*
G02X532446Y1686409I2016J0D01*
G01Y1688821D01*
G02X532749Y1689124I303J0D01*
G37*
G36*
G01X548497D02*
X552197D01*
G02X552500Y1688821I0J-303D01*
G01Y1678815D01*
G02X552197Y1678512I-303J0D01*
G01X548497D01*
G02X548194Y1678815I0J303D01*
G01Y1681227D01*
G02X548181Y1681456I2003J229D01*
G02X548194Y1681685I2016J0D01*
G01Y1685951D01*
G02X548181Y1686180I2003J229D01*
G02X548194Y1686409I2016J0D01*
G01Y1688821D01*
G02X548497Y1689124I303J0D01*
G37*
G36*
G01X568182D02*
X571882D01*
G02X572184Y1688821I-1J-303D01*
G01Y1678815D01*
G02X571882Y1678512I-302J-1D01*
G01X568182D01*
G02X567880Y1678815I1J303D01*
G01Y1681219D01*
G02X567866Y1681456I2002J237D01*
G02X567880Y1681693I2016J0D01*
G01Y1685943D01*
G02X567866Y1686180I2002J237D01*
G02X567880Y1686417I2016J0D01*
G01Y1688821D01*
G02X568182Y1689124I302J1D01*
G37*
G36*
G01X583930D02*
X587630D01*
G02X587932Y1688821I-1J-303D01*
G01Y1678815D01*
G02X587630Y1678512I-302J-1D01*
G01X583930D01*
G02X583628Y1678815I1J303D01*
G01Y1681219D01*
G02X583614Y1681456I2002J237D01*
G02X583628Y1681693I2016J0D01*
G01Y1685943D01*
G02X583614Y1686180I2002J237D01*
G02X583628Y1686417I2016J0D01*
G01Y1688821D01*
G02X583930Y1689124I302J1D01*
G37*
G36*
G01X599678D02*
X603378D01*
G02X603680Y1688821I-1J-303D01*
G01Y1678815D01*
G02X603378Y1678512I-302J-1D01*
G01X599678D01*
G02X599376Y1678815I1J303D01*
G01Y1681219D01*
G02X599362Y1681456I2002J237D01*
G02X599376Y1681693I2016J0D01*
G01Y1685943D01*
G02X599362Y1686180I2002J237D01*
G02X599376Y1686417I2016J0D01*
G01Y1688821D01*
G02X599678Y1689124I302J1D01*
G37*
G36*
G01X615426D02*
X619126D01*
G02X619428Y1688821I-1J-303D01*
G01Y1678815D01*
G02X619126Y1678512I-302J-1D01*
G01X615426D01*
G02X615124Y1678815I1J303D01*
G01Y1681219D01*
G02X615110Y1681456I2002J237D01*
G02X615124Y1681693I2016J0D01*
G01Y1685943D01*
G02X615110Y1686180I2002J237D01*
G02X615124Y1686417I2016J0D01*
G01Y1688821D01*
G02X615426Y1689124I302J1D01*
G37*
G36*
G01X1244954D02*
X1248654D01*
G02X1248956Y1688821I-1J-303D01*
G01Y1678815D01*
G02X1248654Y1678512I-302J-1D01*
G01X1244954D01*
G02X1244652Y1678815I1J303D01*
G01Y1681219D01*
G02X1244638Y1681456I2002J237D01*
G02X1244652Y1681693I2016J0D01*
G01Y1685943D01*
G02X1244638Y1686180I2002J237D01*
G02X1244652Y1686417I2016J0D01*
G01Y1688821D01*
G02X1244954Y1689124I302J1D01*
G37*
G36*
G01X1260702D02*
X1264402D01*
G02X1264704Y1688821I-1J-303D01*
G01Y1678815D01*
G02X1264402Y1678512I-302J-1D01*
G01X1260702D01*
G02X1260400Y1678815I1J303D01*
G01Y1681219D01*
G02X1260386Y1681456I2002J237D01*
G02X1260400Y1681693I2016J0D01*
G01Y1685943D01*
G02X1260386Y1686180I2002J237D01*
G02X1260400Y1686417I2016J0D01*
G01Y1688821D01*
G02X1260702Y1689124I302J1D01*
G37*
G36*
G01X1276450D02*
X1280150D01*
G02X1280452Y1688821I-1J-303D01*
G01Y1678815D01*
G02X1280150Y1678512I-302J-1D01*
G01X1276450D01*
G02X1276148Y1678815I1J303D01*
G01Y1681219D01*
G02X1276134Y1681456I2002J237D01*
G02X1276148Y1681693I2016J0D01*
G01Y1685943D01*
G02X1276134Y1686180I2002J237D01*
G02X1276148Y1686417I2016J0D01*
G01Y1688821D01*
G02X1276450Y1689124I302J1D01*
G37*
G36*
G01X1292198D02*
X1295898D01*
G02X1296200Y1688821I-1J-303D01*
G01Y1678815D01*
G02X1295898Y1678512I-302J-1D01*
G01X1292198D01*
G02X1291896Y1678815I1J303D01*
G01Y1681219D01*
G02X1291882Y1681456I2002J237D01*
G02X1291896Y1681693I2016J0D01*
G01Y1685943D01*
G02X1291882Y1686180I2002J237D01*
G02X1291896Y1686417I2016J0D01*
G01Y1688821D01*
G02X1292198Y1689124I302J1D01*
G37*
G36*
G01X1311883D02*
X1315583D01*
G02X1315886Y1688821I0J-303D01*
G01Y1678815D01*
G02X1315583Y1678512I-303J0D01*
G01X1311883D01*
G02X1311580Y1678815I0J303D01*
G01Y1681227D01*
G02X1311567Y1681456I2003J229D01*
G02X1311580Y1681685I2016J0D01*
G01Y1685951D01*
G02X1311567Y1686180I2003J229D01*
G02X1311580Y1686409I2016J0D01*
G01Y1688821D01*
G02X1311883Y1689124I303J0D01*
G37*
G36*
G01X1327631D02*
X1331331D01*
G02X1331634Y1688821I0J-303D01*
G01Y1678815D01*
G02X1331331Y1678512I-303J0D01*
G01X1327631D01*
G02X1327328Y1678815I0J303D01*
G01Y1681227D01*
G02X1327315Y1681456I2003J229D01*
G02X1327328Y1681685I2016J0D01*
G01Y1685951D01*
G02X1327315Y1686180I2003J229D01*
G02X1327328Y1686409I2016J0D01*
G01Y1688821D01*
G02X1327631Y1689124I303J0D01*
G37*
G36*
G01X1343379D02*
X1347079D01*
G02X1347382Y1688821I0J-303D01*
G01Y1678815D01*
G02X1347079Y1678512I-303J0D01*
G01X1343379D01*
G02X1343076Y1678815I0J303D01*
G01Y1681227D01*
G02X1343063Y1681456I2003J229D01*
G02X1343076Y1681685I2016J0D01*
G01Y1685951D01*
G02X1343063Y1686180I2003J229D01*
G02X1343076Y1686409I2016J0D01*
G01Y1688821D01*
G02X1343379Y1689124I303J0D01*
G37*
G36*
G01X1359127D02*
X1362827D01*
G02X1363130Y1688821I0J-303D01*
G01Y1678815D01*
G02X1362827Y1678512I-303J0D01*
G01X1359127D01*
G02X1358824Y1678815I0J303D01*
G01Y1681227D01*
G02X1358811Y1681456I2003J229D01*
G02X1358824Y1681685I2016J0D01*
G01Y1685951D01*
G02X1358811Y1686180I2003J229D01*
G02X1358824Y1686409I2016J0D01*
G01Y1688821D01*
G02X1359127Y1689124I303J0D01*
G37*
G36*
G01X1509127D02*
X1512827D01*
G02X1513130Y1688821I0J-303D01*
G01Y1678815D01*
G02X1512827Y1678512I-303J0D01*
G01X1509127D01*
G02X1508824Y1678815I0J303D01*
G01Y1681227D01*
G02X1508811Y1681456I2003J229D01*
G02X1508824Y1681685I2016J0D01*
G01Y1685951D01*
G02X1508811Y1686180I2003J229D01*
G02X1508824Y1686409I2016J0D01*
G01Y1688821D01*
G02X1509127Y1689124I303J0D01*
G37*
G36*
G01X1524875D02*
X1528575D01*
G02X1528878Y1688821I0J-303D01*
G01Y1678815D01*
G02X1528575Y1678512I-303J0D01*
G01X1524875D01*
G02X1524572Y1678815I0J303D01*
G01Y1681227D01*
G02X1524559Y1681456I2003J229D01*
G02X1524572Y1681685I2016J0D01*
G01Y1685951D01*
G02X1524559Y1686180I2003J229D01*
G02X1524572Y1686409I2016J0D01*
G01Y1688821D01*
G02X1524875Y1689124I303J0D01*
G37*
G36*
G01X1540623D02*
X1544323D01*
G02X1544626Y1688821I0J-303D01*
G01Y1678815D01*
G02X1544323Y1678512I-303J0D01*
G01X1540623D01*
G02X1540320Y1678815I0J303D01*
G01Y1681227D01*
G02X1540307Y1681456I2003J229D01*
G02X1540320Y1681685I2016J0D01*
G01Y1685951D01*
G02X1540307Y1686180I2003J229D01*
G02X1540320Y1686409I2016J0D01*
G01Y1688821D01*
G02X1540623Y1689124I303J0D01*
G37*
G36*
G01X1556371D02*
X1560071D01*
G02X1560374Y1688821I0J-303D01*
G01Y1678815D01*
G02X1560071Y1678512I-303J0D01*
G01X1556371D01*
G02X1556068Y1678815I0J303D01*
G01Y1681227D01*
G02X1556055Y1681456I2003J229D01*
G02X1556068Y1681685I2016J0D01*
G01Y1685951D01*
G02X1556055Y1686180I2003J229D01*
G02X1556068Y1686409I2016J0D01*
G01Y1688821D01*
G02X1556371Y1689124I303J0D01*
G37*
G36*
G01X1576056D02*
X1579756D01*
G02X1580058Y1688821I-1J-303D01*
G01Y1678815D01*
G02X1579756Y1678512I-302J-1D01*
G01X1576056D01*
G02X1575754Y1678815I1J303D01*
G01Y1681219D01*
G02X1575740Y1681456I2002J237D01*
G02X1575754Y1681693I2016J0D01*
G01Y1685943D01*
G02X1575740Y1686180I2002J237D01*
G02X1575754Y1686417I2016J0D01*
G01Y1688821D01*
G02X1576056Y1689124I302J1D01*
G37*
G36*
G01X1591804D02*
X1595504D01*
G02X1595806Y1688821I-1J-303D01*
G01Y1678815D01*
G02X1595504Y1678512I-302J-1D01*
G01X1591804D01*
G02X1591502Y1678815I1J303D01*
G01Y1681219D01*
G02X1591488Y1681456I2002J237D01*
G02X1591502Y1681693I2016J0D01*
G01Y1685943D01*
G02X1591488Y1686180I2002J237D01*
G02X1591502Y1686417I2016J0D01*
G01Y1688821D01*
G02X1591804Y1689124I302J1D01*
G37*
G36*
G01X1607552D02*
X1611252D01*
G02X1611554Y1688821I-1J-303D01*
G01Y1678815D01*
G02X1611252Y1678512I-302J-1D01*
G01X1607552D01*
G02X1607250Y1678815I1J303D01*
G01Y1681219D01*
G02X1607236Y1681456I2002J237D01*
G02X1607250Y1681693I2016J0D01*
G01Y1685943D01*
G02X1607236Y1686180I2002J237D01*
G02X1607250Y1686417I2016J0D01*
G01Y1688821D01*
G02X1607552Y1689124I302J1D01*
G37*
G36*
G01X1623300D02*
X1627000D01*
G02X1627302Y1688821I-1J-303D01*
G01Y1678815D01*
G02X1627000Y1678512I-302J-1D01*
G01X1623300D01*
G02X1622998Y1678815I1J303D01*
G01Y1681219D01*
G02X1622984Y1681456I2002J237D01*
G02X1622998Y1681693I2016J0D01*
G01Y1685943D01*
G02X1622984Y1686180I2002J237D01*
G02X1622998Y1686417I2016J0D01*
G01Y1688821D01*
G02X1623300Y1689124I302J1D01*
G37*
G36*
G01X229206Y1699360D02*
X232906D01*
G02X233208Y1699057I-1J-303D01*
G01Y1689051D01*
G02X232906Y1688748I-302J-1D01*
G01X229206D01*
G02X228904Y1689051I1J303D01*
G01Y1691455D01*
G02X228890Y1691692I2002J237D01*
G02X228904Y1691929I2016J0D01*
G01Y1696180D01*
G02X228890Y1696417I2002J237D01*
G02X228904Y1696654I2016J0D01*
G01Y1699057D01*
G02X229206Y1699360I302J1D01*
G37*
G36*
G01X244954D02*
X248654D01*
G02X248956Y1699057I-1J-303D01*
G01Y1689051D01*
G02X248654Y1688748I-302J-1D01*
G01X244954D01*
G02X244652Y1689051I1J303D01*
G01Y1691455D01*
G02X244638Y1691692I2002J237D01*
G02X244652Y1691929I2016J0D01*
G01Y1696180D01*
G02X244638Y1696417I2002J237D01*
G02X244652Y1696654I2016J0D01*
G01Y1699057D01*
G02X244954Y1699360I302J1D01*
G37*
G36*
G01X260702D02*
X264402D01*
G02X264704Y1699057I-1J-303D01*
G01Y1689051D01*
G02X264402Y1688748I-302J-1D01*
G01X260702D01*
G02X260400Y1689051I1J303D01*
G01Y1691455D01*
G02X260386Y1691692I2002J237D01*
G02X260400Y1691929I2016J0D01*
G01Y1696180D01*
G02X260386Y1696417I2002J237D01*
G02X260400Y1696654I2016J0D01*
G01Y1699057D01*
G02X260702Y1699360I302J1D01*
G37*
G36*
G01X276450D02*
X280150D01*
G02X280452Y1699057I-1J-303D01*
G01Y1689051D01*
G02X280150Y1688748I-302J-1D01*
G01X276450D01*
G02X276148Y1689051I1J303D01*
G01Y1691455D01*
G02X276134Y1691692I2002J237D01*
G02X276148Y1691929I2016J0D01*
G01Y1696180D01*
G02X276134Y1696417I2002J237D01*
G02X276148Y1696654I2016J0D01*
G01Y1699057D01*
G02X276450Y1699360I302J1D01*
G37*
G36*
G01X296135D02*
X299835D01*
G02X300138Y1699057I0J-303D01*
G01Y1689051D01*
G02X299835Y1688748I-303J0D01*
G01X296135D01*
G02X295832Y1689051I0J303D01*
G01Y1691463D01*
G02X295819Y1691692I2003J229D01*
G02X295832Y1691921I2016J0D01*
G01Y1696188D01*
G02X295819Y1696417I2003J229D01*
G02X295832Y1696646I2016J0D01*
G01Y1699057D01*
G02X296135Y1699360I303J0D01*
G37*
G36*
G01X311883D02*
X315583D01*
G02X315886Y1699057I0J-303D01*
G01Y1689051D01*
G02X315583Y1688748I-303J0D01*
G01X311883D01*
G02X311580Y1689051I0J303D01*
G01Y1691463D01*
G02X311567Y1691692I2003J229D01*
G02X311580Y1691921I2016J0D01*
G01Y1696188D01*
G02X311567Y1696417I2003J229D01*
G02X311580Y1696646I2016J0D01*
G01Y1699057D01*
G02X311883Y1699360I303J0D01*
G37*
G36*
G01X327631D02*
X331331D01*
G02X331634Y1699057I0J-303D01*
G01Y1689051D01*
G02X331331Y1688748I-303J0D01*
G01X327631D01*
G02X327328Y1689051I0J303D01*
G01Y1691463D01*
G02X327315Y1691692I2003J229D01*
G02X327328Y1691921I2016J0D01*
G01Y1696188D01*
G02X327315Y1696417I2003J229D01*
G02X327328Y1696646I2016J0D01*
G01Y1699057D01*
G02X327631Y1699360I303J0D01*
G37*
G36*
G01X343379D02*
X347079D01*
G02X347382Y1699057I0J-303D01*
G01Y1689051D01*
G02X347079Y1688748I-303J0D01*
G01X343379D01*
G02X343076Y1689051I0J303D01*
G01Y1691463D01*
G02X343063Y1691692I2003J229D01*
G02X343076Y1691921I2016J0D01*
G01Y1696188D01*
G02X343063Y1696417I2003J229D01*
G02X343076Y1696646I2016J0D01*
G01Y1699057D01*
G02X343379Y1699360I303J0D01*
G37*
G36*
G01X493379D02*
X497079D01*
G02X497382Y1699057I0J-303D01*
G01Y1689051D01*
G02X497079Y1688748I-303J0D01*
G01X493379D01*
G02X493076Y1689051I0J303D01*
G01Y1691463D01*
G02X493063Y1691692I2003J229D01*
G02X493076Y1691921I2016J0D01*
G01Y1696188D01*
G02X493063Y1696417I2003J229D01*
G02X493076Y1696646I2016J0D01*
G01Y1699057D01*
G02X493379Y1699360I303J0D01*
G37*
G36*
G01X509127D02*
X512827D01*
G02X513130Y1699057I0J-303D01*
G01Y1689051D01*
G02X512827Y1688748I-303J0D01*
G01X509127D01*
G02X508824Y1689051I0J303D01*
G01Y1691463D01*
G02X508811Y1691692I2003J229D01*
G02X508824Y1691921I2016J0D01*
G01Y1696188D01*
G02X508811Y1696417I2003J229D01*
G02X508824Y1696646I2016J0D01*
G01Y1699057D01*
G02X509127Y1699360I303J0D01*
G37*
G36*
G01X524875D02*
X528575D01*
G02X528878Y1699057I0J-303D01*
G01Y1689051D01*
G02X528575Y1688748I-303J0D01*
G01X524875D01*
G02X524572Y1689051I0J303D01*
G01Y1691463D01*
G02X524559Y1691692I2003J229D01*
G02X524572Y1691921I2016J0D01*
G01Y1696188D01*
G02X524559Y1696417I2003J229D01*
G02X524572Y1696646I2016J0D01*
G01Y1699057D01*
G02X524875Y1699360I303J0D01*
G37*
G36*
G01X540623D02*
X544323D01*
G02X544626Y1699057I0J-303D01*
G01Y1689051D01*
G02X544323Y1688748I-303J0D01*
G01X540623D01*
G02X540320Y1689051I0J303D01*
G01Y1691463D01*
G02X540307Y1691692I2003J229D01*
G02X540320Y1691921I2016J0D01*
G01Y1696188D01*
G02X540307Y1696417I2003J229D01*
G02X540320Y1696646I2016J0D01*
G01Y1699057D01*
G02X540623Y1699360I303J0D01*
G37*
G36*
G01X560308D02*
X564008D01*
G02X564310Y1699057I-1J-303D01*
G01Y1689051D01*
G02X564008Y1688748I-302J-1D01*
G01X560308D01*
G02X560006Y1689051I1J303D01*
G01Y1691455D01*
G02X559992Y1691692I2002J237D01*
G02X560006Y1691929I2016J0D01*
G01Y1696180D01*
G02X559992Y1696417I2002J237D01*
G02X560006Y1696654I2016J0D01*
G01Y1699057D01*
G02X560308Y1699360I302J1D01*
G37*
G36*
G01X576056D02*
X579756D01*
G02X580058Y1699057I-1J-303D01*
G01Y1689051D01*
G02X579756Y1688748I-302J-1D01*
G01X576056D01*
G02X575754Y1689051I1J303D01*
G01Y1691455D01*
G02X575740Y1691692I2002J237D01*
G02X575754Y1691929I2016J0D01*
G01Y1696180D01*
G02X575740Y1696417I2002J237D01*
G02X575754Y1696654I2016J0D01*
G01Y1699057D01*
G02X576056Y1699360I302J1D01*
G37*
G36*
G01X591804D02*
X595504D01*
G02X595806Y1699057I-1J-303D01*
G01Y1689051D01*
G02X595504Y1688748I-302J-1D01*
G01X591804D01*
G02X591502Y1689051I1J303D01*
G01Y1691455D01*
G02X591488Y1691692I2002J237D01*
G02X591502Y1691929I2016J0D01*
G01Y1696180D01*
G02X591488Y1696417I2002J237D01*
G02X591502Y1696654I2016J0D01*
G01Y1699057D01*
G02X591804Y1699360I302J1D01*
G37*
G36*
G01X607552D02*
X611252D01*
G02X611554Y1699057I-1J-303D01*
G01Y1689051D01*
G02X611252Y1688748I-302J-1D01*
G01X607552D01*
G02X607250Y1689051I1J303D01*
G01Y1691455D01*
G02X607236Y1691692I2002J237D01*
G02X607250Y1691929I2016J0D01*
G01Y1696180D01*
G02X607236Y1696417I2002J237D01*
G02X607250Y1696654I2016J0D01*
G01Y1699057D01*
G02X607552Y1699360I302J1D01*
G37*
G36*
G01X1237080D02*
X1240780D01*
G02X1241082Y1699057I-1J-303D01*
G01Y1689051D01*
G02X1240780Y1688748I-302J-1D01*
G01X1237080D01*
G02X1236778Y1689051I1J303D01*
G01Y1691455D01*
G02X1236764Y1691692I2002J237D01*
G02X1236778Y1691929I2016J0D01*
G01Y1696180D01*
G02X1236764Y1696417I2002J237D01*
G02X1236778Y1696654I2016J0D01*
G01Y1699057D01*
G02X1237080Y1699360I302J1D01*
G37*
G36*
G01X1252828D02*
X1256528D01*
G02X1256830Y1699057I-1J-303D01*
G01Y1689051D01*
G02X1256528Y1688748I-302J-1D01*
G01X1252828D01*
G02X1252526Y1689051I1J303D01*
G01Y1691455D01*
G02X1252512Y1691692I2002J237D01*
G02X1252526Y1691929I2016J0D01*
G01Y1696180D01*
G02X1252512Y1696417I2002J237D01*
G02X1252526Y1696654I2016J0D01*
G01Y1699057D01*
G02X1252828Y1699360I302J1D01*
G37*
G36*
G01X1268576D02*
X1272276D01*
G02X1272578Y1699057I-1J-303D01*
G01Y1689051D01*
G02X1272276Y1688748I-302J-1D01*
G01X1268576D01*
G02X1268274Y1689051I1J303D01*
G01Y1691455D01*
G02X1268260Y1691692I2002J237D01*
G02X1268274Y1691929I2016J0D01*
G01Y1696180D01*
G02X1268260Y1696417I2002J237D01*
G02X1268274Y1696654I2016J0D01*
G01Y1699057D01*
G02X1268576Y1699360I302J1D01*
G37*
G36*
G01X1284324D02*
X1288024D01*
G02X1288326Y1699057I-1J-303D01*
G01Y1689051D01*
G02X1288024Y1688748I-302J-1D01*
G01X1284324D01*
G02X1284022Y1689051I1J303D01*
G01Y1691455D01*
G02X1284008Y1691692I2002J237D01*
G02X1284022Y1691929I2016J0D01*
G01Y1696180D01*
G02X1284008Y1696417I2002J237D01*
G02X1284022Y1696654I2016J0D01*
G01Y1699057D01*
G02X1284324Y1699360I302J1D01*
G37*
G36*
G01X1304009D02*
X1307709D01*
G02X1308012Y1699057I0J-303D01*
G01Y1689051D01*
G02X1307709Y1688748I-303J0D01*
G01X1304009D01*
G02X1303706Y1689051I0J303D01*
G01Y1691463D01*
G02X1303693Y1691692I2003J229D01*
G02X1303706Y1691921I2016J0D01*
G01Y1696188D01*
G02X1303693Y1696417I2003J229D01*
G02X1303706Y1696646I2016J0D01*
G01Y1699057D01*
G02X1304009Y1699360I303J0D01*
G37*
G36*
G01X1319757D02*
X1323457D01*
G02X1323760Y1699057I0J-303D01*
G01Y1689051D01*
G02X1323457Y1688748I-303J0D01*
G01X1319757D01*
G02X1319454Y1689051I0J303D01*
G01Y1691463D01*
G02X1319441Y1691692I2003J229D01*
G02X1319454Y1691921I2016J0D01*
G01Y1696188D01*
G02X1319441Y1696417I2003J229D01*
G02X1319454Y1696646I2016J0D01*
G01Y1699057D01*
G02X1319757Y1699360I303J0D01*
G37*
G36*
G01X1335505D02*
X1339205D01*
G02X1339508Y1699057I0J-303D01*
G01Y1689051D01*
G02X1339205Y1688748I-303J0D01*
G01X1335505D01*
G02X1335202Y1689051I0J303D01*
G01Y1691463D01*
G02X1335189Y1691692I2003J229D01*
G02X1335202Y1691921I2016J0D01*
G01Y1696188D01*
G02X1335189Y1696417I2003J229D01*
G02X1335202Y1696646I2016J0D01*
G01Y1699057D01*
G02X1335505Y1699360I303J0D01*
G37*
G36*
G01X1351253D02*
X1354953D01*
G02X1355256Y1699057I0J-303D01*
G01Y1689051D01*
G02X1354953Y1688748I-303J0D01*
G01X1351253D01*
G02X1350950Y1689051I0J303D01*
G01Y1691463D01*
G02X1350937Y1691692I2003J229D01*
G02X1350950Y1691921I2016J0D01*
G01Y1696188D01*
G02X1350937Y1696417I2003J229D01*
G02X1350950Y1696646I2016J0D01*
G01Y1699057D01*
G02X1351253Y1699360I303J0D01*
G37*
G36*
G01X1501253D02*
X1504953D01*
G02X1505256Y1699057I0J-303D01*
G01Y1689051D01*
G02X1504953Y1688748I-303J0D01*
G01X1501253D01*
G02X1500950Y1689051I0J303D01*
G01Y1691463D01*
G02X1500937Y1691692I2003J229D01*
G02X1500950Y1691921I2016J0D01*
G01Y1696188D01*
G02X1500937Y1696417I2003J229D01*
G02X1500950Y1696646I2016J0D01*
G01Y1699057D01*
G02X1501253Y1699360I303J0D01*
G37*
G36*
G01X1517001D02*
X1520701D01*
G02X1521004Y1699057I0J-303D01*
G01Y1689051D01*
G02X1520701Y1688748I-303J0D01*
G01X1517001D01*
G02X1516698Y1689051I0J303D01*
G01Y1691463D01*
G02X1516685Y1691692I2003J229D01*
G02X1516698Y1691921I2016J0D01*
G01Y1696188D01*
G02X1516685Y1696417I2003J229D01*
G02X1516698Y1696646I2016J0D01*
G01Y1699057D01*
G02X1517001Y1699360I303J0D01*
G37*
G36*
G01X1532749D02*
X1536449D01*
G02X1536752Y1699057I0J-303D01*
G01Y1689051D01*
G02X1536449Y1688748I-303J0D01*
G01X1532749D01*
G02X1532446Y1689051I0J303D01*
G01Y1691463D01*
G02X1532433Y1691692I2003J229D01*
G02X1532446Y1691921I2016J0D01*
G01Y1696188D01*
G02X1532433Y1696417I2003J229D01*
G02X1532446Y1696646I2016J0D01*
G01Y1699057D01*
G02X1532749Y1699360I303J0D01*
G37*
G36*
G01X1548497D02*
X1552197D01*
G02X1552500Y1699057I0J-303D01*
G01Y1689051D01*
G02X1552197Y1688748I-303J0D01*
G01X1548497D01*
G02X1548194Y1689051I0J303D01*
G01Y1691463D01*
G02X1548181Y1691692I2003J229D01*
G02X1548194Y1691921I2016J0D01*
G01Y1696188D01*
G02X1548181Y1696417I2003J229D01*
G02X1548194Y1696646I2016J0D01*
G01Y1699057D01*
G02X1548497Y1699360I303J0D01*
G37*
G36*
G01X1568182D02*
X1571882D01*
G02X1572184Y1699057I-1J-303D01*
G01Y1689051D01*
G02X1571882Y1688748I-302J-1D01*
G01X1568182D01*
G02X1567880Y1689051I1J303D01*
G01Y1691455D01*
G02X1567866Y1691692I2002J237D01*
G02X1567880Y1691929I2016J0D01*
G01Y1696180D01*
G02X1567866Y1696417I2002J237D01*
G02X1567880Y1696654I2016J0D01*
G01Y1699057D01*
G02X1568182Y1699360I302J1D01*
G37*
G36*
G01X1583930D02*
X1587630D01*
G02X1587932Y1699057I-1J-303D01*
G01Y1689051D01*
G02X1587630Y1688748I-302J-1D01*
G01X1583930D01*
G02X1583628Y1689051I1J303D01*
G01Y1691455D01*
G02X1583614Y1691692I2002J237D01*
G02X1583628Y1691929I2016J0D01*
G01Y1696180D01*
G02X1583614Y1696417I2002J237D01*
G02X1583628Y1696654I2016J0D01*
G01Y1699057D01*
G02X1583930Y1699360I302J1D01*
G37*
G36*
G01X1599678D02*
X1603378D01*
G02X1603680Y1699057I-1J-303D01*
G01Y1689051D01*
G02X1603378Y1688748I-302J-1D01*
G01X1599678D01*
G02X1599376Y1689051I1J303D01*
G01Y1691455D01*
G02X1599362Y1691692I2002J237D01*
G02X1599376Y1691929I2016J0D01*
G01Y1696180D01*
G02X1599362Y1696417I2002J237D01*
G02X1599376Y1696654I2016J0D01*
G01Y1699057D01*
G02X1599678Y1699360I302J1D01*
G37*
G36*
G01X1615426D02*
X1619126D01*
G02X1619428Y1699057I-1J-303D01*
G01Y1689051D01*
G02X1619126Y1688748I-302J-1D01*
G01X1615426D01*
G02X1615124Y1689051I1J303D01*
G01Y1691455D01*
G02X1615110Y1691692I2002J237D01*
G02X1615124Y1691929I2016J0D01*
G01Y1696180D01*
G02X1615110Y1696417I2002J237D01*
G02X1615124Y1696654I2016J0D01*
G01Y1699057D01*
G02X1615426Y1699360I302J1D01*
G37*
G36*
G01X237080Y1703296D02*
X240780D01*
G02X241082Y1702994I0J-302D01*
G01Y1692988D01*
G02X240780Y1692686I-302J0D01*
G01X237080D01*
G02X236778Y1692988I0J302D01*
G01Y1695392D01*
G02X236764Y1695629I2002J237D01*
G02X236778Y1695866I2016J0D01*
G01Y1700117D01*
G02X236764Y1700354I2002J237D01*
G02X236778Y1700591I2016J0D01*
G01Y1702994D01*
G02X237080Y1703296I302J0D01*
G37*
G36*
G01X252828D02*
X256528D01*
G02X256830Y1702994I0J-302D01*
G01Y1692988D01*
G02X256528Y1692686I-302J0D01*
G01X252828D01*
G02X252526Y1692988I0J302D01*
G01Y1695392D01*
G02X252512Y1695629I2002J237D01*
G02X252526Y1695866I2016J0D01*
G01Y1700117D01*
G02X252512Y1700354I2002J237D01*
G02X252526Y1700591I2016J0D01*
G01Y1702994D01*
G02X252828Y1703296I302J0D01*
G37*
G36*
G01X268576D02*
X272276D01*
G02X272578Y1702994I0J-302D01*
G01Y1692988D01*
G02X272276Y1692686I-302J0D01*
G01X268576D01*
G02X268274Y1692988I0J302D01*
G01Y1695392D01*
G02X268260Y1695629I2002J237D01*
G02X268274Y1695866I2016J0D01*
G01Y1700117D01*
G02X268260Y1700354I2002J237D01*
G02X268274Y1700591I2016J0D01*
G01Y1702994D01*
G02X268576Y1703296I302J0D01*
G37*
G36*
G01X284324D02*
X288024D01*
G02X288326Y1702994I0J-302D01*
G01Y1692988D01*
G02X288024Y1692686I-302J0D01*
G01X284324D01*
G02X284022Y1692988I0J302D01*
G01Y1695392D01*
G02X284008Y1695629I2002J237D01*
G02X284022Y1695866I2016J0D01*
G01Y1700117D01*
G02X284008Y1700354I2002J237D01*
G02X284022Y1700591I2016J0D01*
G01Y1702994D01*
G02X284324Y1703296I302J0D01*
G37*
G36*
G01X568182D02*
X571882D01*
G02X572184Y1702994I0J-302D01*
G01Y1692988D01*
G02X571882Y1692686I-302J0D01*
G01X568182D01*
G02X567880Y1692988I0J302D01*
G01Y1695392D01*
G02X567866Y1695629I2002J237D01*
G02X567880Y1695866I2016J0D01*
G01Y1700117D01*
G02X567866Y1700354I2002J237D01*
G02X567880Y1700591I2016J0D01*
G01Y1702994D01*
G02X568182Y1703296I302J0D01*
G37*
G36*
G01X583930D02*
X587630D01*
G02X587932Y1702994I0J-302D01*
G01Y1692988D01*
G02X587630Y1692686I-302J0D01*
G01X583930D01*
G02X583628Y1692988I0J302D01*
G01Y1695392D01*
G02X583614Y1695629I2002J237D01*
G02X583628Y1695866I2016J0D01*
G01Y1700117D01*
G02X583614Y1700354I2002J237D01*
G02X583628Y1700591I2016J0D01*
G01Y1702994D01*
G02X583930Y1703296I302J0D01*
G37*
G36*
G01X599678D02*
X603378D01*
G02X603680Y1702994I0J-302D01*
G01Y1692988D01*
G02X603378Y1692686I-302J0D01*
G01X599678D01*
G02X599376Y1692988I0J302D01*
G01Y1695392D01*
G02X599362Y1695629I2002J237D01*
G02X599376Y1695866I2016J0D01*
G01Y1700117D01*
G02X599362Y1700354I2002J237D01*
G02X599376Y1700591I2016J0D01*
G01Y1702994D01*
G02X599678Y1703296I302J0D01*
G37*
G36*
G01X615426D02*
X619126D01*
G02X619428Y1702994I0J-302D01*
G01Y1692988D01*
G02X619126Y1692686I-302J0D01*
G01X615426D01*
G02X615124Y1692988I0J302D01*
G01Y1695392D01*
G02X615110Y1695629I2002J237D01*
G02X615124Y1695866I2016J0D01*
G01Y1700117D01*
G02X615110Y1700354I2002J237D01*
G02X615124Y1700591I2016J0D01*
G01Y1702994D01*
G02X615426Y1703296I302J0D01*
G37*
G36*
G01X1244954D02*
X1248654D01*
G02X1248956Y1702994I0J-302D01*
G01Y1692988D01*
G02X1248654Y1692686I-302J0D01*
G01X1244954D01*
G02X1244652Y1692988I0J302D01*
G01Y1695392D01*
G02X1244638Y1695629I2002J237D01*
G02X1244652Y1695866I2016J0D01*
G01Y1700117D01*
G02X1244638Y1700354I2002J237D01*
G02X1244652Y1700591I2016J0D01*
G01Y1702994D01*
G02X1244954Y1703296I302J0D01*
G37*
G36*
G01X1260702D02*
X1264402D01*
G02X1264704Y1702994I0J-302D01*
G01Y1692988D01*
G02X1264402Y1692686I-302J0D01*
G01X1260702D01*
G02X1260400Y1692988I0J302D01*
G01Y1695392D01*
G02X1260386Y1695629I2002J237D01*
G02X1260400Y1695866I2016J0D01*
G01Y1700117D01*
G02X1260386Y1700354I2002J237D01*
G02X1260400Y1700591I2016J0D01*
G01Y1702994D01*
G02X1260702Y1703296I302J0D01*
G37*
G36*
G01X1276450D02*
X1280150D01*
G02X1280452Y1702994I0J-302D01*
G01Y1692988D01*
G02X1280150Y1692686I-302J0D01*
G01X1276450D01*
G02X1276148Y1692988I0J302D01*
G01Y1695392D01*
G02X1276134Y1695629I2002J237D01*
G02X1276148Y1695866I2016J0D01*
G01Y1700117D01*
G02X1276134Y1700354I2002J237D01*
G02X1276148Y1700591I2016J0D01*
G01Y1702994D01*
G02X1276450Y1703296I302J0D01*
G37*
G36*
G01X1292198D02*
X1295898D01*
G02X1296200Y1702994I0J-302D01*
G01Y1692988D01*
G02X1295898Y1692686I-302J0D01*
G01X1292198D01*
G02X1291896Y1692988I0J302D01*
G01Y1695392D01*
G02X1291882Y1695629I2002J237D01*
G02X1291896Y1695866I2016J0D01*
G01Y1700117D01*
G02X1291882Y1700354I2002J237D01*
G02X1291896Y1700591I2016J0D01*
G01Y1702994D01*
G02X1292198Y1703296I302J0D01*
G37*
G36*
G01X1576056D02*
X1579756D01*
G02X1580058Y1702994I0J-302D01*
G01Y1692988D01*
G02X1579756Y1692686I-302J0D01*
G01X1576056D01*
G02X1575754Y1692988I0J302D01*
G01Y1695392D01*
G02X1575740Y1695629I2002J237D01*
G02X1575754Y1695866I2016J0D01*
G01Y1700117D01*
G02X1575740Y1700354I2002J237D01*
G02X1575754Y1700591I2016J0D01*
G01Y1702994D01*
G02X1576056Y1703296I302J0D01*
G37*
G36*
G01X1591804D02*
X1595504D01*
G02X1595806Y1702994I0J-302D01*
G01Y1692988D01*
G02X1595504Y1692686I-302J0D01*
G01X1591804D01*
G02X1591502Y1692988I0J302D01*
G01Y1695392D01*
G02X1591488Y1695629I2002J237D01*
G02X1591502Y1695866I2016J0D01*
G01Y1700117D01*
G02X1591488Y1700354I2002J237D01*
G02X1591502Y1700591I2016J0D01*
G01Y1702994D01*
G02X1591804Y1703296I302J0D01*
G37*
G36*
G01X1607552D02*
X1611252D01*
G02X1611554Y1702994I0J-302D01*
G01Y1692988D01*
G02X1611252Y1692686I-302J0D01*
G01X1607552D01*
G02X1607250Y1692988I0J302D01*
G01Y1695392D01*
G02X1607236Y1695629I2002J237D01*
G02X1607250Y1695866I2016J0D01*
G01Y1700117D01*
G02X1607236Y1700354I2002J237D01*
G02X1607250Y1700591I2016J0D01*
G01Y1702994D01*
G02X1607552Y1703296I302J0D01*
G37*
G36*
G01X1623300D02*
X1627000D01*
G02X1627302Y1702994I0J-302D01*
G01Y1692988D01*
G02X1627000Y1692686I-302J0D01*
G01X1623300D01*
G02X1622998Y1692988I0J302D01*
G01Y1695392D01*
G02X1622984Y1695629I2002J237D01*
G02X1622998Y1695866I2016J0D01*
G01Y1700117D01*
G02X1622984Y1700354I2002J237D01*
G02X1622998Y1700591I2016J0D01*
G01Y1702994D01*
G02X1623300Y1703296I302J0D01*
G37*
G36*
G01X304009D02*
X307709D01*
G02X308012Y1702994I1J-302D01*
G01Y1692988D01*
G02X307709Y1692686I-303J1D01*
G01X304009D01*
G02X303706Y1692988I-1J302D01*
G01Y1695400D01*
G02X303693Y1695629I2003J229D01*
G02X303706Y1695858I2016J0D01*
G01Y1700125D01*
G02X303693Y1700354I2003J229D01*
G02X303706Y1700583I2016J0D01*
G01Y1702994D01*
G02X304009Y1703296I303J-1D01*
G37*
G36*
G01X319757D02*
X323457D01*
G02X323760Y1702994I1J-302D01*
G01Y1692988D01*
G02X323457Y1692686I-303J1D01*
G01X319757D01*
G02X319454Y1692988I-1J302D01*
G01Y1695400D01*
G02X319441Y1695629I2003J229D01*
G02X319454Y1695858I2016J0D01*
G01Y1700125D01*
G02X319441Y1700354I2003J229D01*
G02X319454Y1700583I2016J0D01*
G01Y1702994D01*
G02X319757Y1703296I303J-1D01*
G37*
G36*
G01X335505D02*
X339205D01*
G02X339508Y1702994I1J-302D01*
G01Y1692988D01*
G02X339205Y1692686I-303J1D01*
G01X335505D01*
G02X335202Y1692988I-1J302D01*
G01Y1695400D01*
G02X335189Y1695629I2003J229D01*
G02X335202Y1695858I2016J0D01*
G01Y1700125D01*
G02X335189Y1700354I2003J229D01*
G02X335202Y1700583I2016J0D01*
G01Y1702994D01*
G02X335505Y1703296I303J-1D01*
G37*
G36*
G01X351253D02*
X354953D01*
G02X355256Y1702994I1J-302D01*
G01Y1692988D01*
G02X354953Y1692686I-303J1D01*
G01X351253D01*
G02X350950Y1692988I-1J302D01*
G01Y1695400D01*
G02X350937Y1695629I2003J229D01*
G02X350950Y1695858I2016J0D01*
G01Y1700125D01*
G02X350937Y1700354I2003J229D01*
G02X350950Y1700583I2016J0D01*
G01Y1702994D01*
G02X351253Y1703296I303J-1D01*
G37*
G36*
G01X501253D02*
X504953D01*
G02X505256Y1702994I1J-302D01*
G01Y1692988D01*
G02X504953Y1692686I-303J1D01*
G01X501253D01*
G02X500950Y1692988I-1J302D01*
G01Y1695400D01*
G02X500937Y1695629I2003J229D01*
G02X500950Y1695858I2016J0D01*
G01Y1700125D01*
G02X500937Y1700354I2003J229D01*
G02X500950Y1700583I2016J0D01*
G01Y1702994D01*
G02X501253Y1703296I303J-1D01*
G37*
G36*
G01X517001D02*
X520701D01*
G02X521004Y1702994I1J-302D01*
G01Y1692988D01*
G02X520701Y1692686I-303J1D01*
G01X517001D01*
G02X516698Y1692988I-1J302D01*
G01Y1695400D01*
G02X516685Y1695629I2003J229D01*
G02X516698Y1695858I2016J0D01*
G01Y1700125D01*
G02X516685Y1700354I2003J229D01*
G02X516698Y1700583I2016J0D01*
G01Y1702994D01*
G02X517001Y1703296I303J-1D01*
G37*
G36*
G01X532749D02*
X536449D01*
G02X536752Y1702994I1J-302D01*
G01Y1692988D01*
G02X536449Y1692686I-303J1D01*
G01X532749D01*
G02X532446Y1692988I-1J302D01*
G01Y1695400D01*
G02X532433Y1695629I2003J229D01*
G02X532446Y1695858I2016J0D01*
G01Y1700125D01*
G02X532433Y1700354I2003J229D01*
G02X532446Y1700583I2016J0D01*
G01Y1702994D01*
G02X532749Y1703296I303J-1D01*
G37*
G36*
G01X548497D02*
X552197D01*
G02X552500Y1702994I1J-302D01*
G01Y1692988D01*
G02X552197Y1692686I-303J1D01*
G01X548497D01*
G02X548194Y1692988I-1J302D01*
G01Y1695400D01*
G02X548181Y1695629I2003J229D01*
G02X548194Y1695858I2016J0D01*
G01Y1700125D01*
G02X548181Y1700354I2003J229D01*
G02X548194Y1700583I2016J0D01*
G01Y1702994D01*
G02X548497Y1703296I303J-1D01*
G37*
G36*
G01X1311883D02*
X1315583D01*
G02X1315886Y1702994I1J-302D01*
G01Y1692988D01*
G02X1315583Y1692686I-303J1D01*
G01X1311883D01*
G02X1311580Y1692988I-1J302D01*
G01Y1695400D01*
G02X1311567Y1695629I2003J229D01*
G02X1311580Y1695858I2016J0D01*
G01Y1700125D01*
G02X1311567Y1700354I2003J229D01*
G02X1311580Y1700583I2016J0D01*
G01Y1702994D01*
G02X1311883Y1703296I303J-1D01*
G37*
G36*
G01X1327631D02*
X1331331D01*
G02X1331634Y1702994I1J-302D01*
G01Y1692988D01*
G02X1331331Y1692686I-303J1D01*
G01X1327631D01*
G02X1327328Y1692988I-1J302D01*
G01Y1695400D01*
G02X1327315Y1695629I2003J229D01*
G02X1327328Y1695858I2016J0D01*
G01Y1700125D01*
G02X1327315Y1700354I2003J229D01*
G02X1327328Y1700583I2016J0D01*
G01Y1702994D01*
G02X1327631Y1703296I303J-1D01*
G37*
G36*
G01X1343379D02*
X1347079D01*
G02X1347382Y1702994I1J-302D01*
G01Y1692988D01*
G02X1347079Y1692686I-303J1D01*
G01X1343379D01*
G02X1343076Y1692988I-1J302D01*
G01Y1695400D01*
G02X1343063Y1695629I2003J229D01*
G02X1343076Y1695858I2016J0D01*
G01Y1700125D01*
G02X1343063Y1700354I2003J229D01*
G02X1343076Y1700583I2016J0D01*
G01Y1702994D01*
G02X1343379Y1703296I303J-1D01*
G37*
G36*
G01X1359127D02*
X1362827D01*
G02X1363130Y1702994I1J-302D01*
G01Y1692988D01*
G02X1362827Y1692686I-303J1D01*
G01X1359127D01*
G02X1358824Y1692988I-1J302D01*
G01Y1695400D01*
G02X1358811Y1695629I2003J229D01*
G02X1358824Y1695858I2016J0D01*
G01Y1700125D01*
G02X1358811Y1700354I2003J229D01*
G02X1358824Y1700583I2016J0D01*
G01Y1702994D01*
G02X1359127Y1703296I303J-1D01*
G37*
G36*
G01X1509127D02*
X1512827D01*
G02X1513130Y1702994I1J-302D01*
G01Y1692988D01*
G02X1512827Y1692686I-303J1D01*
G01X1509127D01*
G02X1508824Y1692988I-1J302D01*
G01Y1695400D01*
G02X1508811Y1695629I2003J229D01*
G02X1508824Y1695858I2016J0D01*
G01Y1700125D01*
G02X1508811Y1700354I2003J229D01*
G02X1508824Y1700583I2016J0D01*
G01Y1702994D01*
G02X1509127Y1703296I303J-1D01*
G37*
G36*
G01X1524875D02*
X1528575D01*
G02X1528878Y1702994I1J-302D01*
G01Y1692988D01*
G02X1528575Y1692686I-303J1D01*
G01X1524875D01*
G02X1524572Y1692988I-1J302D01*
G01Y1695400D01*
G02X1524559Y1695629I2003J229D01*
G02X1524572Y1695858I2016J0D01*
G01Y1700125D01*
G02X1524559Y1700354I2003J229D01*
G02X1524572Y1700583I2016J0D01*
G01Y1702994D01*
G02X1524875Y1703296I303J-1D01*
G37*
G36*
G01X1540623D02*
X1544323D01*
G02X1544626Y1702994I1J-302D01*
G01Y1692988D01*
G02X1544323Y1692686I-303J1D01*
G01X1540623D01*
G02X1540320Y1692988I-1J302D01*
G01Y1695400D01*
G02X1540307Y1695629I2003J229D01*
G02X1540320Y1695858I2016J0D01*
G01Y1700125D01*
G02X1540307Y1700354I2003J229D01*
G02X1540320Y1700583I2016J0D01*
G01Y1702994D01*
G02X1540623Y1703296I303J-1D01*
G37*
G36*
G01X1556371D02*
X1560071D01*
G02X1560374Y1702994I1J-302D01*
G01Y1692988D01*
G02X1560071Y1692686I-303J1D01*
G01X1556371D01*
G02X1556068Y1692988I-1J302D01*
G01Y1695400D01*
G02X1556055Y1695629I2003J229D01*
G02X1556068Y1695858I2016J0D01*
G01Y1700125D01*
G02X1556055Y1700354I2003J229D01*
G02X1556068Y1700583I2016J0D01*
G01Y1702994D01*
G02X1556371Y1703296I303J-1D01*
G37*
G36*
G01X229206Y1713532D02*
X232906D01*
G02X233208Y1713230I0J-302D01*
G01Y1703224D01*
G02X232906Y1702922I-302J0D01*
G01X229206D01*
G02X228904Y1703224I0J302D01*
G01Y1705256D01*
G02X228813Y1705866I2002J610D01*
G02X229536Y1707448I2092J0D01*
G01X229854Y1708097D01*
G03Y1708359I-267J131D01*
G01X229536Y1709008D01*
G02X228813Y1710590I1369J1582D01*
G02X228904Y1711200I2093J0D01*
G01Y1713230D01*
G02X229206Y1713532I302J0D01*
G37*
G36*
G01X244954D02*
X248654D01*
G02X248956Y1713230I0J-302D01*
G01Y1703224D01*
G02X248654Y1702922I-302J0D01*
G01X244954D01*
G02X244652Y1703224I0J302D01*
G01Y1705256D01*
G02X244561Y1705866I2002J610D01*
G02X245284Y1707448I2092J0D01*
G01X245602Y1708097D01*
G03Y1708359I-267J131D01*
G01X245284Y1709008D01*
G02X244561Y1710590I1369J1582D01*
G02X244652Y1711200I2093J0D01*
G01Y1713230D01*
G02X244954Y1713532I302J0D01*
G37*
G36*
G01X260702D02*
X264402D01*
G02X264704Y1713230I0J-302D01*
G01Y1703224D01*
G02X264402Y1702922I-302J0D01*
G01X260702D01*
G02X260400Y1703224I0J302D01*
G01Y1705256D01*
G02X260309Y1705866I2002J610D01*
G02X261032Y1707448I2092J0D01*
G01X261350Y1708097D01*
G03Y1708359I-267J131D01*
G01X261032Y1709008D01*
G02X260309Y1710590I1369J1582D01*
G02X260400Y1711200I2093J0D01*
G01Y1713230D01*
G02X260702Y1713532I302J0D01*
G37*
G36*
G01X276450D02*
X280150D01*
G02X280452Y1713230I0J-302D01*
G01Y1703224D01*
G02X280150Y1702922I-302J0D01*
G01X276450D01*
G02X276148Y1703224I0J302D01*
G01Y1705256D01*
G02X276057Y1705866I2002J610D01*
G02X276780Y1707448I2092J0D01*
G01X277098Y1708097D01*
G03Y1708359I-267J131D01*
G01X276780Y1709008D01*
G02X276057Y1710590I1369J1582D01*
G02X276148Y1711200I2093J0D01*
G01Y1713230D01*
G02X276450Y1713532I302J0D01*
G37*
G36*
G01X560308D02*
X564008D01*
G02X564310Y1713230I0J-302D01*
G01Y1703224D01*
G02X564008Y1702922I-302J0D01*
G01X560308D01*
G02X560006Y1703224I0J302D01*
G01Y1705629D01*
G02X559992Y1705866I2002J237D01*
G02X560006Y1706103I2016J0D01*
G01Y1710353D01*
G02X559992Y1710590I2002J237D01*
G02X560006Y1710827I2016J0D01*
G01Y1713230D01*
G02X560308Y1713532I302J0D01*
G37*
G36*
G01X576056D02*
X579756D01*
G02X580058Y1713230I0J-302D01*
G01Y1703224D01*
G02X579756Y1702922I-302J0D01*
G01X576056D01*
G02X575754Y1703224I0J302D01*
G01Y1705629D01*
G02X575740Y1705866I2002J237D01*
G02X575754Y1706103I2016J0D01*
G01Y1710353D01*
G02X575740Y1710590I2002J237D01*
G02X575754Y1710827I2016J0D01*
G01Y1713230D01*
G02X576056Y1713532I302J0D01*
G37*
G36*
G01X591804D02*
X595504D01*
G02X595806Y1713230I0J-302D01*
G01Y1703224D01*
G02X595504Y1702922I-302J0D01*
G01X591804D01*
G02X591502Y1703224I0J302D01*
G01Y1705629D01*
G02X591488Y1705866I2002J237D01*
G02X591502Y1706103I2016J0D01*
G01Y1710353D01*
G02X591488Y1710590I2002J237D01*
G02X591502Y1710827I2016J0D01*
G01Y1713230D01*
G02X591804Y1713532I302J0D01*
G37*
G36*
G01X607552D02*
X611252D01*
G02X611554Y1713230I0J-302D01*
G01Y1703224D01*
G02X611252Y1702922I-302J0D01*
G01X607552D01*
G02X607250Y1703224I0J302D01*
G01Y1705629D01*
G02X607236Y1705866I2002J237D01*
G02X607250Y1706103I2016J0D01*
G01Y1710353D01*
G02X607236Y1710590I2002J237D01*
G02X607250Y1710827I2016J0D01*
G01Y1713230D01*
G02X607552Y1713532I302J0D01*
G37*
G36*
G01X1237080D02*
X1240780D01*
G02X1241082Y1713230I0J-302D01*
G01Y1703224D01*
G02X1240780Y1702922I-302J0D01*
G01X1237080D01*
G02X1236778Y1703224I0J302D01*
G01Y1705256D01*
G02X1236687Y1705866I2002J610D01*
G02X1237410Y1707448I2092J0D01*
G01X1237728Y1708097D01*
G03Y1708359I-267J131D01*
G01X1237410Y1709008D01*
G02X1236687Y1710590I1369J1582D01*
G02X1236778Y1711200I2093J0D01*
G01Y1713230D01*
G02X1237080Y1713532I302J0D01*
G37*
G36*
G01X1252828D02*
X1256528D01*
G02X1256830Y1713230I0J-302D01*
G01Y1703224D01*
G02X1256528Y1702922I-302J0D01*
G01X1252828D01*
G02X1252526Y1703224I0J302D01*
G01Y1705256D01*
G02X1252435Y1705866I2002J610D01*
G02X1253158Y1707448I2092J0D01*
G01X1253476Y1708097D01*
G03Y1708359I-267J131D01*
G01X1253158Y1709008D01*
G02X1252435Y1710590I1369J1582D01*
G02X1252526Y1711200I2093J0D01*
G01Y1713230D01*
G02X1252828Y1713532I302J0D01*
G37*
G36*
G01X1268576D02*
X1272276D01*
G02X1272578Y1713230I0J-302D01*
G01Y1703224D01*
G02X1272276Y1702922I-302J0D01*
G01X1268576D01*
G02X1268274Y1703224I0J302D01*
G01Y1705256D01*
G02X1268183Y1705866I2002J610D01*
G02X1268906Y1707448I2092J0D01*
G01X1269224Y1708097D01*
G03Y1708359I-267J131D01*
G01X1268906Y1709008D01*
G02X1268183Y1710590I1369J1582D01*
G02X1268274Y1711200I2093J0D01*
G01Y1713230D01*
G02X1268576Y1713532I302J0D01*
G37*
G36*
G01X1284324D02*
X1288024D01*
G02X1288326Y1713230I0J-302D01*
G01Y1703224D01*
G02X1288024Y1702922I-302J0D01*
G01X1284324D01*
G02X1284022Y1703224I0J302D01*
G01Y1705256D01*
G02X1283931Y1705866I2002J610D01*
G02X1284654Y1707448I2092J0D01*
G01X1284972Y1708097D01*
G03Y1708359I-267J131D01*
G01X1284654Y1709008D01*
G02X1283931Y1710590I1369J1582D01*
G02X1284022Y1711200I2093J0D01*
G01Y1713230D01*
G02X1284324Y1713532I302J0D01*
G37*
G36*
G01X1568182D02*
X1571882D01*
G02X1572184Y1713230I0J-302D01*
G01Y1703224D01*
G02X1571882Y1702922I-302J0D01*
G01X1568182D01*
G02X1567880Y1703224I0J302D01*
G01Y1705629D01*
G02X1567866Y1705866I2002J237D01*
G02X1567880Y1706103I2016J0D01*
G01Y1710353D01*
G02X1567866Y1710590I2002J237D01*
G02X1567880Y1710827I2016J0D01*
G01Y1713230D01*
G02X1568182Y1713532I302J0D01*
G37*
G36*
G01X1583930D02*
X1587630D01*
G02X1587932Y1713230I0J-302D01*
G01Y1703224D01*
G02X1587630Y1702922I-302J0D01*
G01X1583930D01*
G02X1583628Y1703224I0J302D01*
G01Y1705629D01*
G02X1583614Y1705866I2002J237D01*
G02X1583628Y1706103I2016J0D01*
G01Y1710353D01*
G02X1583614Y1710590I2002J237D01*
G02X1583628Y1710827I2016J0D01*
G01Y1713230D01*
G02X1583930Y1713532I302J0D01*
G37*
G36*
G01X1599678D02*
X1603378D01*
G02X1603680Y1713230I0J-302D01*
G01Y1703224D01*
G02X1603378Y1702922I-302J0D01*
G01X1599678D01*
G02X1599376Y1703224I0J302D01*
G01Y1705629D01*
G02X1599362Y1705866I2002J237D01*
G02X1599376Y1706103I2016J0D01*
G01Y1710353D01*
G02X1599362Y1710590I2002J237D01*
G02X1599376Y1710827I2016J0D01*
G01Y1713230D01*
G02X1599678Y1713532I302J0D01*
G37*
G36*
G01X1615426D02*
X1619126D01*
G02X1619428Y1713230I0J-302D01*
G01Y1703224D01*
G02X1619126Y1702922I-302J0D01*
G01X1615426D01*
G02X1615124Y1703224I0J302D01*
G01Y1705629D01*
G02X1615110Y1705866I2002J237D01*
G02X1615124Y1706103I2016J0D01*
G01Y1710353D01*
G02X1615110Y1710590I2002J237D01*
G02X1615124Y1710827I2016J0D01*
G01Y1713230D01*
G02X1615426Y1713532I302J0D01*
G37*
G36*
G01X296135D02*
X299835D01*
G02X300138Y1713230I1J-302D01*
G01Y1703224D01*
G02X299835Y1702922I-303J1D01*
G01X296135D01*
G02X295832Y1703224I-1J302D01*
G01Y1705259D01*
G02X295742Y1705866I2002J607D01*
G02X296465Y1707448I2092J0D01*
G01X296783Y1708097D01*
G03Y1708359I-267J131D01*
G01X296465Y1709008D01*
G02X295742Y1710590I1369J1582D01*
G02X295832Y1711197I2092J0D01*
G01Y1713230D01*
G02X296135Y1713532I303J-1D01*
G37*
G36*
G01X311883D02*
X315583D01*
G02X315886Y1713230I1J-302D01*
G01Y1703224D01*
G02X315583Y1702922I-303J1D01*
G01X311883D01*
G02X311580Y1703224I-1J302D01*
G01Y1705259D01*
G02X311490Y1705866I2002J607D01*
G02X312213Y1707448I2092J0D01*
G01X312531Y1708097D01*
G03Y1708359I-267J131D01*
G01X312213Y1709008D01*
G02X311490Y1710590I1369J1582D01*
G02X311580Y1711197I2092J0D01*
G01Y1713230D01*
G02X311883Y1713532I303J-1D01*
G37*
G36*
G01X327631D02*
X331331D01*
G02X331634Y1713230I1J-302D01*
G01Y1703224D01*
G02X331331Y1702922I-303J1D01*
G01X327631D01*
G02X327328Y1703224I-1J302D01*
G01Y1705259D01*
G02X327238Y1705866I2002J607D01*
G02X327961Y1707448I2092J0D01*
G01X328279Y1708097D01*
G03Y1708359I-267J131D01*
G01X327961Y1709008D01*
G02X327238Y1710590I1369J1582D01*
G02X327328Y1711197I2092J0D01*
G01Y1713230D01*
G02X327631Y1713532I303J-1D01*
G37*
G36*
G01X343379D02*
X347079D01*
G02X347382Y1713230I1J-302D01*
G01Y1703224D01*
G02X347079Y1702922I-303J1D01*
G01X343379D01*
G02X343076Y1703224I-1J302D01*
G01Y1705259D01*
G02X342986Y1705866I2002J607D01*
G02X343709Y1707448I2092J0D01*
G01X344027Y1708097D01*
G03Y1708359I-267J131D01*
G01X343709Y1709008D01*
G02X342986Y1710590I1369J1582D01*
G02X343076Y1711197I2092J0D01*
G01Y1713230D01*
G02X343379Y1713532I303J-1D01*
G37*
G36*
G01X493379D02*
X497079D01*
G02X497382Y1713230I1J-302D01*
G01Y1703224D01*
G02X497079Y1702922I-303J1D01*
G01X493379D01*
G02X493076Y1703224I-1J302D01*
G01Y1705637D01*
G02X493063Y1705866I2003J229D01*
G02X493076Y1706095I2016J0D01*
G01Y1710361D01*
G02X493063Y1710590I2003J229D01*
G02X493076Y1710819I2016J0D01*
G01Y1713230D01*
G02X493379Y1713532I303J-1D01*
G37*
G36*
G01X509127D02*
X512827D01*
G02X513130Y1713230I1J-302D01*
G01Y1703224D01*
G02X512827Y1702922I-303J1D01*
G01X509127D01*
G02X508824Y1703224I-1J302D01*
G01Y1705637D01*
G02X508811Y1705866I2003J229D01*
G02X508824Y1706095I2016J0D01*
G01Y1710361D01*
G02X508811Y1710590I2003J229D01*
G02X508824Y1710819I2016J0D01*
G01Y1713230D01*
G02X509127Y1713532I303J-1D01*
G37*
G36*
G01X524875D02*
X528575D01*
G02X528878Y1713230I1J-302D01*
G01Y1703224D01*
G02X528575Y1702922I-303J1D01*
G01X524875D01*
G02X524572Y1703224I-1J302D01*
G01Y1705637D01*
G02X524559Y1705866I2003J229D01*
G02X524572Y1706095I2016J0D01*
G01Y1710361D01*
G02X524559Y1710590I2003J229D01*
G02X524572Y1710819I2016J0D01*
G01Y1713230D01*
G02X524875Y1713532I303J-1D01*
G37*
G36*
G01X540623D02*
X544323D01*
G02X544626Y1713230I1J-302D01*
G01Y1703224D01*
G02X544323Y1702922I-303J1D01*
G01X540623D01*
G02X540320Y1703224I-1J302D01*
G01Y1705637D01*
G02X540307Y1705866I2003J229D01*
G02X540320Y1706095I2016J0D01*
G01Y1710361D01*
G02X540307Y1710590I2003J229D01*
G02X540320Y1710819I2016J0D01*
G01Y1713230D01*
G02X540623Y1713532I303J-1D01*
G37*
G36*
G01X1304009D02*
X1307709D01*
G02X1308012Y1713230I1J-302D01*
G01Y1703224D01*
G02X1307709Y1702922I-303J1D01*
G01X1304009D01*
G02X1303706Y1703224I-1J302D01*
G01Y1705259D01*
G02X1303616Y1705866I2002J607D01*
G02X1304339Y1707448I2092J0D01*
G01X1304657Y1708097D01*
G03Y1708359I-267J131D01*
G01X1304339Y1709008D01*
G02X1303616Y1710590I1369J1582D01*
G02X1303706Y1711197I2092J0D01*
G01Y1713230D01*
G02X1304009Y1713532I303J-1D01*
G37*
G36*
G01X1319757D02*
X1323457D01*
G02X1323760Y1713230I1J-302D01*
G01Y1703224D01*
G02X1323457Y1702922I-303J1D01*
G01X1319757D01*
G02X1319454Y1703224I-1J302D01*
G01Y1705259D01*
G02X1319364Y1705866I2002J607D01*
G02X1320087Y1707448I2092J0D01*
G01X1320405Y1708097D01*
G03Y1708359I-267J131D01*
G01X1320087Y1709008D01*
G02X1319364Y1710590I1369J1582D01*
G02X1319454Y1711197I2092J0D01*
G01Y1713230D01*
G02X1319757Y1713532I303J-1D01*
G37*
G36*
G01X1335505D02*
X1339205D01*
G02X1339508Y1713230I1J-302D01*
G01Y1703224D01*
G02X1339205Y1702922I-303J1D01*
G01X1335505D01*
G02X1335202Y1703224I-1J302D01*
G01Y1705259D01*
G02X1335112Y1705866I2002J607D01*
G02X1335835Y1707448I2092J0D01*
G01X1336153Y1708097D01*
G03Y1708359I-267J131D01*
G01X1335835Y1709008D01*
G02X1335112Y1710590I1369J1582D01*
G02X1335202Y1711197I2092J0D01*
G01Y1713230D01*
G02X1335505Y1713532I303J-1D01*
G37*
G36*
G01X1351253D02*
X1354953D01*
G02X1355256Y1713230I1J-302D01*
G01Y1703224D01*
G02X1354953Y1702922I-303J1D01*
G01X1351253D01*
G02X1350950Y1703224I-1J302D01*
G01Y1705259D01*
G02X1350860Y1705866I2002J607D01*
G02X1351583Y1707448I2092J0D01*
G01X1351901Y1708097D01*
G03Y1708359I-267J131D01*
G01X1351583Y1709008D01*
G02X1350860Y1710590I1369J1582D01*
G02X1350950Y1711197I2092J0D01*
G01Y1713230D01*
G02X1351253Y1713532I303J-1D01*
G37*
G36*
G01X1501253D02*
X1504953D01*
G02X1505256Y1713230I1J-302D01*
G01Y1703224D01*
G02X1504953Y1702922I-303J1D01*
G01X1501253D01*
G02X1500950Y1703224I-1J302D01*
G01Y1705637D01*
G02X1500937Y1705866I2003J229D01*
G02X1500950Y1706095I2016J0D01*
G01Y1710361D01*
G02X1500937Y1710590I2003J229D01*
G02X1500950Y1710819I2016J0D01*
G01Y1713230D01*
G02X1501253Y1713532I303J-1D01*
G37*
G36*
G01X1517001D02*
X1520701D01*
G02X1521004Y1713230I1J-302D01*
G01Y1703224D01*
G02X1520701Y1702922I-303J1D01*
G01X1517001D01*
G02X1516698Y1703224I-1J302D01*
G01Y1705637D01*
G02X1516685Y1705866I2003J229D01*
G02X1516698Y1706095I2016J0D01*
G01Y1710361D01*
G02X1516685Y1710590I2003J229D01*
G02X1516698Y1710819I2016J0D01*
G01Y1713230D01*
G02X1517001Y1713532I303J-1D01*
G37*
G36*
G01X1532749D02*
X1536449D01*
G02X1536752Y1713230I1J-302D01*
G01Y1703224D01*
G02X1536449Y1702922I-303J1D01*
G01X1532749D01*
G02X1532446Y1703224I-1J302D01*
G01Y1705637D01*
G02X1532433Y1705866I2003J229D01*
G02X1532446Y1706095I2016J0D01*
G01Y1710361D01*
G02X1532433Y1710590I2003J229D01*
G02X1532446Y1710819I2016J0D01*
G01Y1713230D01*
G02X1532749Y1713532I303J-1D01*
G37*
G36*
G01X1548497D02*
X1552197D01*
G02X1552500Y1713230I1J-302D01*
G01Y1703224D01*
G02X1552197Y1702922I-303J1D01*
G01X1548497D01*
G02X1548194Y1703224I-1J302D01*
G01Y1705637D01*
G02X1548181Y1705866I2003J229D01*
G02X1548194Y1706095I2016J0D01*
G01Y1710361D01*
G02X1548181Y1710590I2003J229D01*
G02X1548194Y1710819I2016J0D01*
G01Y1713230D01*
G02X1548497Y1713532I303J-1D01*
G37*
G36*
G01X237080Y1717470D02*
X240780D01*
G02X241082Y1717167I-1J-303D01*
G01Y1707161D01*
G02X240780Y1706858I-302J-1D01*
G01X237080D01*
G02X236778Y1707161I1J303D01*
G01Y1709193D01*
G02X236687Y1709803I2002J610D01*
G02X237410Y1711385I2092J0D01*
G01X237728Y1712034D01*
G03Y1712296I-267J131D01*
G01X237410Y1712945D01*
G02X236687Y1714527I1369J1582D01*
G02X236778Y1715137I2093J0D01*
G01Y1717167D01*
G02X237080Y1717470I302J1D01*
G37*
G36*
G01X252828D02*
X256528D01*
G02X256830Y1717167I-1J-303D01*
G01Y1707161D01*
G02X256528Y1706858I-302J-1D01*
G01X252828D01*
G02X252526Y1707161I1J303D01*
G01Y1709193D01*
G02X252435Y1709803I2002J610D01*
G02X253158Y1711385I2092J0D01*
G01X253476Y1712034D01*
G03Y1712296I-267J131D01*
G01X253158Y1712945D01*
G02X252435Y1714527I1369J1582D01*
G02X252526Y1715137I2093J0D01*
G01Y1717167D01*
G02X252828Y1717470I302J1D01*
G37*
G36*
G01X268576D02*
X272276D01*
G02X272578Y1717167I-1J-303D01*
G01Y1707161D01*
G02X272276Y1706858I-302J-1D01*
G01X268576D01*
G02X268274Y1707161I1J303D01*
G01Y1709193D01*
G02X268183Y1709803I2002J610D01*
G02X268906Y1711385I2092J0D01*
G01X269224Y1712034D01*
G03Y1712296I-267J131D01*
G01X268906Y1712945D01*
G02X268183Y1714527I1369J1582D01*
G02X268274Y1715137I2093J0D01*
G01Y1717167D01*
G02X268576Y1717470I302J1D01*
G37*
G36*
G01X284324D02*
X288024D01*
G02X288326Y1717167I-1J-303D01*
G01Y1707161D01*
G02X288024Y1706858I-302J-1D01*
G01X284324D01*
G02X284022Y1707161I1J303D01*
G01Y1709193D01*
G02X283931Y1709803I2002J610D01*
G02X284654Y1711385I2092J0D01*
G01X284972Y1712034D01*
G03Y1712296I-267J131D01*
G01X284654Y1712945D01*
G02X283931Y1714527I1369J1582D01*
G02X284022Y1715137I2093J0D01*
G01Y1717167D01*
G02X284324Y1717470I302J1D01*
G37*
G36*
G01X304009D02*
X307709D01*
G02X308012Y1717167I0J-303D01*
G01Y1707161D01*
G02X307709Y1706858I-303J0D01*
G01X304009D01*
G02X303706Y1707161I0J303D01*
G01Y1709196D01*
G02X303616Y1709803I2002J607D01*
G02X304339Y1711385I2092J0D01*
G01X304657Y1712034D01*
G03Y1712296I-267J131D01*
G01X304339Y1712945D01*
G02X303616Y1714527I1369J1582D01*
G02X303706Y1715134I2092J0D01*
G01Y1717167D01*
G02X304009Y1717470I303J0D01*
G37*
G36*
G01X319757D02*
X323457D01*
G02X323760Y1717167I0J-303D01*
G01Y1707161D01*
G02X323457Y1706858I-303J0D01*
G01X319757D01*
G02X319454Y1707161I0J303D01*
G01Y1709196D01*
G02X319364Y1709803I2002J607D01*
G02X320087Y1711385I2092J0D01*
G01X320405Y1712034D01*
G03Y1712296I-267J131D01*
G01X320087Y1712945D01*
G02X319364Y1714527I1369J1582D01*
G02X319454Y1715134I2092J0D01*
G01Y1717167D01*
G02X319757Y1717470I303J0D01*
G37*
G36*
G01X335505D02*
X339205D01*
G02X339508Y1717167I0J-303D01*
G01Y1707161D01*
G02X339205Y1706858I-303J0D01*
G01X335505D01*
G02X335202Y1707161I0J303D01*
G01Y1709196D01*
G02X335112Y1709803I2002J607D01*
G02X335835Y1711385I2092J0D01*
G01X336153Y1712034D01*
G03Y1712296I-267J131D01*
G01X335835Y1712945D01*
G02X335112Y1714527I1369J1582D01*
G02X335202Y1715134I2092J0D01*
G01Y1717167D01*
G02X335505Y1717470I303J0D01*
G37*
G36*
G01X351253D02*
X354953D01*
G02X355256Y1717167I0J-303D01*
G01Y1707161D01*
G02X354953Y1706858I-303J0D01*
G01X351253D01*
G02X350950Y1707161I0J303D01*
G01Y1709196D01*
G02X350860Y1709803I2002J607D01*
G02X351583Y1711385I2092J0D01*
G01X351901Y1712034D01*
G03Y1712296I-267J131D01*
G01X351583Y1712945D01*
G02X350860Y1714527I1369J1582D01*
G02X350950Y1715134I2092J0D01*
G01Y1717167D01*
G02X351253Y1717470I303J0D01*
G37*
G36*
G01X501253D02*
X504953D01*
G02X505256Y1717167I0J-303D01*
G01Y1707161D01*
G02X504953Y1706858I-303J0D01*
G01X501253D01*
G02X500950Y1707161I0J303D01*
G01Y1709574D01*
G02X500937Y1709803I2003J229D01*
G02X500950Y1710032I2016J0D01*
G01Y1714298D01*
G02X500937Y1714527I2003J229D01*
G02X500950Y1714756I2016J0D01*
G01Y1717167D01*
G02X501253Y1717470I303J0D01*
G37*
G36*
G01X517001D02*
X520701D01*
G02X521004Y1717167I0J-303D01*
G01Y1707161D01*
G02X520701Y1706858I-303J0D01*
G01X517001D01*
G02X516698Y1707161I0J303D01*
G01Y1709574D01*
G02X516685Y1709803I2003J229D01*
G02X516698Y1710032I2016J0D01*
G01Y1714298D01*
G02X516685Y1714527I2003J229D01*
G02X516698Y1714756I2016J0D01*
G01Y1717167D01*
G02X517001Y1717470I303J0D01*
G37*
G36*
G01X532749D02*
X536449D01*
G02X536752Y1717167I0J-303D01*
G01Y1707161D01*
G02X536449Y1706858I-303J0D01*
G01X532749D01*
G02X532446Y1707161I0J303D01*
G01Y1709574D01*
G02X532433Y1709803I2003J229D01*
G02X532446Y1710032I2016J0D01*
G01Y1714298D01*
G02X532433Y1714527I2003J229D01*
G02X532446Y1714756I2016J0D01*
G01Y1717167D01*
G02X532749Y1717470I303J0D01*
G37*
G36*
G01X548497D02*
X552197D01*
G02X552500Y1717167I0J-303D01*
G01Y1707161D01*
G02X552197Y1706858I-303J0D01*
G01X548497D01*
G02X548194Y1707161I0J303D01*
G01Y1709574D01*
G02X548181Y1709803I2003J229D01*
G02X548194Y1710032I2016J0D01*
G01Y1714298D01*
G02X548181Y1714527I2003J229D01*
G02X548194Y1714756I2016J0D01*
G01Y1717167D01*
G02X548497Y1717470I303J0D01*
G37*
G36*
G01X568182D02*
X571882D01*
G02X572184Y1717167I-1J-303D01*
G01Y1707161D01*
G02X571882Y1706858I-302J-1D01*
G01X568182D01*
G02X567880Y1707161I1J303D01*
G01Y1709566D01*
G02X567866Y1709803I2002J237D01*
G02X567880Y1710040I2016J0D01*
G01Y1714290D01*
G02X567866Y1714527I2002J237D01*
G02X567880Y1714764I2016J0D01*
G01Y1717167D01*
G02X568182Y1717470I302J1D01*
G37*
G36*
G01X583930D02*
X587630D01*
G02X587932Y1717167I-1J-303D01*
G01Y1707161D01*
G02X587630Y1706858I-302J-1D01*
G01X583930D01*
G02X583628Y1707161I1J303D01*
G01Y1709566D01*
G02X583614Y1709803I2002J237D01*
G02X583628Y1710040I2016J0D01*
G01Y1714290D01*
G02X583614Y1714527I2002J237D01*
G02X583628Y1714764I2016J0D01*
G01Y1717167D01*
G02X583930Y1717470I302J1D01*
G37*
G36*
G01X599678D02*
X603378D01*
G02X603680Y1717167I-1J-303D01*
G01Y1707161D01*
G02X603378Y1706858I-302J-1D01*
G01X599678D01*
G02X599376Y1707161I1J303D01*
G01Y1709566D01*
G02X599362Y1709803I2002J237D01*
G02X599376Y1710040I2016J0D01*
G01Y1714290D01*
G02X599362Y1714527I2002J237D01*
G02X599376Y1714764I2016J0D01*
G01Y1717167D01*
G02X599678Y1717470I302J1D01*
G37*
G36*
G01X615426D02*
X619126D01*
G02X619428Y1717167I-1J-303D01*
G01Y1707161D01*
G02X619126Y1706858I-302J-1D01*
G01X615426D01*
G02X615124Y1707161I1J303D01*
G01Y1709566D01*
G02X615110Y1709803I2002J237D01*
G02X615124Y1710040I2016J0D01*
G01Y1714290D01*
G02X615110Y1714527I2002J237D01*
G02X615124Y1714764I2016J0D01*
G01Y1717167D01*
G02X615426Y1717470I302J1D01*
G37*
G36*
G01X1244954D02*
X1248654D01*
G02X1248956Y1717167I-1J-303D01*
G01Y1707161D01*
G02X1248654Y1706858I-302J-1D01*
G01X1244954D01*
G02X1244652Y1707161I1J303D01*
G01Y1709193D01*
G02X1244561Y1709803I2002J610D01*
G02X1245284Y1711385I2092J0D01*
G01X1245602Y1712034D01*
G03Y1712296I-267J131D01*
G01X1245284Y1712945D01*
G02X1244561Y1714527I1369J1582D01*
G02X1244652Y1715137I2093J0D01*
G01Y1717167D01*
G02X1244954Y1717470I302J1D01*
G37*
G36*
G01X1260702D02*
X1264402D01*
G02X1264704Y1717167I-1J-303D01*
G01Y1707161D01*
G02X1264402Y1706858I-302J-1D01*
G01X1260702D01*
G02X1260400Y1707161I1J303D01*
G01Y1709193D01*
G02X1260309Y1709803I2002J610D01*
G02X1261032Y1711385I2092J0D01*
G01X1261350Y1712034D01*
G03Y1712296I-267J131D01*
G01X1261032Y1712945D01*
G02X1260309Y1714527I1369J1582D01*
G02X1260400Y1715137I2093J0D01*
G01Y1717167D01*
G02X1260702Y1717470I302J1D01*
G37*
G36*
G01X1276450D02*
X1280150D01*
G02X1280452Y1717167I-1J-303D01*
G01Y1707161D01*
G02X1280150Y1706858I-302J-1D01*
G01X1276450D01*
G02X1276148Y1707161I1J303D01*
G01Y1709193D01*
G02X1276057Y1709803I2002J610D01*
G02X1276780Y1711385I2092J0D01*
G01X1277098Y1712034D01*
G03Y1712296I-267J131D01*
G01X1276780Y1712945D01*
G02X1276057Y1714527I1369J1582D01*
G02X1276148Y1715137I2093J0D01*
G01Y1717167D01*
G02X1276450Y1717470I302J1D01*
G37*
G36*
G01X1292198D02*
X1295898D01*
G02X1296200Y1717167I-1J-303D01*
G01Y1707161D01*
G02X1295898Y1706858I-302J-1D01*
G01X1292198D01*
G02X1291896Y1707161I1J303D01*
G01Y1709193D01*
G02X1291805Y1709803I2002J610D01*
G02X1292528Y1711385I2092J0D01*
G01X1292846Y1712034D01*
G03Y1712296I-267J131D01*
G01X1292528Y1712945D01*
G02X1291805Y1714527I1369J1582D01*
G02X1291896Y1715137I2093J0D01*
G01Y1717167D01*
G02X1292198Y1717470I302J1D01*
G37*
G36*
G01X1311883D02*
X1315583D01*
G02X1315886Y1717167I0J-303D01*
G01Y1707161D01*
G02X1315583Y1706858I-303J0D01*
G01X1311883D01*
G02X1311580Y1707161I0J303D01*
G01Y1709196D01*
G02X1311490Y1709803I2002J607D01*
G02X1312213Y1711385I2092J0D01*
G01X1312531Y1712034D01*
G03Y1712296I-267J131D01*
G01X1312213Y1712945D01*
G02X1311490Y1714527I1369J1582D01*
G02X1311580Y1715134I2092J0D01*
G01Y1717167D01*
G02X1311883Y1717470I303J0D01*
G37*
G36*
G01X1327631D02*
X1331331D01*
G02X1331634Y1717167I0J-303D01*
G01Y1707161D01*
G02X1331331Y1706858I-303J0D01*
G01X1327631D01*
G02X1327328Y1707161I0J303D01*
G01Y1709196D01*
G02X1327238Y1709803I2002J607D01*
G02X1327961Y1711385I2092J0D01*
G01X1328279Y1712034D01*
G03Y1712296I-267J131D01*
G01X1327961Y1712945D01*
G02X1327238Y1714527I1369J1582D01*
G02X1327328Y1715134I2092J0D01*
G01Y1717167D01*
G02X1327631Y1717470I303J0D01*
G37*
G36*
G01X1343379D02*
X1347079D01*
G02X1347382Y1717167I0J-303D01*
G01Y1707161D01*
G02X1347079Y1706858I-303J0D01*
G01X1343379D01*
G02X1343076Y1707161I0J303D01*
G01Y1709196D01*
G02X1342986Y1709803I2002J607D01*
G02X1343709Y1711385I2092J0D01*
G01X1344027Y1712034D01*
G03Y1712296I-267J131D01*
G01X1343709Y1712945D01*
G02X1342986Y1714527I1369J1582D01*
G02X1343076Y1715134I2092J0D01*
G01Y1717167D01*
G02X1343379Y1717470I303J0D01*
G37*
G36*
G01X1359127D02*
X1362827D01*
G02X1363130Y1717167I0J-303D01*
G01Y1707161D01*
G02X1362827Y1706858I-303J0D01*
G01X1359127D01*
G02X1358824Y1707161I0J303D01*
G01Y1709196D01*
G02X1358734Y1709803I2002J607D01*
G02X1359457Y1711385I2092J0D01*
G01X1359775Y1712034D01*
G03Y1712296I-267J131D01*
G01X1359457Y1712945D01*
G02X1358734Y1714527I1369J1582D01*
G02X1358824Y1715134I2092J0D01*
G01Y1717167D01*
G02X1359127Y1717470I303J0D01*
G37*
G36*
G01X1509127D02*
X1512827D01*
G02X1513130Y1717167I0J-303D01*
G01Y1707161D01*
G02X1512827Y1706858I-303J0D01*
G01X1509127D01*
G02X1508824Y1707161I0J303D01*
G01Y1709574D01*
G02X1508811Y1709803I2003J229D01*
G02X1508824Y1710032I2016J0D01*
G01Y1714298D01*
G02X1508811Y1714527I2003J229D01*
G02X1508824Y1714756I2016J0D01*
G01Y1717167D01*
G02X1509127Y1717470I303J0D01*
G37*
G36*
G01X1524875D02*
X1528575D01*
G02X1528878Y1717167I0J-303D01*
G01Y1707161D01*
G02X1528575Y1706858I-303J0D01*
G01X1524875D01*
G02X1524572Y1707161I0J303D01*
G01Y1709574D01*
G02X1524559Y1709803I2003J229D01*
G02X1524572Y1710032I2016J0D01*
G01Y1714298D01*
G02X1524559Y1714527I2003J229D01*
G02X1524572Y1714756I2016J0D01*
G01Y1717167D01*
G02X1524875Y1717470I303J0D01*
G37*
G36*
G01X1540623D02*
X1544323D01*
G02X1544626Y1717167I0J-303D01*
G01Y1707161D01*
G02X1544323Y1706858I-303J0D01*
G01X1540623D01*
G02X1540320Y1707161I0J303D01*
G01Y1709574D01*
G02X1540307Y1709803I2003J229D01*
G02X1540320Y1710032I2016J0D01*
G01Y1714298D01*
G02X1540307Y1714527I2003J229D01*
G02X1540320Y1714756I2016J0D01*
G01Y1717167D01*
G02X1540623Y1717470I303J0D01*
G37*
G36*
G01X1556371D02*
X1560071D01*
G02X1560374Y1717167I0J-303D01*
G01Y1707161D01*
G02X1560071Y1706858I-303J0D01*
G01X1556371D01*
G02X1556068Y1707161I0J303D01*
G01Y1709574D01*
G02X1556055Y1709803I2003J229D01*
G02X1556068Y1710032I2016J0D01*
G01Y1714298D01*
G02X1556055Y1714527I2003J229D01*
G02X1556068Y1714756I2016J0D01*
G01Y1717167D01*
G02X1556371Y1717470I303J0D01*
G37*
G36*
G01X1576056D02*
X1579756D01*
G02X1580058Y1717167I-1J-303D01*
G01Y1707161D01*
G02X1579756Y1706858I-302J-1D01*
G01X1576056D01*
G02X1575754Y1707161I1J303D01*
G01Y1709566D01*
G02X1575740Y1709803I2002J237D01*
G02X1575754Y1710040I2016J0D01*
G01Y1714290D01*
G02X1575740Y1714527I2002J237D01*
G02X1575754Y1714764I2016J0D01*
G01Y1717167D01*
G02X1576056Y1717470I302J1D01*
G37*
G36*
G01X1591804D02*
X1595504D01*
G02X1595806Y1717167I-1J-303D01*
G01Y1707161D01*
G02X1595504Y1706858I-302J-1D01*
G01X1591804D01*
G02X1591502Y1707161I1J303D01*
G01Y1709566D01*
G02X1591488Y1709803I2002J237D01*
G02X1591502Y1710040I2016J0D01*
G01Y1714290D01*
G02X1591488Y1714527I2002J237D01*
G02X1591502Y1714764I2016J0D01*
G01Y1717167D01*
G02X1591804Y1717470I302J1D01*
G37*
G36*
G01X1607552D02*
X1611252D01*
G02X1611554Y1717167I-1J-303D01*
G01Y1707161D01*
G02X1611252Y1706858I-302J-1D01*
G01X1607552D01*
G02X1607250Y1707161I1J303D01*
G01Y1709566D01*
G02X1607236Y1709803I2002J237D01*
G02X1607250Y1710040I2016J0D01*
G01Y1714290D01*
G02X1607236Y1714527I2002J237D01*
G02X1607250Y1714764I2016J0D01*
G01Y1717167D01*
G02X1607552Y1717470I302J1D01*
G37*
G36*
G01X1623300D02*
X1627000D01*
G02X1627302Y1717167I-1J-303D01*
G01Y1707161D01*
G02X1627000Y1706858I-302J-1D01*
G01X1623300D01*
G02X1622998Y1707161I1J303D01*
G01Y1709566D01*
G02X1622984Y1709803I2002J237D01*
G02X1622998Y1710040I2016J0D01*
G01Y1714290D01*
G02X1622984Y1714527I2002J237D01*
G02X1622998Y1714764I2016J0D01*
G01Y1717167D01*
G02X1623300Y1717470I302J1D01*
G37*
G36*
G01X229206Y1727706D02*
X232906D01*
G02X233208Y1727404I0J-302D01*
G01Y1717398D01*
G02X232906Y1717096I-302J0D01*
G01X229206D01*
G02X228904Y1717398I0J302D01*
G01Y1719802D01*
G02X228890Y1720039I2002J237D01*
G02X228904Y1720276I2016J0D01*
G01Y1724526D01*
G02X228890Y1724763I2002J237D01*
G02X228904Y1725000I2016J0D01*
G01Y1727404D01*
G02X229206Y1727706I302J0D01*
G37*
G36*
G01X244954D02*
X248654D01*
G02X248956Y1727404I0J-302D01*
G01Y1717398D01*
G02X248654Y1717096I-302J0D01*
G01X244954D01*
G02X244652Y1717398I0J302D01*
G01Y1719802D01*
G02X244638Y1720039I2002J237D01*
G02X244652Y1720276I2016J0D01*
G01Y1724526D01*
G02X244638Y1724763I2002J237D01*
G02X244652Y1725000I2016J0D01*
G01Y1727404D01*
G02X244954Y1727706I302J0D01*
G37*
G36*
G01X260702D02*
X264402D01*
G02X264704Y1727404I0J-302D01*
G01Y1717398D01*
G02X264402Y1717096I-302J0D01*
G01X260702D01*
G02X260400Y1717398I0J302D01*
G01Y1719802D01*
G02X260386Y1720039I2002J237D01*
G02X260400Y1720276I2016J0D01*
G01Y1724526D01*
G02X260386Y1724763I2002J237D01*
G02X260400Y1725000I2016J0D01*
G01Y1727404D01*
G02X260702Y1727706I302J0D01*
G37*
G36*
G01X276450D02*
X280150D01*
G02X280452Y1727404I0J-302D01*
G01Y1717398D01*
G02X280150Y1717096I-302J0D01*
G01X276450D01*
G02X276148Y1717398I0J302D01*
G01Y1719802D01*
G02X276134Y1720039I2002J237D01*
G02X276148Y1720276I2016J0D01*
G01Y1724526D01*
G02X276134Y1724763I2002J237D01*
G02X276148Y1725000I2016J0D01*
G01Y1727404D01*
G02X276450Y1727706I302J0D01*
G37*
G36*
G01X560308D02*
X564008D01*
G02X564310Y1727404I0J-302D01*
G01Y1717398D01*
G02X564008Y1717096I-302J0D01*
G01X560308D01*
G02X560006Y1717398I0J302D01*
G01Y1719429D01*
G02X559915Y1720039I2002J610D01*
G02X560637Y1721621I2094J0D01*
G01X560956Y1722271D01*
G03Y1722533I-267J131D01*
G01X560639Y1723180D01*
G02X559915Y1724763I1369J1583D01*
G02X560006Y1725373I2093J0D01*
G01Y1727404D01*
G02X560308Y1727706I302J0D01*
G37*
G36*
G01X576056D02*
X579756D01*
G02X580058Y1727404I0J-302D01*
G01Y1717398D01*
G02X579756Y1717096I-302J0D01*
G01X576056D01*
G02X575754Y1717398I0J302D01*
G01Y1719429D01*
G02X575663Y1720039I2002J610D01*
G02X576385Y1721621I2094J0D01*
G01X576704Y1722271D01*
G03Y1722533I-267J131D01*
G01X576387Y1723180D01*
G02X575663Y1724763I1369J1583D01*
G02X575754Y1725373I2093J0D01*
G01Y1727404D01*
G02X576056Y1727706I302J0D01*
G37*
G36*
G01X591804D02*
X595504D01*
G02X595806Y1727404I0J-302D01*
G01Y1717398D01*
G02X595504Y1717096I-302J0D01*
G01X591804D01*
G02X591502Y1717398I0J302D01*
G01Y1719429D01*
G02X591411Y1720039I2002J610D01*
G02X592133Y1721621I2094J0D01*
G01X592452Y1722271D01*
G03Y1722533I-267J131D01*
G01X592135Y1723180D01*
G02X591411Y1724763I1369J1583D01*
G02X591502Y1725373I2093J0D01*
G01Y1727404D01*
G02X591804Y1727706I302J0D01*
G37*
G36*
G01X607552D02*
X611252D01*
G02X611554Y1727404I0J-302D01*
G01Y1717398D01*
G02X611252Y1717096I-302J0D01*
G01X607552D01*
G02X607250Y1717398I0J302D01*
G01Y1719429D01*
G02X607159Y1720039I2002J610D01*
G02X607881Y1721621I2094J0D01*
G01X608200Y1722271D01*
G03Y1722533I-267J131D01*
G01X607883Y1723180D01*
G02X607159Y1724763I1369J1583D01*
G02X607250Y1725373I2093J0D01*
G01Y1727404D01*
G02X607552Y1727706I302J0D01*
G37*
G36*
G01X1237080D02*
X1240780D01*
G02X1241082Y1727404I0J-302D01*
G01Y1717398D01*
G02X1240780Y1717096I-302J0D01*
G01X1237080D01*
G02X1236778Y1717398I0J302D01*
G01Y1719802D01*
G02X1236764Y1720039I2002J237D01*
G02X1236778Y1720276I2016J0D01*
G01Y1724526D01*
G02X1236764Y1724763I2002J237D01*
G02X1236778Y1725000I2016J0D01*
G01Y1727404D01*
G02X1237080Y1727706I302J0D01*
G37*
G36*
G01X1252828D02*
X1256528D01*
G02X1256830Y1727404I0J-302D01*
G01Y1717398D01*
G02X1256528Y1717096I-302J0D01*
G01X1252828D01*
G02X1252526Y1717398I0J302D01*
G01Y1719802D01*
G02X1252512Y1720039I2002J237D01*
G02X1252526Y1720276I2016J0D01*
G01Y1724526D01*
G02X1252512Y1724763I2002J237D01*
G02X1252526Y1725000I2016J0D01*
G01Y1727404D01*
G02X1252828Y1727706I302J0D01*
G37*
G36*
G01X1268576D02*
X1272276D01*
G02X1272578Y1727404I0J-302D01*
G01Y1717398D01*
G02X1272276Y1717096I-302J0D01*
G01X1268576D01*
G02X1268274Y1717398I0J302D01*
G01Y1719802D01*
G02X1268260Y1720039I2002J237D01*
G02X1268274Y1720276I2016J0D01*
G01Y1724526D01*
G02X1268260Y1724763I2002J237D01*
G02X1268274Y1725000I2016J0D01*
G01Y1727404D01*
G02X1268576Y1727706I302J0D01*
G37*
G36*
G01X1284324D02*
X1288024D01*
G02X1288326Y1727404I0J-302D01*
G01Y1717398D01*
G02X1288024Y1717096I-302J0D01*
G01X1284324D01*
G02X1284022Y1717398I0J302D01*
G01Y1719802D01*
G02X1284008Y1720039I2002J237D01*
G02X1284022Y1720276I2016J0D01*
G01Y1724526D01*
G02X1284008Y1724763I2002J237D01*
G02X1284022Y1725000I2016J0D01*
G01Y1727404D01*
G02X1284324Y1727706I302J0D01*
G37*
G36*
G01X1568182D02*
X1571882D01*
G02X1572184Y1727404I0J-302D01*
G01Y1717398D01*
G02X1571882Y1717096I-302J0D01*
G01X1568182D01*
G02X1567880Y1717398I0J302D01*
G01Y1719429D01*
G02X1567789Y1720039I2002J610D01*
G02X1568511Y1721621I2094J0D01*
G01X1568830Y1722271D01*
G03Y1722533I-267J131D01*
G01X1568513Y1723180D01*
G02X1567789Y1724763I1369J1583D01*
G02X1567880Y1725373I2093J0D01*
G01Y1727404D01*
G02X1568182Y1727706I302J0D01*
G37*
G36*
G01X1583930D02*
X1587630D01*
G02X1587932Y1727404I0J-302D01*
G01Y1717398D01*
G02X1587630Y1717096I-302J0D01*
G01X1583930D01*
G02X1583628Y1717398I0J302D01*
G01Y1719429D01*
G02X1583537Y1720039I2002J610D01*
G02X1584259Y1721621I2094J0D01*
G01X1584578Y1722271D01*
G03Y1722533I-267J131D01*
G01X1584261Y1723180D01*
G02X1583537Y1724763I1369J1583D01*
G02X1583628Y1725373I2093J0D01*
G01Y1727404D01*
G02X1583930Y1727706I302J0D01*
G37*
G36*
G01X1599678D02*
X1603378D01*
G02X1603680Y1727404I0J-302D01*
G01Y1717398D01*
G02X1603378Y1717096I-302J0D01*
G01X1599678D01*
G02X1599376Y1717398I0J302D01*
G01Y1719429D01*
G02X1599285Y1720039I2002J610D01*
G02X1600007Y1721621I2094J0D01*
G01X1600326Y1722271D01*
G03Y1722533I-267J131D01*
G01X1600009Y1723180D01*
G02X1599285Y1724763I1369J1583D01*
G02X1599376Y1725373I2093J0D01*
G01Y1727404D01*
G02X1599678Y1727706I302J0D01*
G37*
G36*
G01X1615426D02*
X1619126D01*
G02X1619428Y1727404I0J-302D01*
G01Y1717398D01*
G02X1619126Y1717096I-302J0D01*
G01X1615426D01*
G02X1615124Y1717398I0J302D01*
G01Y1719429D01*
G02X1615033Y1720039I2002J610D01*
G02X1615755Y1721621I2094J0D01*
G01X1616074Y1722271D01*
G03Y1722533I-267J131D01*
G01X1615757Y1723180D01*
G02X1615033Y1724763I1369J1583D01*
G02X1615124Y1725373I2093J0D01*
G01Y1727404D01*
G02X1615426Y1727706I302J0D01*
G37*
G36*
G01X296135D02*
X299835D01*
G02X300138Y1727404I1J-302D01*
G01Y1717398D01*
G02X299835Y1717096I-303J1D01*
G01X296135D01*
G02X295832Y1717398I-1J302D01*
G01Y1719810D01*
G02X295819Y1720039I2003J229D01*
G02X295832Y1720268I2016J0D01*
G01Y1724534D01*
G02X295819Y1724763I2003J229D01*
G02X295832Y1724992I2016J0D01*
G01Y1727404D01*
G02X296135Y1727706I303J-1D01*
G37*
G36*
G01X311883D02*
X315583D01*
G02X315886Y1727404I1J-302D01*
G01Y1717398D01*
G02X315583Y1717096I-303J1D01*
G01X311883D01*
G02X311580Y1717398I-1J302D01*
G01Y1719810D01*
G02X311567Y1720039I2003J229D01*
G02X311580Y1720268I2016J0D01*
G01Y1724534D01*
G02X311567Y1724763I2003J229D01*
G02X311580Y1724992I2016J0D01*
G01Y1727404D01*
G02X311883Y1727706I303J-1D01*
G37*
G36*
G01X327631D02*
X331331D01*
G02X331634Y1727404I1J-302D01*
G01Y1717398D01*
G02X331331Y1717096I-303J1D01*
G01X327631D01*
G02X327328Y1717398I-1J302D01*
G01Y1719810D01*
G02X327315Y1720039I2003J229D01*
G02X327328Y1720268I2016J0D01*
G01Y1724534D01*
G02X327315Y1724763I2003J229D01*
G02X327328Y1724992I2016J0D01*
G01Y1727404D01*
G02X327631Y1727706I303J-1D01*
G37*
G36*
G01X343379D02*
X347079D01*
G02X347382Y1727404I1J-302D01*
G01Y1717398D01*
G02X347079Y1717096I-303J1D01*
G01X343379D01*
G02X343076Y1717398I-1J302D01*
G01Y1719810D01*
G02X343063Y1720039I2003J229D01*
G02X343076Y1720268I2016J0D01*
G01Y1724534D01*
G02X343063Y1724763I2003J229D01*
G02X343076Y1724992I2016J0D01*
G01Y1727404D01*
G02X343379Y1727706I303J-1D01*
G37*
G36*
G01X493379D02*
X497079D01*
G02X497382Y1727404I1J-302D01*
G01Y1717398D01*
G02X497079Y1717096I-303J1D01*
G01X493379D01*
G02X493076Y1717398I-1J302D01*
G01Y1719432D01*
G02X492986Y1720039I2002J607D01*
G02X493708Y1721621I2094J0D01*
G01X494027Y1722271D01*
G03Y1722533I-267J131D01*
G01X493710Y1723180D01*
G02X492986Y1724763I1369J1583D01*
G02X493076Y1725370I2092J0D01*
G01Y1727404D01*
G02X493379Y1727706I303J-1D01*
G37*
G36*
G01X509127D02*
X512827D01*
G02X513130Y1727404I1J-302D01*
G01Y1717398D01*
G02X512827Y1717096I-303J1D01*
G01X509127D01*
G02X508824Y1717398I-1J302D01*
G01Y1719432D01*
G02X508734Y1720039I2002J607D01*
G02X509456Y1721621I2094J0D01*
G01X509775Y1722271D01*
G03Y1722533I-267J131D01*
G01X509458Y1723180D01*
G02X508734Y1724763I1369J1583D01*
G02X508824Y1725370I2092J0D01*
G01Y1727404D01*
G02X509127Y1727706I303J-1D01*
G37*
G36*
G01X524875D02*
X528575D01*
G02X528878Y1727404I1J-302D01*
G01Y1717398D01*
G02X528575Y1717096I-303J1D01*
G01X524875D01*
G02X524572Y1717398I-1J302D01*
G01Y1719432D01*
G02X524482Y1720039I2002J607D01*
G02X525204Y1721621I2094J0D01*
G01X525523Y1722271D01*
G03Y1722533I-267J131D01*
G01X525206Y1723180D01*
G02X524482Y1724763I1369J1583D01*
G02X524572Y1725370I2092J0D01*
G01Y1727404D01*
G02X524875Y1727706I303J-1D01*
G37*
G36*
G01X540623D02*
X544323D01*
G02X544626Y1727404I1J-302D01*
G01Y1717398D01*
G02X544323Y1717096I-303J1D01*
G01X540623D01*
G02X540320Y1717398I-1J302D01*
G01Y1719432D01*
G02X540230Y1720039I2002J607D01*
G02X540952Y1721621I2094J0D01*
G01X541271Y1722271D01*
G03Y1722533I-267J131D01*
G01X540954Y1723180D01*
G02X540230Y1724763I1369J1583D01*
G02X540320Y1725370I2092J0D01*
G01Y1727404D01*
G02X540623Y1727706I303J-1D01*
G37*
G36*
G01X1304009D02*
X1307709D01*
G02X1308012Y1727404I1J-302D01*
G01Y1717398D01*
G02X1307709Y1717096I-303J1D01*
G01X1304009D01*
G02X1303706Y1717398I-1J302D01*
G01Y1719810D01*
G02X1303693Y1720039I2003J229D01*
G02X1303706Y1720268I2016J0D01*
G01Y1724534D01*
G02X1303693Y1724763I2003J229D01*
G02X1303706Y1724992I2016J0D01*
G01Y1727404D01*
G02X1304009Y1727706I303J-1D01*
G37*
G36*
G01X1319757D02*
X1323457D01*
G02X1323760Y1727404I1J-302D01*
G01Y1717398D01*
G02X1323457Y1717096I-303J1D01*
G01X1319757D01*
G02X1319454Y1717398I-1J302D01*
G01Y1719810D01*
G02X1319441Y1720039I2003J229D01*
G02X1319454Y1720268I2016J0D01*
G01Y1724534D01*
G02X1319441Y1724763I2003J229D01*
G02X1319454Y1724992I2016J0D01*
G01Y1727404D01*
G02X1319757Y1727706I303J-1D01*
G37*
G36*
G01X1335505D02*
X1339205D01*
G02X1339508Y1727404I1J-302D01*
G01Y1717398D01*
G02X1339205Y1717096I-303J1D01*
G01X1335505D01*
G02X1335202Y1717398I-1J302D01*
G01Y1719810D01*
G02X1335189Y1720039I2003J229D01*
G02X1335202Y1720268I2016J0D01*
G01Y1724534D01*
G02X1335189Y1724763I2003J229D01*
G02X1335202Y1724992I2016J0D01*
G01Y1727404D01*
G02X1335505Y1727706I303J-1D01*
G37*
G36*
G01X1351253D02*
X1354953D01*
G02X1355256Y1727404I1J-302D01*
G01Y1717398D01*
G02X1354953Y1717096I-303J1D01*
G01X1351253D01*
G02X1350950Y1717398I-1J302D01*
G01Y1719810D01*
G02X1350937Y1720039I2003J229D01*
G02X1350950Y1720268I2016J0D01*
G01Y1724534D01*
G02X1350937Y1724763I2003J229D01*
G02X1350950Y1724992I2016J0D01*
G01Y1727404D01*
G02X1351253Y1727706I303J-1D01*
G37*
G36*
G01X1501253D02*
X1504953D01*
G02X1505256Y1727404I1J-302D01*
G01Y1717398D01*
G02X1504953Y1717096I-303J1D01*
G01X1501253D01*
G02X1500950Y1717398I-1J302D01*
G01Y1719432D01*
G02X1500860Y1720039I2002J607D01*
G02X1501582Y1721621I2094J0D01*
G01X1501901Y1722271D01*
G03Y1722533I-267J131D01*
G01X1501584Y1723180D01*
G02X1500860Y1724763I1369J1583D01*
G02X1500950Y1725370I2092J0D01*
G01Y1727404D01*
G02X1501253Y1727706I303J-1D01*
G37*
G36*
G01X1517001D02*
X1520701D01*
G02X1521004Y1727404I1J-302D01*
G01Y1717398D01*
G02X1520701Y1717096I-303J1D01*
G01X1517001D01*
G02X1516698Y1717398I-1J302D01*
G01Y1719432D01*
G02X1516608Y1720039I2002J607D01*
G02X1517330Y1721621I2094J0D01*
G01X1517649Y1722271D01*
G03Y1722533I-267J131D01*
G01X1517332Y1723180D01*
G02X1516608Y1724763I1369J1583D01*
G02X1516698Y1725370I2092J0D01*
G01Y1727404D01*
G02X1517001Y1727706I303J-1D01*
G37*
G36*
G01X1532749D02*
X1536449D01*
G02X1536752Y1727404I1J-302D01*
G01Y1717398D01*
G02X1536449Y1717096I-303J1D01*
G01X1532749D01*
G02X1532446Y1717398I-1J302D01*
G01Y1719432D01*
G02X1532356Y1720039I2002J607D01*
G02X1533078Y1721621I2094J0D01*
G01X1533397Y1722271D01*
G03Y1722533I-267J131D01*
G01X1533080Y1723180D01*
G02X1532356Y1724763I1369J1583D01*
G02X1532446Y1725370I2092J0D01*
G01Y1727404D01*
G02X1532749Y1727706I303J-1D01*
G37*
G36*
G01X1548497D02*
X1552197D01*
G02X1552500Y1727404I1J-302D01*
G01Y1717398D01*
G02X1552197Y1717096I-303J1D01*
G01X1548497D01*
G02X1548194Y1717398I-1J302D01*
G01Y1719432D01*
G02X1548104Y1720039I2002J607D01*
G02X1548826Y1721621I2094J0D01*
G01X1549145Y1722271D01*
G03Y1722533I-267J131D01*
G01X1548828Y1723180D01*
G02X1548104Y1724763I1369J1583D01*
G02X1548194Y1725370I2092J0D01*
G01Y1727404D01*
G02X1548497Y1727706I303J-1D01*
G37*
G36*
G01X237080Y1731644D02*
X240780D01*
G02X241082Y1731341I-1J-303D01*
G01Y1721335D01*
G02X240780Y1721032I-302J-1D01*
G01X237080D01*
G02X236778Y1721335I1J303D01*
G01Y1723739D01*
G02X236764Y1723976I2002J237D01*
G02X236778Y1724213I2016J0D01*
G01Y1728463D01*
G02X236764Y1728700I2002J237D01*
G02X236778Y1728937I2016J0D01*
G01Y1731341D01*
G02X237080Y1731644I302J1D01*
G37*
G36*
G01X252828D02*
X256528D01*
G02X256830Y1731341I-1J-303D01*
G01Y1721335D01*
G02X256528Y1721032I-302J-1D01*
G01X252828D01*
G02X252526Y1721335I1J303D01*
G01Y1723739D01*
G02X252512Y1723976I2002J237D01*
G02X252526Y1724213I2016J0D01*
G01Y1728463D01*
G02X252512Y1728700I2002J237D01*
G02X252526Y1728937I2016J0D01*
G01Y1731341D01*
G02X252828Y1731644I302J1D01*
G37*
G36*
G01X268576D02*
X272276D01*
G02X272578Y1731341I-1J-303D01*
G01Y1721335D01*
G02X272276Y1721032I-302J-1D01*
G01X268576D01*
G02X268274Y1721335I1J303D01*
G01Y1723739D01*
G02X268260Y1723976I2002J237D01*
G02X268274Y1724213I2016J0D01*
G01Y1728463D01*
G02X268260Y1728700I2002J237D01*
G02X268274Y1728937I2016J0D01*
G01Y1731341D01*
G02X268576Y1731644I302J1D01*
G37*
G36*
G01X284324D02*
X288024D01*
G02X288326Y1731341I-1J-303D01*
G01Y1721335D01*
G02X288024Y1721032I-302J-1D01*
G01X284324D01*
G02X284022Y1721335I1J303D01*
G01Y1723739D01*
G02X284008Y1723976I2002J237D01*
G02X284022Y1724213I2016J0D01*
G01Y1728463D01*
G02X284008Y1728700I2002J237D01*
G02X284022Y1728937I2016J0D01*
G01Y1731341D01*
G02X284324Y1731644I302J1D01*
G37*
G36*
G01X304009D02*
X307709D01*
G02X308012Y1731341I0J-303D01*
G01Y1721335D01*
G02X307709Y1721032I-303J0D01*
G01X304009D01*
G02X303706Y1721335I0J303D01*
G01Y1723747D01*
G02X303693Y1723976I2003J229D01*
G02X303706Y1724205I2016J0D01*
G01Y1728471D01*
G02X303693Y1728700I2003J229D01*
G02X303706Y1728929I2016J0D01*
G01Y1731341D01*
G02X304009Y1731644I303J0D01*
G37*
G36*
G01X319757D02*
X323457D01*
G02X323760Y1731341I0J-303D01*
G01Y1721335D01*
G02X323457Y1721032I-303J0D01*
G01X319757D01*
G02X319454Y1721335I0J303D01*
G01Y1723747D01*
G02X319441Y1723976I2003J229D01*
G02X319454Y1724205I2016J0D01*
G01Y1728471D01*
G02X319441Y1728700I2003J229D01*
G02X319454Y1728929I2016J0D01*
G01Y1731341D01*
G02X319757Y1731644I303J0D01*
G37*
G36*
G01X335505D02*
X339205D01*
G02X339508Y1731341I0J-303D01*
G01Y1721335D01*
G02X339205Y1721032I-303J0D01*
G01X335505D01*
G02X335202Y1721335I0J303D01*
G01Y1723747D01*
G02X335189Y1723976I2003J229D01*
G02X335202Y1724205I2016J0D01*
G01Y1728471D01*
G02X335189Y1728700I2003J229D01*
G02X335202Y1728929I2016J0D01*
G01Y1731341D01*
G02X335505Y1731644I303J0D01*
G37*
G36*
G01X351253D02*
X354953D01*
G02X355256Y1731341I0J-303D01*
G01Y1721335D01*
G02X354953Y1721032I-303J0D01*
G01X351253D01*
G02X350950Y1721335I0J303D01*
G01Y1723747D01*
G02X350937Y1723976I2003J229D01*
G02X350950Y1724205I2016J0D01*
G01Y1728471D01*
G02X350937Y1728700I2003J229D01*
G02X350950Y1728929I2016J0D01*
G01Y1731341D01*
G02X351253Y1731644I303J0D01*
G37*
G36*
G01X501253D02*
X504953D01*
G02X505256Y1731341I0J-303D01*
G01Y1721335D01*
G02X504953Y1721032I-303J0D01*
G01X501253D01*
G02X500950Y1721335I0J303D01*
G01Y1723369D01*
G02X500860Y1723976I2002J607D01*
G02X501582Y1725558I2094J0D01*
G01X501901Y1726208D01*
G03Y1726470I-267J131D01*
G01X501584Y1727117D01*
G02X500860Y1728700I1369J1583D01*
G02X500950Y1729307I2092J0D01*
G01Y1731341D01*
G02X501253Y1731644I303J0D01*
G37*
G36*
G01X517001D02*
X520701D01*
G02X521004Y1731341I0J-303D01*
G01Y1721335D01*
G02X520701Y1721032I-303J0D01*
G01X517001D01*
G02X516698Y1721335I0J303D01*
G01Y1723369D01*
G02X516608Y1723976I2002J607D01*
G02X517330Y1725558I2094J0D01*
G01X517649Y1726208D01*
G03Y1726470I-267J131D01*
G01X517332Y1727117D01*
G02X516608Y1728700I1369J1583D01*
G02X516698Y1729307I2092J0D01*
G01Y1731341D01*
G02X517001Y1731644I303J0D01*
G37*
G36*
G01X532749D02*
X536449D01*
G02X536752Y1731341I0J-303D01*
G01Y1721335D01*
G02X536449Y1721032I-303J0D01*
G01X532749D01*
G02X532446Y1721335I0J303D01*
G01Y1723369D01*
G02X532356Y1723976I2002J607D01*
G02X533078Y1725558I2094J0D01*
G01X533397Y1726208D01*
G03Y1726470I-267J131D01*
G01X533080Y1727117D01*
G02X532356Y1728700I1369J1583D01*
G02X532446Y1729307I2092J0D01*
G01Y1731341D01*
G02X532749Y1731644I303J0D01*
G37*
G36*
G01X548497D02*
X552197D01*
G02X552500Y1731341I0J-303D01*
G01Y1721335D01*
G02X552197Y1721032I-303J0D01*
G01X548497D01*
G02X548194Y1721335I0J303D01*
G01Y1723369D01*
G02X548104Y1723976I2002J607D01*
G02X548826Y1725558I2094J0D01*
G01X549145Y1726208D01*
G03Y1726470I-267J131D01*
G01X548828Y1727117D01*
G02X548104Y1728700I1369J1583D01*
G02X548194Y1729307I2092J0D01*
G01Y1731341D01*
G02X548497Y1731644I303J0D01*
G37*
G36*
G01X568182D02*
X571882D01*
G02X572184Y1731341I-1J-303D01*
G01Y1721335D01*
G02X571882Y1721032I-302J-1D01*
G01X568182D01*
G02X567880Y1721335I1J303D01*
G01Y1723366D01*
G02X567789Y1723976I2002J610D01*
G02X568511Y1725558I2094J0D01*
G01X568830Y1726208D01*
G03Y1726470I-267J131D01*
G01X568513Y1727117D01*
G02X567789Y1728700I1369J1583D01*
G02X567880Y1729310I2093J0D01*
G01Y1731341D01*
G02X568182Y1731644I302J1D01*
G37*
G36*
G01X583930D02*
X587630D01*
G02X587932Y1731341I-1J-303D01*
G01Y1721335D01*
G02X587630Y1721032I-302J-1D01*
G01X583930D01*
G02X583628Y1721335I1J303D01*
G01Y1723366D01*
G02X583537Y1723976I2002J610D01*
G02X584259Y1725558I2094J0D01*
G01X584578Y1726208D01*
G03Y1726470I-267J131D01*
G01X584261Y1727117D01*
G02X583537Y1728700I1369J1583D01*
G02X583628Y1729310I2093J0D01*
G01Y1731341D01*
G02X583930Y1731644I302J1D01*
G37*
G36*
G01X599678D02*
X603378D01*
G02X603680Y1731341I-1J-303D01*
G01Y1721335D01*
G02X603378Y1721032I-302J-1D01*
G01X599678D01*
G02X599376Y1721335I1J303D01*
G01Y1723366D01*
G02X599285Y1723976I2002J610D01*
G02X600007Y1725558I2094J0D01*
G01X600326Y1726208D01*
G03Y1726470I-267J131D01*
G01X600009Y1727117D01*
G02X599285Y1728700I1369J1583D01*
G02X599376Y1729310I2093J0D01*
G01Y1731341D01*
G02X599678Y1731644I302J1D01*
G37*
G36*
G01X615426D02*
X619126D01*
G02X619428Y1731341I-1J-303D01*
G01Y1721335D01*
G02X619126Y1721032I-302J-1D01*
G01X615426D01*
G02X615124Y1721335I1J303D01*
G01Y1723366D01*
G02X615033Y1723976I2002J610D01*
G02X615755Y1725558I2094J0D01*
G01X616074Y1726208D01*
G03Y1726470I-267J131D01*
G01X615757Y1727117D01*
G02X615033Y1728700I1369J1583D01*
G02X615124Y1729310I2093J0D01*
G01Y1731341D01*
G02X615426Y1731644I302J1D01*
G37*
G36*
G01X1244954D02*
X1248654D01*
G02X1248956Y1731341I-1J-303D01*
G01Y1721335D01*
G02X1248654Y1721032I-302J-1D01*
G01X1244954D01*
G02X1244652Y1721335I1J303D01*
G01Y1723739D01*
G02X1244638Y1723976I2002J237D01*
G02X1244652Y1724213I2016J0D01*
G01Y1728463D01*
G02X1244638Y1728700I2002J237D01*
G02X1244652Y1728937I2016J0D01*
G01Y1731341D01*
G02X1244954Y1731644I302J1D01*
G37*
G36*
G01X1260702D02*
X1264402D01*
G02X1264704Y1731341I-1J-303D01*
G01Y1721335D01*
G02X1264402Y1721032I-302J-1D01*
G01X1260702D01*
G02X1260400Y1721335I1J303D01*
G01Y1723739D01*
G02X1260386Y1723976I2002J237D01*
G02X1260400Y1724213I2016J0D01*
G01Y1728463D01*
G02X1260386Y1728700I2002J237D01*
G02X1260400Y1728937I2016J0D01*
G01Y1731341D01*
G02X1260702Y1731644I302J1D01*
G37*
G36*
G01X1276450D02*
X1280150D01*
G02X1280452Y1731341I-1J-303D01*
G01Y1721335D01*
G02X1280150Y1721032I-302J-1D01*
G01X1276450D01*
G02X1276148Y1721335I1J303D01*
G01Y1723739D01*
G02X1276134Y1723976I2002J237D01*
G02X1276148Y1724213I2016J0D01*
G01Y1728463D01*
G02X1276134Y1728700I2002J237D01*
G02X1276148Y1728937I2016J0D01*
G01Y1731341D01*
G02X1276450Y1731644I302J1D01*
G37*
G36*
G01X1292198D02*
X1295898D01*
G02X1296200Y1731341I-1J-303D01*
G01Y1721335D01*
G02X1295898Y1721032I-302J-1D01*
G01X1292198D01*
G02X1291896Y1721335I1J303D01*
G01Y1723739D01*
G02X1291882Y1723976I2002J237D01*
G02X1291896Y1724213I2016J0D01*
G01Y1728463D01*
G02X1291882Y1728700I2002J237D01*
G02X1291896Y1728937I2016J0D01*
G01Y1731341D01*
G02X1292198Y1731644I302J1D01*
G37*
G36*
G01X1311883D02*
X1315583D01*
G02X1315886Y1731341I0J-303D01*
G01Y1721335D01*
G02X1315583Y1721032I-303J0D01*
G01X1311883D01*
G02X1311580Y1721335I0J303D01*
G01Y1723747D01*
G02X1311567Y1723976I2003J229D01*
G02X1311580Y1724205I2016J0D01*
G01Y1728471D01*
G02X1311567Y1728700I2003J229D01*
G02X1311580Y1728929I2016J0D01*
G01Y1731341D01*
G02X1311883Y1731644I303J0D01*
G37*
G36*
G01X1327631D02*
X1331331D01*
G02X1331634Y1731341I0J-303D01*
G01Y1721335D01*
G02X1331331Y1721032I-303J0D01*
G01X1327631D01*
G02X1327328Y1721335I0J303D01*
G01Y1723747D01*
G02X1327315Y1723976I2003J229D01*
G02X1327328Y1724205I2016J0D01*
G01Y1728471D01*
G02X1327315Y1728700I2003J229D01*
G02X1327328Y1728929I2016J0D01*
G01Y1731341D01*
G02X1327631Y1731644I303J0D01*
G37*
G36*
G01X1343379D02*
X1347079D01*
G02X1347382Y1731341I0J-303D01*
G01Y1721335D01*
G02X1347079Y1721032I-303J0D01*
G01X1343379D01*
G02X1343076Y1721335I0J303D01*
G01Y1723747D01*
G02X1343063Y1723976I2003J229D01*
G02X1343076Y1724205I2016J0D01*
G01Y1728471D01*
G02X1343063Y1728700I2003J229D01*
G02X1343076Y1728929I2016J0D01*
G01Y1731341D01*
G02X1343379Y1731644I303J0D01*
G37*
G36*
G01X1359127D02*
X1362827D01*
G02X1363130Y1731341I0J-303D01*
G01Y1721335D01*
G02X1362827Y1721032I-303J0D01*
G01X1359127D01*
G02X1358824Y1721335I0J303D01*
G01Y1723747D01*
G02X1358811Y1723976I2003J229D01*
G02X1358824Y1724205I2016J0D01*
G01Y1728471D01*
G02X1358811Y1728700I2003J229D01*
G02X1358824Y1728929I2016J0D01*
G01Y1731341D01*
G02X1359127Y1731644I303J0D01*
G37*
G36*
G01X1509127D02*
X1512827D01*
G02X1513130Y1731341I0J-303D01*
G01Y1721335D01*
G02X1512827Y1721032I-303J0D01*
G01X1509127D01*
G02X1508824Y1721335I0J303D01*
G01Y1723369D01*
G02X1508734Y1723976I2002J607D01*
G02X1509456Y1725558I2094J0D01*
G01X1509775Y1726208D01*
G03Y1726470I-267J131D01*
G01X1509458Y1727117D01*
G02X1508734Y1728700I1369J1583D01*
G02X1508824Y1729307I2092J0D01*
G01Y1731341D01*
G02X1509127Y1731644I303J0D01*
G37*
G36*
G01X1524875D02*
X1528575D01*
G02X1528878Y1731341I0J-303D01*
G01Y1721335D01*
G02X1528575Y1721032I-303J0D01*
G01X1524875D01*
G02X1524572Y1721335I0J303D01*
G01Y1723369D01*
G02X1524482Y1723976I2002J607D01*
G02X1525204Y1725558I2094J0D01*
G01X1525523Y1726208D01*
G03Y1726470I-267J131D01*
G01X1525206Y1727117D01*
G02X1524482Y1728700I1369J1583D01*
G02X1524572Y1729307I2092J0D01*
G01Y1731341D01*
G02X1524875Y1731644I303J0D01*
G37*
G36*
G01X1540623D02*
X1544323D01*
G02X1544626Y1731341I0J-303D01*
G01Y1721335D01*
G02X1544323Y1721032I-303J0D01*
G01X1540623D01*
G02X1540320Y1721335I0J303D01*
G01Y1723369D01*
G02X1540230Y1723976I2002J607D01*
G02X1540952Y1725558I2094J0D01*
G01X1541271Y1726208D01*
G03Y1726470I-267J131D01*
G01X1540954Y1727117D01*
G02X1540230Y1728700I1369J1583D01*
G02X1540320Y1729307I2092J0D01*
G01Y1731341D01*
G02X1540623Y1731644I303J0D01*
G37*
G36*
G01X1556371D02*
X1560071D01*
G02X1560374Y1731341I0J-303D01*
G01Y1721335D01*
G02X1560071Y1721032I-303J0D01*
G01X1556371D01*
G02X1556068Y1721335I0J303D01*
G01Y1723369D01*
G02X1555978Y1723976I2002J607D01*
G02X1556700Y1725558I2094J0D01*
G01X1557019Y1726208D01*
G03Y1726470I-267J131D01*
G01X1556702Y1727117D01*
G02X1555978Y1728700I1369J1583D01*
G02X1556068Y1729307I2092J0D01*
G01Y1731341D01*
G02X1556371Y1731644I303J0D01*
G37*
G36*
G01X1576056D02*
X1579756D01*
G02X1580058Y1731341I-1J-303D01*
G01Y1721335D01*
G02X1579756Y1721032I-302J-1D01*
G01X1576056D01*
G02X1575754Y1721335I1J303D01*
G01Y1723366D01*
G02X1575663Y1723976I2002J610D01*
G02X1576385Y1725558I2094J0D01*
G01X1576704Y1726208D01*
G03Y1726470I-267J131D01*
G01X1576387Y1727117D01*
G02X1575663Y1728700I1369J1583D01*
G02X1575754Y1729310I2093J0D01*
G01Y1731341D01*
G02X1576056Y1731644I302J1D01*
G37*
G36*
G01X1591804D02*
X1595504D01*
G02X1595806Y1731341I-1J-303D01*
G01Y1721335D01*
G02X1595504Y1721032I-302J-1D01*
G01X1591804D01*
G02X1591502Y1721335I1J303D01*
G01Y1723366D01*
G02X1591411Y1723976I2002J610D01*
G02X1592133Y1725558I2094J0D01*
G01X1592452Y1726208D01*
G03Y1726470I-267J131D01*
G01X1592135Y1727117D01*
G02X1591411Y1728700I1369J1583D01*
G02X1591502Y1729310I2093J0D01*
G01Y1731341D01*
G02X1591804Y1731644I302J1D01*
G37*
G36*
G01X1607552D02*
X1611252D01*
G02X1611554Y1731341I-1J-303D01*
G01Y1721335D01*
G02X1611252Y1721032I-302J-1D01*
G01X1607552D01*
G02X1607250Y1721335I1J303D01*
G01Y1723366D01*
G02X1607159Y1723976I2002J610D01*
G02X1607881Y1725558I2094J0D01*
G01X1608200Y1726208D01*
G03Y1726470I-267J131D01*
G01X1607883Y1727117D01*
G02X1607159Y1728700I1369J1583D01*
G02X1607250Y1729310I2093J0D01*
G01Y1731341D01*
G02X1607552Y1731644I302J1D01*
G37*
G36*
G01X1623300D02*
X1627000D01*
G02X1627302Y1731341I-1J-303D01*
G01Y1721335D01*
G02X1627000Y1721032I-302J-1D01*
G01X1623300D01*
G02X1622998Y1721335I1J303D01*
G01Y1723366D01*
G02X1622907Y1723976I2002J610D01*
G02X1623629Y1725558I2094J0D01*
G01X1623948Y1726208D01*
G03Y1726470I-267J131D01*
G01X1623631Y1727117D01*
G02X1622907Y1728700I1369J1583D01*
G02X1622998Y1729310I2093J0D01*
G01Y1731341D01*
G02X1623300Y1731644I302J1D01*
G37*
G36*
G01X816942Y1721140D02*
X901218D01*
G02X902102Y1720774I0J-1251D01*
G01X909144Y1713732D01*
G02X909510Y1712848I-885J-884D01*
G01Y1667648D01*
X918648Y1658510D01*
X1064948D01*
G02X1065832Y1658144I0J-1251D01*
G01X1085876Y1638100D01*
X1102078D01*
G02X1102962Y1637734I0J-1251D01*
G01X1105274Y1635422D01*
G02X1105640Y1634538I-885J-884D01*
G01Y1606962D01*
G02X1105274Y1606078I-1251J0D01*
G01X1103642Y1604446D01*
G02X1102758Y1604080I-884J885D01*
G01X943752D01*
G02X942868Y1604446I0J1251D01*
G01X916564Y1630750D01*
X815802D01*
G02X814918Y1631116I0J1251D01*
G01X810826Y1635208D01*
G02X810460Y1636092I885J884D01*
G01Y1714658D01*
G02X810826Y1715542I1251J0D01*
G01X816058Y1720774D01*
G02X816942Y1721140I884J-885D01*
G37*
G36*
G01X944340Y1584840D02*
X1103630D01*
G02X1104337Y1584547I0J-999D01*
G01X1105077Y1583807D01*
G02X1105370Y1583100I-706J-707D01*
G01Y1564620D01*
G02X1105077Y1563913I-999J0D01*
G01X1104017Y1562853D01*
G02X1103310Y1562560I-707J706D01*
G01X945140D01*
G02X944433Y1562853I0J999D01*
G01X942903Y1564383D01*
G02X942610Y1565090I706J707D01*
G01Y1583110D01*
G02X942903Y1583817I999J0D01*
G01X943633Y1584547D01*
G02X944340Y1584840I707J-706D01*
G37*
G36*
G01X105651Y1575002D02*
X102251D01*
G02Y1578006I0J1502D01*
G01X105651D01*
G02Y1575002I0J-1502D01*
G37*
G36*
G01X74218Y1574006D02*
X77618D01*
G02Y1571002I0J-1502D01*
G01X74218D01*
G02Y1574006I0J1502D01*
G37*
G36*
G01X76369Y1508958D02*
X79769D01*
G02Y1505954I0J-1502D01*
G01X76369D01*
G02Y1508958I0J1502D01*
G37*
G36*
G01X391330Y1583652D02*
X387930D01*
G02Y1586658I0J1503D01*
G01X391330D01*
G02Y1583652I0J-1503D01*
G37*
G36*
G01X148938Y1515872D02*
X145538D01*
G02Y1518876I0J1502D01*
G01X148938D01*
G02Y1515872I0J-1502D01*
G37*
G36*
G01X164710Y1519516D02*
X168110D01*
G02Y1516512I0J-1502D01*
G01X164710D01*
G02Y1519516I0J1502D01*
G37*
G36*
G01X89264Y1509114D02*
X92664D01*
G02Y1506108I0J-1503D01*
G01X89264D01*
G02Y1509114I0J1503D01*
G37*
G36*
G01X167266Y1571470D02*
X170666D01*
G02Y1568466I0J-1502D01*
G01X167266D01*
G02Y1571470I0J1502D01*
G37*
G36*
G01X1346792Y1615794D02*
X1350192D01*
G02Y1612790I0J-1502D01*
G01X1346792D01*
G02Y1615794I0J1502D01*
G37*
G36*
G01X1358852D02*
X1362252D01*
G02Y1612790I0J-1502D01*
G01X1358852D01*
G02Y1615794I0J1502D01*
G37*
G36*
G01X1365612Y1591596D02*
X1369012D01*
G02Y1588592I0J-1502D01*
G01X1365612D01*
G02Y1591596I0J1502D01*
G37*
G36*
G01Y1579684D02*
X1369012D01*
G02Y1576680I0J-1502D01*
G01X1365612D01*
G02Y1579684I0J1502D01*
G37*
G36*
G01X1305312D02*
X1308712D01*
G02Y1576680I0J-1502D01*
G01X1305312D01*
G02Y1579684I0J1502D01*
G37*
G36*
G01X1293252Y1591596D02*
X1296652D01*
G02Y1588592I0J-1502D01*
G01X1293252D01*
G02Y1591596I0J1502D01*
G37*
G36*
G01X1310612Y1615794D02*
X1314012D01*
G02Y1612790I0J-1502D01*
G01X1310612D01*
G02Y1615794I0J1502D01*
G37*
G36*
G01X1262372Y1603882D02*
X1265772D01*
G02Y1600878I0J-1502D01*
G01X1262372D01*
G02Y1603882I0J1502D01*
G37*
G36*
G01X1286492Y1615794D02*
X1289892D01*
G02Y1612790I0J-1502D01*
G01X1286492D01*
G02Y1615794I0J1502D01*
G37*
G36*
G01X1262372D02*
X1265772D01*
G02Y1612790I0J-1502D01*
G01X1262372D01*
G02Y1615794I0J1502D01*
G37*
G36*
G01X1334732Y1603882D02*
X1338132D01*
G02Y1600878I0J-1502D01*
G01X1334732D01*
G02Y1603882I0J1502D01*
G37*
G36*
G01X1220892Y1579684D02*
X1224292D01*
G02Y1576680I0J-1502D01*
G01X1220892D01*
G02Y1579684I0J1502D01*
G37*
G36*
G01X1334732Y1615794D02*
X1338132D01*
G02Y1612790I0J-1502D01*
G01X1334732D01*
G02Y1615794I0J1502D01*
G37*
G36*
G01X1370912Y1603882D02*
X1374312D01*
G02Y1600878I0J-1502D01*
G01X1370912D01*
G02Y1603882I0J1502D01*
G37*
G36*
G01X1214132D02*
X1217532D01*
G02Y1600878I0J-1502D01*
G01X1214132D01*
G02Y1603882I0J1502D01*
G37*
G36*
G01X1286492D02*
X1289892D01*
G02Y1600878I0J-1502D01*
G01X1286492D01*
G02Y1603882I0J1502D01*
G37*
G36*
G01X1298552D02*
X1301952D01*
G02Y1600878I0J-1502D01*
G01X1298552D01*
G02Y1603882I0J1502D01*
G37*
G36*
G01X1353552Y1579684D02*
X1356952D01*
G02Y1576680I0J-1502D01*
G01X1353552D01*
G02Y1579684I0J1502D01*
G37*
G36*
G01X1341492Y1591596D02*
X1344892D01*
G02Y1588592I0J-1502D01*
G01X1341492D01*
G02Y1591596I0J1502D01*
G37*
G36*
G01X1370912Y1615794D02*
X1374312D01*
G02Y1612790I0J-1502D01*
G01X1370912D01*
G02Y1615794I0J1502D01*
G37*
G36*
G01X1269132Y1591596D02*
X1272532D01*
G02Y1588592I0J-1502D01*
G01X1269132D01*
G02Y1591596I0J1502D01*
G37*
G36*
G01X1238252Y1603882D02*
X1241652D01*
G02Y1600878I0J-1502D01*
G01X1238252D01*
G02Y1603882I0J1502D01*
G37*
G36*
G01X1353552Y1591596D02*
X1356952D01*
G02Y1588592I0J-1502D01*
G01X1353552D01*
G02Y1591596I0J1502D01*
G37*
G36*
G01X1214132Y1615794D02*
X1217532D01*
G02Y1612790I0J-1502D01*
G01X1214132D01*
G02Y1615794I0J1502D01*
G37*
G36*
G01X1226192Y1603882D02*
X1229592D01*
G02Y1600878I0J-1502D01*
G01X1226192D01*
G02Y1603882I0J1502D01*
G37*
G36*
G01X1208832Y1579684D02*
X1212232D01*
G02Y1576680I0J-1502D01*
G01X1208832D01*
G02Y1579684I0J1502D01*
G37*
G36*
G01Y1591596D02*
X1212232D01*
G02Y1588592I0J-1502D01*
G01X1208832D01*
G02Y1591596I0J1502D01*
G37*
G36*
G01X1341492Y1579684D02*
X1344892D01*
G02Y1576680I0J-1502D01*
G01X1341492D01*
G02Y1579684I0J1502D01*
G37*
G36*
G01X1250312Y1615794D02*
X1253712D01*
G02Y1612790I0J-1502D01*
G01X1250312D01*
G02Y1615794I0J1502D01*
G37*
G36*
G01X1232952Y1579684D02*
X1236352D01*
G02Y1576680I0J-1502D01*
G01X1232952D01*
G02Y1579684I0J1502D01*
G37*
G36*
G01Y1591596D02*
X1236352D01*
G02Y1588592I0J-1502D01*
G01X1232952D01*
G02Y1591596I0J1502D01*
G37*
G36*
G01X1196772Y1579684D02*
X1200172D01*
G02Y1576680I0J-1502D01*
G01X1196772D01*
G02Y1579684I0J1502D01*
G37*
G36*
G01X1257072D02*
X1260472D01*
G02Y1576680I0J-1502D01*
G01X1257072D01*
G02Y1579684I0J1502D01*
G37*
G36*
G01X1220892Y1591596D02*
X1224292D01*
G02Y1588592I0J-1502D01*
G01X1220892D01*
G02Y1591596I0J1502D01*
G37*
G36*
G01X1269132Y1579684D02*
X1272532D01*
G02Y1576680I0J-1502D01*
G01X1269132D01*
G02Y1579684I0J1502D01*
G37*
G36*
G01X1305312Y1591596D02*
X1308712D01*
G02Y1588592I0J-1502D01*
G01X1305312D01*
G02Y1591596I0J1502D01*
G37*
G36*
G01X1245012D02*
X1248412D01*
G02Y1588592I0J-1502D01*
G01X1245012D01*
G02Y1591596I0J1502D01*
G37*
G36*
G01X1250312Y1603882D02*
X1253712D01*
G02Y1600878I0J-1502D01*
G01X1250312D01*
G02Y1603882I0J1502D01*
G37*
G36*
G01X1317372Y1579684D02*
X1320772D01*
G02Y1576680I0J-1502D01*
G01X1317372D01*
G02Y1579684I0J1502D01*
G37*
G36*
G01X1358852Y1603882D02*
X1362252D01*
G02Y1600878I0J-1502D01*
G01X1358852D01*
G02Y1603882I0J1502D01*
G37*
G36*
G01X1202072D02*
X1205472D01*
G02Y1600878I0J-1502D01*
G01X1202072D01*
G02Y1603882I0J1502D01*
G37*
G36*
G01Y1615794D02*
X1205472D01*
G02Y1612790I0J-1502D01*
G01X1202072D01*
G02Y1615794I0J1502D01*
G37*
G36*
G01X1322672Y1603882D02*
X1326072D01*
G02Y1600878I0J-1502D01*
G01X1322672D01*
G02Y1603882I0J1502D01*
G37*
G36*
G01X1310612D02*
X1314012D01*
G02Y1600878I0J-1502D01*
G01X1310612D01*
G02Y1603882I0J1502D01*
G37*
G36*
G01X1274432Y1615794D02*
X1277832D01*
G02Y1612790I0J-1502D01*
G01X1274432D01*
G02Y1615794I0J1502D01*
G37*
G36*
G01X1329432Y1579684D02*
X1332832D01*
G02Y1576680I0J-1502D01*
G01X1329432D01*
G02Y1579684I0J1502D01*
G37*
G36*
G01X1346792Y1603882D02*
X1350192D01*
G02Y1600878I0J-1502D01*
G01X1346792D01*
G02Y1603882I0J1502D01*
G37*
G36*
G01X1317372Y1591596D02*
X1320772D01*
G02Y1588592I0J-1502D01*
G01X1317372D01*
G02Y1591596I0J1502D01*
G37*
G36*
G01X1329432D02*
X1332832D01*
G02Y1588592I0J-1502D01*
G01X1329432D01*
G02Y1591596I0J1502D01*
G37*
G36*
G01X1322672Y1615794D02*
X1326072D01*
G02Y1612790I0J-1502D01*
G01X1322672D01*
G02Y1615794I0J1502D01*
G37*
G36*
G01X1281192Y1591596D02*
X1284592D01*
G02Y1588592I0J-1502D01*
G01X1281192D01*
G02Y1591596I0J1502D01*
G37*
G36*
G01X1196772D02*
X1200172D01*
G02Y1588592I0J-1502D01*
G01X1196772D01*
G02Y1591596I0J1502D01*
G37*
G36*
G01X1226192Y1615794D02*
X1229592D01*
G02Y1612790I0J-1502D01*
G01X1226192D01*
G02Y1615794I0J1502D01*
G37*
G36*
G01X1293252Y1579684D02*
X1296652D01*
G02Y1576680I0J-1502D01*
G01X1293252D01*
G02Y1579684I0J1502D01*
G37*
G36*
G01X1298552Y1615794D02*
X1301952D01*
G02Y1612790I0J-1502D01*
G01X1298552D01*
G02Y1615794I0J1502D01*
G37*
G36*
G01X1281192Y1579684D02*
X1284592D01*
G02Y1576680I0J-1502D01*
G01X1281192D01*
G02Y1579684I0J1502D01*
G37*
G36*
G01X1245012D02*
X1248412D01*
G02Y1576680I0J-1502D01*
G01X1245012D01*
G02Y1579684I0J1502D01*
G37*
G36*
G01X1257072Y1591596D02*
X1260472D01*
G02Y1588592I0J-1502D01*
G01X1257072D01*
G02Y1591596I0J1502D01*
G37*
G36*
G01X1274432Y1603882D02*
X1277832D01*
G02Y1600878I0J-1502D01*
G01X1274432D01*
G02Y1603882I0J1502D01*
G37*
G36*
G01X1238252Y1615794D02*
X1241652D01*
G02Y1612790I0J-1502D01*
G01X1238252D01*
G02Y1615794I0J1502D01*
G37*
G36*
G01X1474516Y730492D02*
G02X1473515Y728758I-2002J0D01*
G01X1469877Y726657D01*
G02X1468878Y726390I-999J1736D01*
G01X1468876D01*
G02X1466874Y728392I0J2002D01*
G02X1467875Y730126I2002J0D01*
G01X1471513Y732227D01*
G02X1472512Y732494I999J-1736D01*
G01X1472514D01*
G02X1474516Y730492I0J-2002D01*
G37*
G36*
G01X1477716Y717492D02*
G02X1476715Y715758I-2002J0D01*
G01X1473077Y713657D01*
G02X1472078Y713390I-999J1736D01*
G01X1472076D01*
G02X1470074Y715392I0J2002D01*
G02X1471075Y717126I2002J0D01*
G01X1474713Y719227D01*
G02X1475712Y719494I999J-1736D01*
G01X1475714D01*
G02X1477716Y717492I0J-2002D01*
G37*
G36*
G01Y702992D02*
G02X1476715Y701258I-2002J0D01*
G01X1473077Y699157D01*
G02X1472078Y698890I-999J1736D01*
G01X1472076D01*
G02X1470074Y700892I0J2002D01*
G02X1471075Y702626I2002J0D01*
G01X1474713Y704727D01*
G02X1475712Y704994I999J-1736D01*
G01X1475714D01*
G02X1477716Y702992I0J-2002D01*
G37*
G36*
G01Y688492D02*
G02X1476715Y686758I-2002J0D01*
G01X1473077Y684657D01*
G02X1472078Y684390I-999J1736D01*
G01X1472076D01*
G02X1470074Y686392I0J2002D01*
G02X1471075Y688126I2002J0D01*
G01X1474713Y690227D01*
G02X1475712Y690494I999J-1736D01*
G01X1475714D01*
G02X1477716Y688492I0J-2002D01*
G37*
G36*
G01Y673992D02*
G02X1476715Y672258I-2002J0D01*
G01X1473077Y670157D01*
G02X1472078Y669890I-999J1736D01*
G01X1472076D01*
G02X1470074Y671892I0J2002D01*
G02X1471075Y673626I2002J0D01*
G01X1474713Y675727D01*
G02X1475712Y675994I999J-1736D01*
G01X1475714D01*
G02X1477716Y673992I0J-2002D01*
G37*
G36*
G01Y659492D02*
G02X1476715Y657758I-2002J0D01*
G01X1473077Y655657D01*
G02X1472078Y655390I-999J1736D01*
G01X1472076D01*
G02X1470074Y657392I0J2002D01*
G02X1471075Y659126I2002J0D01*
G01X1474713Y661227D01*
G02X1475712Y661494I999J-1736D01*
G01X1475714D01*
G02X1477716Y659492I0J-2002D01*
G37*
G36*
G01X1455174Y716992D02*
G02X1457176Y718994I2002J0D01*
G01X1457178D01*
G02X1458177Y718727I0J-2003D01*
G01X1461815Y716626D01*
G02X1462816Y714892I-1001J-1734D01*
G02X1460814Y712890I-2002J0D01*
G01X1460812D01*
G02X1459813Y713157I0J2003D01*
G01X1456175Y715258D01*
G02X1455174Y716992I1001J1734D01*
G37*
G36*
G01Y704992D02*
G02X1457176Y706994I2002J0D01*
G01X1457178D01*
G02X1458177Y706727I0J-2003D01*
G01X1461815Y704626D01*
G02X1462816Y702892I-1001J-1734D01*
G02X1460814Y700890I-2002J0D01*
G01X1460812D01*
G02X1459813Y701157I0J2003D01*
G01X1456175Y703258D01*
G02X1455174Y704992I1001J1734D01*
G37*
G36*
G01Y692992D02*
G02X1457176Y694994I2002J0D01*
G01X1457178D01*
G02X1458177Y694727I0J-2003D01*
G01X1461815Y692626D01*
G02X1462816Y690892I-1001J-1734D01*
G02X1460814Y688890I-2002J0D01*
G01X1460812D01*
G02X1459813Y689157I0J2003D01*
G01X1456175Y691258D01*
G02X1455174Y692992I1001J1734D01*
G37*
G36*
G01Y680992D02*
G02X1457176Y682994I2002J0D01*
G01X1457178D01*
G02X1458177Y682727I0J-2003D01*
G01X1461815Y680626D01*
G02X1462816Y678892I-1001J-1734D01*
G02X1460814Y676890I-2002J0D01*
G01X1460812D01*
G02X1459813Y677157I0J2003D01*
G01X1456175Y679258D01*
G02X1455174Y680992I1001J1734D01*
G37*
G36*
G01Y668992D02*
G02X1457176Y670994I2002J0D01*
G01X1457178D01*
G02X1458177Y670727I0J-2003D01*
G01X1461815Y668626D01*
G02X1462816Y666892I-1001J-1734D01*
G02X1460814Y664890I-2002J0D01*
G01X1460812D01*
G02X1459813Y665157I0J2003D01*
G01X1456175Y667258D01*
G02X1455174Y668992I1001J1734D01*
G37*
G36*
G01Y656992D02*
G02X1457176Y658994I2002J0D01*
G01X1457178D01*
G02X1458177Y658727I0J-2003D01*
G01X1461815Y656626D01*
G02X1462816Y654892I-1001J-1734D01*
G02X1460814Y652890I-2002J0D01*
G01X1460812D01*
G02X1459813Y653157I0J2003D01*
G01X1456175Y655258D01*
G02X1455174Y656992I1001J1734D01*
G37*
G36*
G01X1390978Y737198D02*
G02X1389977Y735464I-2002J0D01*
G01X1386339Y733363D01*
G02X1385340Y733096I-999J1736D01*
G01X1385338D01*
G02X1383336Y735098I0J2002D01*
G02X1384337Y736832I2002J0D01*
G01X1387975Y738933D01*
G02X1388974Y739200I999J-1736D01*
G01X1388976D01*
G02X1390978Y737198I0J-2002D01*
G37*
G36*
G01X1395208Y722735D02*
G02X1394207Y721001I-2002J0D01*
G01X1390569Y718900D01*
G02X1389570Y718632I-1001J1735D01*
G01X1389568D01*
G02X1387566Y720635I1J2003D01*
G02X1388567Y722369I2002J0D01*
G01X1392205Y724470D01*
G02X1393204Y724738I1001J-1735D01*
G01X1393206D01*
G02X1395208Y722735I-1J-2003D01*
G37*
G36*
G01Y693708D02*
G02X1394207Y691974I-2002J0D01*
G01X1390569Y689873D01*
G02X1389570Y689606I-999J1736D01*
G01X1389568D01*
G02X1387566Y691608I0J2002D01*
G02X1388567Y693342I2002J0D01*
G01X1392205Y695443D01*
G02X1393204Y695710I999J-1736D01*
G01X1393206D01*
G02X1395208Y693708I0J-2002D01*
G37*
G36*
G01Y708208D02*
G02X1394207Y706474I-2002J0D01*
G01X1390569Y704373D01*
G02X1389570Y704106I-999J1736D01*
G01X1389568D01*
G02X1387566Y706108I0J2002D01*
G02X1388567Y707842I2002J0D01*
G01X1392205Y709943D01*
G02X1393204Y710210I999J-1736D01*
G01X1393206D01*
G02X1395208Y708208I0J-2002D01*
G37*
G36*
G01Y679208D02*
G02X1394207Y677474I-2002J0D01*
G01X1390569Y675373D01*
G02X1389570Y675106I-999J1736D01*
G01X1389568D01*
G02X1387566Y677108I0J2002D01*
G02X1388567Y678842I2002J0D01*
G01X1392205Y680943D01*
G02X1393204Y681210I999J-1736D01*
G01X1393206D01*
G02X1395208Y679208I0J-2002D01*
G37*
G36*
G01Y664708D02*
G02X1394207Y662974I-2002J0D01*
G01X1390569Y660873D01*
G02X1389570Y660606I-999J1736D01*
G01X1389568D01*
G02X1387566Y662608I0J2002D01*
G02X1388567Y664342I2002J0D01*
G01X1392205Y666443D01*
G02X1393204Y666710I999J-1736D01*
G01X1393206D01*
G02X1395208Y664708I0J-2002D01*
G37*
G36*
G01X1372666Y719708D02*
G02X1374668Y721710I2002J0D01*
G01X1374670D01*
G02X1375669Y721443I0J-2003D01*
G01X1379307Y719342D01*
G02X1380308Y717608I-1001J-1734D01*
G02X1378306Y715606I-2002J0D01*
G01X1378304D01*
G02X1377305Y715873I0J2003D01*
G01X1373667Y717974D01*
G02X1372666Y719708I1001J1734D01*
G37*
G36*
G01Y695708D02*
G02X1374668Y697710I2002J0D01*
G01X1374670D01*
G02X1375669Y697443I0J-2003D01*
G01X1379307Y695342D01*
G02X1380308Y693608I-1001J-1734D01*
G02X1378306Y691606I-2002J0D01*
G01X1378304D01*
G02X1377305Y691873I0J2003D01*
G01X1373667Y693974D01*
G02X1372666Y695708I1001J1734D01*
G37*
G36*
G01Y707708D02*
G02X1374668Y709710I2002J0D01*
G01X1374670D01*
G02X1375669Y709443I0J-2003D01*
G01X1379307Y707342D01*
G02X1380308Y705608I-1001J-1734D01*
G02X1378306Y703606I-2002J0D01*
G01X1378304D01*
G02X1377305Y703873I0J2003D01*
G01X1373667Y705974D01*
G02X1372666Y707708I1001J1734D01*
G37*
G36*
G01Y683708D02*
G02X1374668Y685710I2002J0D01*
G01X1374670D01*
G02X1375669Y685443I0J-2003D01*
G01X1379307Y683342D01*
G02X1380308Y681608I-1001J-1734D01*
G02X1378306Y679606I-2002J0D01*
G01X1378304D01*
G02X1377305Y679873I0J2003D01*
G01X1373667Y681974D01*
G02X1372666Y683708I1001J1734D01*
G37*
G36*
G01Y671708D02*
G02X1374668Y673710I2002J0D01*
G01X1374670D01*
G02X1375669Y673443I0J-2003D01*
G01X1379307Y671342D01*
G02X1380308Y669608I-1001J-1734D01*
G02X1378306Y667606I-2002J0D01*
G01X1378304D01*
G02X1377305Y667873I0J2003D01*
G01X1373667Y669974D01*
G02X1372666Y671708I1001J1734D01*
G37*
G36*
G01Y659708D02*
G02X1374668Y661710I2002J0D01*
G01X1374670D01*
G02X1375669Y661443I0J-2003D01*
G01X1379307Y659342D01*
G02X1380308Y657608I-1001J-1734D01*
G02X1378306Y655606I-2002J0D01*
G01X1378304D01*
G02X1377305Y655873I0J2003D01*
G01X1373667Y657974D01*
G02X1372666Y659708I1001J1734D01*
G37*
G36*
G01X146312Y1571028D02*
X149712D01*
G02Y1568022I0J-1503D01*
G01X146312D01*
G02Y1571028I0J1503D01*
G37*
G36*
G01X1701934Y76800D02*
X1705334D01*
G02Y73794I0J-1503D01*
G01X1701934D01*
G02Y76800I0J1503D01*
G37*
G36*
G01X1690934Y70800D02*
X1694334D01*
G02Y67794I0J-1503D01*
G01X1690934D01*
G02Y70800I0J1503D01*
G37*
G36*
G01X1679934Y76800D02*
X1683334D01*
G02Y73794I0J-1503D01*
G01X1679934D01*
G02Y76800I0J1503D01*
G37*
G36*
G01X1657800D02*
X1661200D01*
G02Y73794I0J-1503D01*
G01X1657800D01*
G02Y76800I0J1503D01*
G37*
G36*
G01X1668800Y70800D02*
X1672200D01*
G02Y67794I0J-1503D01*
G01X1668800D01*
G02Y70800I0J1503D01*
G37*
G36*
G01X1646800D02*
X1650200D01*
G02Y67794I0J-1503D01*
G01X1646800D01*
G02Y70800I0J1503D01*
G37*
G36*
G01X1635800Y76800D02*
X1639200D01*
G02Y73794I0J-1503D01*
G01X1635800D01*
G02Y76800I0J1503D01*
G37*
G36*
G01X1612596D02*
X1615996D01*
G02Y73794I0J-1503D01*
G01X1612596D01*
G02Y76800I0J1503D01*
G37*
G36*
G01X1623596Y70800D02*
X1626996D01*
G02Y67794I0J-1503D01*
G01X1623596D01*
G02Y70800I0J1503D01*
G37*
G36*
G01X1601596D02*
X1604996D01*
G02Y67794I0J-1503D01*
G01X1601596D01*
G02Y70800I0J1503D01*
G37*
G36*
G01X1590596Y76800D02*
X1593996D01*
G02Y73794I0J-1503D01*
G01X1590596D01*
G02Y76800I0J1503D01*
G37*
G36*
G01X1579596Y70800D02*
X1582996D01*
G02Y67794I0J-1503D01*
G01X1579596D01*
G02Y70800I0J1503D01*
G37*
G36*
G01X1568596Y76800D02*
X1571996D01*
G02Y73794I0J-1503D01*
G01X1568596D01*
G02Y76800I0J1503D01*
G37*
G36*
G01X1546596D02*
X1549996D01*
G02Y73794I0J-1503D01*
G01X1546596D01*
G02Y76800I0J1503D01*
G37*
G36*
G01X1557596Y70800D02*
X1560996D01*
G02Y67794I0J-1503D01*
G01X1557596D01*
G02Y70800I0J1503D01*
G37*
G36*
G01X1535596D02*
X1538996D01*
G02Y67794I0J-1503D01*
G01X1535596D01*
G02Y70800I0J1503D01*
G37*
G36*
G01X230895Y73838D02*
X227495D01*
G02Y76842I0J1502D01*
G01X230895D01*
G02Y73838I0J-1502D01*
G37*
G36*
G01X219895Y67838D02*
X216495D01*
G02Y70842I0J1502D01*
G01X219895D01*
G02Y67838I0J-1502D01*
G37*
G36*
G01X208895Y73838D02*
X205495D01*
G02Y76842I0J1502D01*
G01X208895D01*
G02Y73838I0J-1502D01*
G37*
G36*
G01X194361Y70842D02*
X197761D01*
G02Y67838I0J-1502D01*
G01X194361D01*
G02Y70842I0J1502D01*
G37*
G36*
G01X183361Y76842D02*
X186761D01*
G02Y73838I0J-1502D01*
G01X183361D01*
G02Y76842I0J1502D01*
G37*
G36*
G01X161361D02*
X164761D01*
G02Y73838I0J-1502D01*
G01X161361D01*
G02Y76842I0J1502D01*
G37*
G36*
G01X172361Y70842D02*
X175761D01*
G02Y67838I0J-1502D01*
G01X172361D01*
G02Y70842I0J1502D01*
G37*
G36*
G01X149157D02*
X152557D01*
G02Y67838I0J-1502D01*
G01X149157D01*
G02Y70842I0J1502D01*
G37*
G36*
G01X138157Y76842D02*
X141557D01*
G02Y73838I0J-1502D01*
G01X138157D01*
G02Y76842I0J1502D01*
G37*
G36*
G01X116157D02*
X119557D01*
G02Y73838I0J-1502D01*
G01X116157D01*
G02Y76842I0J1502D01*
G37*
G36*
G01X127157Y70842D02*
X130557D01*
G02Y67838I0J-1502D01*
G01X127157D01*
G02Y70842I0J1502D01*
G37*
G36*
G01X105157D02*
X108557D01*
G02Y67838I0J-1502D01*
G01X105157D01*
G02Y70842I0J1502D01*
G37*
G36*
G01X94157Y76842D02*
X97557D01*
G02Y73838I0J-1502D01*
G01X94157D01*
G02Y76842I0J1502D01*
G37*
G36*
G01X83157Y70842D02*
X86557D01*
G02Y67838I0J-1502D01*
G01X83157D01*
G02Y70842I0J1502D01*
G37*
G36*
G01X72157Y76842D02*
X75557D01*
G02Y73838I0J-1502D01*
G01X72157D01*
G02Y76842I0J1502D01*
G37*
G36*
G01X61157Y70842D02*
X64557D01*
G02Y67838I0J-1502D01*
G01X61157D01*
G02Y70842I0J1502D01*
G37*
G36*
G01X1619075Y1579684D02*
X1622475D01*
G02Y1576680I0J-1502D01*
G01X1619075D01*
G02Y1579684I0J1502D01*
G37*
G36*
G01X326857Y1603882D02*
X330257D01*
G02Y1600878I0J-1502D01*
G01X326857D01*
G02Y1603882I0J1502D01*
G37*
G36*
G01X363037Y1615794D02*
X366437D01*
G02Y1612790I0J-1502D01*
G01X363037D01*
G02Y1615794I0J1502D01*
G37*
G36*
G01X545411Y1579684D02*
X548811D01*
G02Y1576680I0J-1502D01*
G01X545411D01*
G02Y1579684I0J1502D01*
G37*
G36*
G01Y1591596D02*
X548811D01*
G02Y1588592I0J-1502D01*
G01X545411D01*
G02Y1591596I0J1502D01*
G37*
G36*
G01X1377672D02*
X1381072D01*
G02Y1588592I0J-1502D01*
G01X1377672D01*
G02Y1591596I0J1502D01*
G37*
G36*
G01X533351D02*
X536751D01*
G02Y1588592I0J-1502D01*
G01X533351D01*
G02Y1591596I0J1502D01*
G37*
G36*
G01Y1579684D02*
X536751D01*
G02Y1576680I0J-1502D01*
G01X533351D01*
G02Y1579684I0J1502D01*
G37*
G36*
G01X1594955Y1591596D02*
X1598355D01*
G02Y1588592I0J-1502D01*
G01X1594955D01*
G02Y1591596I0J1502D01*
G37*
G36*
G01X581591D02*
X584991D01*
G02Y1588592I0J-1502D01*
G01X581591D01*
G02Y1591596I0J1502D01*
G37*
G36*
G01Y1579684D02*
X584991D01*
G02Y1576680I0J-1502D01*
G01X581591D01*
G02Y1579684I0J1502D01*
G37*
G36*
G01X1594955D02*
X1598355D01*
G02Y1576680I0J-1502D01*
G01X1594955D01*
G02Y1579684I0J1502D01*
G37*
G36*
G01X605711Y1591596D02*
X609111D01*
G02Y1588592I0J-1502D01*
G01X605711D01*
G02Y1591596I0J1502D01*
G37*
G36*
G01X333617Y1579684D02*
X337017D01*
G02Y1576680I0J-1502D01*
G01X333617D01*
G02Y1579684I0J1502D01*
G37*
G36*
G01X345677D02*
X349077D01*
G02Y1576680I0J-1502D01*
G01X345677D01*
G02Y1579684I0J1502D01*
G37*
G36*
G01X617771D02*
X621171D01*
G02Y1576680I0J-1502D01*
G01X617771D01*
G02Y1579684I0J1502D01*
G37*
G36*
G01Y1591596D02*
X621171D01*
G02Y1588592I0J-1502D01*
G01X617771D01*
G02Y1591596I0J1502D01*
G37*
G36*
G01X629831Y1579684D02*
X633231D01*
G02Y1576680I0J-1502D01*
G01X629831D01*
G02Y1579684I0J1502D01*
G37*
G36*
G01X1582895D02*
X1586295D01*
G02Y1576680I0J-1502D01*
G01X1582895D01*
G02Y1579684I0J1502D01*
G37*
G36*
G01X1570835D02*
X1574235D01*
G02Y1576680I0J-1502D01*
G01X1570835D01*
G02Y1579684I0J1502D01*
G37*
G36*
G01X1558775D02*
X1562175D01*
G02Y1576680I0J-1502D01*
G01X1558775D01*
G02Y1579684I0J1502D01*
G37*
G36*
G01X321557D02*
X324957D01*
G02Y1576680I0J-1502D01*
G01X321557D01*
G02Y1579684I0J1502D01*
G37*
G36*
G01X278617Y1603882D02*
X282017D01*
G02Y1600878I0J-1502D01*
G01X278617D01*
G02Y1603882I0J1502D01*
G37*
G36*
G01X1534655Y1591596D02*
X1538055D01*
G02Y1588592I0J-1502D01*
G01X1534655D01*
G02Y1591596I0J1502D01*
G37*
G36*
G01Y1579684D02*
X1538055D01*
G02Y1576680I0J-1502D01*
G01X1534655D01*
G02Y1579684I0J1502D01*
G37*
G36*
G01X1510535Y1591596D02*
X1513935D01*
G02Y1588592I0J-1502D01*
G01X1510535D01*
G02Y1591596I0J1502D01*
G37*
G36*
G01X1522595D02*
X1525995D01*
G02Y1588592I0J-1502D01*
G01X1522595D01*
G02Y1591596I0J1502D01*
G37*
G36*
G01X309497Y1579684D02*
X312897D01*
G02Y1576680I0J-1502D01*
G01X309497D01*
G02Y1579684I0J1502D01*
G37*
G36*
G01X302737Y1603882D02*
X306137D01*
G02Y1600878I0J-1502D01*
G01X302737D01*
G02Y1603882I0J1502D01*
G37*
G36*
G01X1498475Y1579684D02*
X1501875D01*
G02Y1576680I0J-1502D01*
G01X1498475D01*
G02Y1579684I0J1502D01*
G37*
G36*
G01X314797Y1615794D02*
X318197D01*
G02Y1612790I0J-1502D01*
G01X314797D01*
G02Y1615794I0J1502D01*
G37*
G36*
G01X278617D02*
X282017D01*
G02Y1612790I0J-1502D01*
G01X278617D01*
G02Y1615794I0J1502D01*
G37*
G36*
G01X497171Y1591596D02*
X500571D01*
G02Y1588592I0J-1502D01*
G01X497171D01*
G02Y1591596I0J1502D01*
G37*
G36*
G01X509231D02*
X512631D01*
G02Y1588592I0J-1502D01*
G01X509231D01*
G02Y1591596I0J1502D01*
G37*
G36*
G01Y1579684D02*
X512631D01*
G02Y1576680I0J-1502D01*
G01X509231D01*
G02Y1579684I0J1502D01*
G37*
G36*
G01X1486415Y1591596D02*
X1489815D01*
G02Y1588592I0J-1502D01*
G01X1486415D01*
G02Y1591596I0J1502D01*
G37*
G36*
G01Y1579684D02*
X1489815D01*
G02Y1576680I0J-1502D01*
G01X1486415D01*
G02Y1579684I0J1502D01*
G37*
G36*
G01X321557Y1591596D02*
X324957D01*
G02Y1588592I0J-1502D01*
G01X321557D01*
G02Y1591596I0J1502D01*
G37*
G36*
G01X1462295D02*
X1465695D01*
G02Y1588592I0J-1502D01*
G01X1462295D01*
G02Y1591596I0J1502D01*
G37*
G36*
G01X1474355D02*
X1477755D01*
G02Y1588592I0J-1502D01*
G01X1474355D01*
G02Y1591596I0J1502D01*
G37*
G36*
G01X641891Y1579684D02*
X645291D01*
G02Y1576680I0J-1502D01*
G01X641891D01*
G02Y1579684I0J1502D01*
G37*
G36*
G01Y1591596D02*
X645291D01*
G02Y1588592I0J-1502D01*
G01X641891D01*
G02Y1591596I0J1502D01*
G37*
G36*
G01X285377Y1579684D02*
X288777D01*
G02Y1576680I0J-1502D01*
G01X285377D01*
G02Y1579684I0J1502D01*
G37*
G36*
G01X1462295D02*
X1465695D01*
G02Y1576680I0J-1502D01*
G01X1462295D01*
G02Y1579684I0J1502D01*
G37*
G36*
G01X206257Y1615794D02*
X209657D01*
G02Y1612790I0J-1502D01*
G01X206257D01*
G02Y1615794I0J1502D01*
G37*
G36*
G01X338917D02*
X342317D01*
G02Y1612790I0J-1502D01*
G01X338917D01*
G02Y1615794I0J1502D01*
G37*
G36*
G01X1474355Y1579684D02*
X1477755D01*
G02Y1576680I0J-1502D01*
G01X1474355D01*
G02Y1579684I0J1502D01*
G37*
G36*
G01X261257D02*
X264657D01*
G02Y1576680I0J-1502D01*
G01X261257D01*
G02Y1579684I0J1502D01*
G37*
G36*
G01X485111D02*
X488511D01*
G02Y1576680I0J-1502D01*
G01X485111D01*
G02Y1579684I0J1502D01*
G37*
G36*
G01Y1591596D02*
X488511D01*
G02Y1588592I0J-1502D01*
G01X485111D01*
G02Y1591596I0J1502D01*
G37*
G36*
G01X338917Y1603882D02*
X342317D01*
G02Y1600878I0J-1502D01*
G01X338917D01*
G02Y1603882I0J1502D01*
G37*
G36*
G01X1648495Y1615794D02*
X1651895D01*
G02Y1612790I0J-1502D01*
G01X1648495D01*
G02Y1615794I0J1502D01*
G37*
G36*
G01Y1603882D02*
X1651895D01*
G02Y1600878I0J-1502D01*
G01X1648495D01*
G02Y1603882I0J1502D01*
G37*
G36*
G01X1624375Y1615794D02*
X1627775D01*
G02Y1612790I0J-1502D01*
G01X1624375D01*
G02Y1615794I0J1502D01*
G37*
G36*
G01X266557D02*
X269957D01*
G02Y1612790I0J-1502D01*
G01X266557D01*
G02Y1615794I0J1502D01*
G37*
G36*
G01X254497Y1603882D02*
X257897D01*
G02Y1600878I0J-1502D01*
G01X254497D01*
G02Y1603882I0J1502D01*
G37*
G36*
G01X653951Y1591596D02*
X657351D01*
G02Y1588592I0J-1502D01*
G01X653951D01*
G02Y1591596I0J1502D01*
G37*
G36*
G01Y1579684D02*
X657351D01*
G02Y1576680I0J-1502D01*
G01X653951D01*
G02Y1579684I0J1502D01*
G37*
G36*
G01X369797Y1591596D02*
X373197D01*
G02Y1588592I0J-1502D01*
G01X369797D01*
G02Y1591596I0J1502D01*
G37*
G36*
G01X1636435Y1603882D02*
X1639835D01*
G02Y1600878I0J-1502D01*
G01X1636435D01*
G02Y1603882I0J1502D01*
G37*
G36*
G01X266557D02*
X269957D01*
G02Y1600878I0J-1502D01*
G01X266557D01*
G02Y1603882I0J1502D01*
G37*
G36*
G01X1624375D02*
X1627775D01*
G02Y1600878I0J-1502D01*
G01X1624375D01*
G02Y1603882I0J1502D01*
G37*
G36*
G01X254497Y1615794D02*
X257897D01*
G02Y1612790I0J-1502D01*
G01X254497D01*
G02Y1615794I0J1502D01*
G37*
G36*
G01X194197Y1603882D02*
X197597D01*
G02Y1600878I0J-1502D01*
G01X194197D01*
G02Y1603882I0J1502D01*
G37*
G36*
G01X242437D02*
X245837D01*
G02Y1600878I0J-1502D01*
G01X242437D01*
G02Y1603882I0J1502D01*
G37*
G36*
G01X1612315D02*
X1615715D01*
G02Y1600878I0J-1502D01*
G01X1612315D01*
G02Y1603882I0J1502D01*
G37*
G36*
G01Y1615794D02*
X1615715D01*
G02Y1612790I0J-1502D01*
G01X1612315D01*
G02Y1615794I0J1502D01*
G37*
G36*
G01X230377D02*
X233777D01*
G02Y1612790I0J-1502D01*
G01X230377D01*
G02Y1615794I0J1502D01*
G37*
G36*
G01X521291Y1579684D02*
X524691D01*
G02Y1576680I0J-1502D01*
G01X521291D01*
G02Y1579684I0J1502D01*
G37*
G36*
G01Y1591596D02*
X524691D01*
G02Y1588592I0J-1502D01*
G01X521291D01*
G02Y1591596I0J1502D01*
G37*
G36*
G01X497171Y1579684D02*
X500571D01*
G02Y1576680I0J-1502D01*
G01X497171D01*
G02Y1579684I0J1502D01*
G37*
G36*
G01X593651D02*
X597051D01*
G02Y1576680I0J-1502D01*
G01X593651D01*
G02Y1579684I0J1502D01*
G37*
G36*
G01Y1591596D02*
X597051D01*
G02Y1588592I0J-1502D01*
G01X593651D01*
G02Y1591596I0J1502D01*
G37*
G36*
G01X1600255Y1603882D02*
X1603655D01*
G02Y1600878I0J-1502D01*
G01X1600255D01*
G02Y1603882I0J1502D01*
G37*
G36*
G01Y1615794D02*
X1603655D01*
G02Y1612790I0J-1502D01*
G01X1600255D01*
G02Y1615794I0J1502D01*
G37*
G36*
G01X557471Y1579684D02*
X560871D01*
G02Y1576680I0J-1502D01*
G01X557471D01*
G02Y1579684I0J1502D01*
G37*
G36*
G01X569531D02*
X572931D01*
G02Y1576680I0J-1502D01*
G01X569531D01*
G02Y1579684I0J1502D01*
G37*
G36*
G01Y1591596D02*
X572931D01*
G02Y1588592I0J-1502D01*
G01X569531D01*
G02Y1591596I0J1502D01*
G37*
G36*
G01X557471D02*
X560871D01*
G02Y1588592I0J-1502D01*
G01X557471D01*
G02Y1591596I0J1502D01*
G37*
G36*
G01X333617D02*
X337017D01*
G02Y1588592I0J-1502D01*
G01X333617D01*
G02Y1591596I0J1502D01*
G37*
G36*
G01X345677D02*
X349077D01*
G02Y1588592I0J-1502D01*
G01X345677D01*
G02Y1591596I0J1502D01*
G37*
G36*
G01X1607015Y1579684D02*
X1610415D01*
G02Y1576680I0J-1502D01*
G01X1607015D01*
G02Y1579684I0J1502D01*
G37*
G36*
G01X1576135Y1615794D02*
X1579535D01*
G02Y1612790I0J-1502D01*
G01X1576135D01*
G02Y1615794I0J1502D01*
G37*
G36*
G01X314797Y1603882D02*
X318197D01*
G02Y1600878I0J-1502D01*
G01X314797D01*
G02Y1603882I0J1502D01*
G37*
G36*
G01X1576135D02*
X1579535D01*
G02Y1600878I0J-1502D01*
G01X1576135D01*
G02Y1603882I0J1502D01*
G37*
G36*
G01X261257Y1591596D02*
X264657D01*
G02Y1588592I0J-1502D01*
G01X261257D01*
G02Y1591596I0J1502D01*
G37*
G36*
G01X357737Y1579684D02*
X361137D01*
G02Y1576680I0J-1502D01*
G01X357737D01*
G02Y1579684I0J1502D01*
G37*
G36*
G01X1546715Y1591596D02*
X1550115D01*
G02Y1588592I0J-1502D01*
G01X1546715D01*
G02Y1591596I0J1502D01*
G37*
G36*
G01Y1579684D02*
X1550115D01*
G02Y1576680I0J-1502D01*
G01X1546715D01*
G02Y1579684I0J1502D01*
G37*
G36*
G01X326857Y1615794D02*
X330257D01*
G02Y1612790I0J-1502D01*
G01X326857D01*
G02Y1615794I0J1502D01*
G37*
G36*
G01X249197Y1591596D02*
X252597D01*
G02Y1588592I0J-1502D01*
G01X249197D01*
G02Y1591596I0J1502D01*
G37*
G36*
G01X309497D02*
X312897D01*
G02Y1588592I0J-1502D01*
G01X309497D01*
G02Y1591596I0J1502D01*
G37*
G36*
G01X1564075Y1603882D02*
X1567475D01*
G02Y1600878I0J-1502D01*
G01X1564075D01*
G02Y1603882I0J1502D01*
G37*
G36*
G01Y1615794D02*
X1567475D01*
G02Y1612790I0J-1502D01*
G01X1564075D01*
G02Y1615794I0J1502D01*
G37*
G36*
G01X1552015D02*
X1555415D01*
G02Y1612790I0J-1502D01*
G01X1552015D01*
G02Y1615794I0J1502D01*
G37*
G36*
G01X1503775D02*
X1507175D01*
G02Y1612790I0J-1502D01*
G01X1503775D01*
G02Y1615794I0J1502D01*
G37*
G36*
G01X1552015Y1603882D02*
X1555415D01*
G02Y1600878I0J-1502D01*
G01X1552015D01*
G02Y1603882I0J1502D01*
G37*
G36*
G01X629831Y1591596D02*
X633231D01*
G02Y1588592I0J-1502D01*
G01X629831D01*
G02Y1591596I0J1502D01*
G37*
G36*
G01X1377672Y1579684D02*
X1381072D01*
G02Y1576680I0J-1502D01*
G01X1377672D01*
G02Y1579684I0J1502D01*
G37*
G36*
G01X218317Y1603882D02*
X221717D01*
G02Y1600878I0J-1502D01*
G01X218317D01*
G02Y1603882I0J1502D01*
G37*
G36*
G01X206257D02*
X209657D01*
G02Y1600878I0J-1502D01*
G01X206257D01*
G02Y1603882I0J1502D01*
G37*
G36*
G01X1527895Y1615794D02*
X1531295D01*
G02Y1612790I0J-1502D01*
G01X1527895D01*
G02Y1615794I0J1502D01*
G37*
G36*
G01X200957Y1591596D02*
X204357D01*
G02Y1588592I0J-1502D01*
G01X200957D01*
G02Y1591596I0J1502D01*
G37*
G36*
G01X1631135D02*
X1634535D01*
G02Y1588592I0J-1502D01*
G01X1631135D01*
G02Y1591596I0J1502D01*
G37*
G36*
G01X1539955Y1615794D02*
X1543355D01*
G02Y1612790I0J-1502D01*
G01X1539955D01*
G02Y1615794I0J1502D01*
G37*
G36*
G01Y1603882D02*
X1543355D01*
G02Y1600878I0J-1502D01*
G01X1539955D01*
G02Y1603882I0J1502D01*
G37*
G36*
G01X1527895D02*
X1531295D01*
G02Y1600878I0J-1502D01*
G01X1527895D01*
G02Y1603882I0J1502D01*
G37*
G36*
G01X302737Y1615794D02*
X306137D01*
G02Y1612790I0J-1502D01*
G01X302737D01*
G02Y1615794I0J1502D01*
G37*
G36*
G01X1522595Y1579684D02*
X1525995D01*
G02Y1576680I0J-1502D01*
G01X1522595D01*
G02Y1579684I0J1502D01*
G37*
G36*
G01X1515835Y1615794D02*
X1519235D01*
G02Y1612790I0J-1502D01*
G01X1515835D01*
G02Y1615794I0J1502D01*
G37*
G36*
G01X1636435D02*
X1639835D01*
G02Y1612790I0J-1502D01*
G01X1636435D01*
G02Y1615794I0J1502D01*
G37*
G36*
G01X1498475Y1591596D02*
X1501875D01*
G02Y1588592I0J-1502D01*
G01X1498475D01*
G02Y1591596I0J1502D01*
G37*
G36*
G01X1643195D02*
X1646595D01*
G02Y1588592I0J-1502D01*
G01X1643195D01*
G02Y1591596I0J1502D01*
G37*
G36*
G01X1515835Y1603882D02*
X1519235D01*
G02Y1600878I0J-1502D01*
G01X1515835D01*
G02Y1603882I0J1502D01*
G37*
G36*
G01X357737Y1591596D02*
X361137D01*
G02Y1588592I0J-1502D01*
G01X357737D01*
G02Y1591596I0J1502D01*
G37*
G36*
G01X194197Y1615794D02*
X197597D01*
G02Y1612790I0J-1502D01*
G01X194197D01*
G02Y1615794I0J1502D01*
G37*
G36*
G01X1510535Y1579684D02*
X1513935D01*
G02Y1576680I0J-1502D01*
G01X1510535D01*
G02Y1579684I0J1502D01*
G37*
G36*
G01X1570835Y1591596D02*
X1574235D01*
G02Y1588592I0J-1502D01*
G01X1570835D01*
G02Y1591596I0J1502D01*
G37*
G36*
G01X273317D02*
X276717D01*
G02Y1588592I0J-1502D01*
G01X273317D01*
G02Y1591596I0J1502D01*
G37*
G36*
G01Y1579684D02*
X276717D01*
G02Y1576680I0J-1502D01*
G01X273317D01*
G02Y1579684I0J1502D01*
G37*
G36*
G01X1491715Y1603882D02*
X1495115D01*
G02Y1600878I0J-1502D01*
G01X1491715D01*
G02Y1603882I0J1502D01*
G37*
G36*
G01Y1615794D02*
X1495115D01*
G02Y1612790I0J-1502D01*
G01X1491715D01*
G02Y1615794I0J1502D01*
G37*
G36*
G01X1631135Y1579684D02*
X1634535D01*
G02Y1576680I0J-1502D01*
G01X1631135D01*
G02Y1579684I0J1502D01*
G37*
G36*
G01X213017Y1591596D02*
X216417D01*
G02Y1588592I0J-1502D01*
G01X213017D01*
G02Y1591596I0J1502D01*
G37*
G36*
G01X188897Y1579684D02*
X192297D01*
G02Y1576680I0J-1502D01*
G01X188897D01*
G02Y1579684I0J1502D01*
G37*
G36*
G01X1503775Y1603882D02*
X1507175D01*
G02Y1600878I0J-1502D01*
G01X1503775D01*
G02Y1603882I0J1502D01*
G37*
G36*
G01X200957Y1579684D02*
X204357D01*
G02Y1576680I0J-1502D01*
G01X200957D01*
G02Y1579684I0J1502D01*
G37*
G36*
G01X605711D02*
X609111D01*
G02Y1576680I0J-1502D01*
G01X605711D01*
G02Y1579684I0J1502D01*
G37*
G36*
G01X1479655Y1603882D02*
X1483055D01*
G02Y1600878I0J-1502D01*
G01X1479655D01*
G02Y1603882I0J1502D01*
G37*
G36*
G01Y1615794D02*
X1483055D01*
G02Y1612790I0J-1502D01*
G01X1479655D01*
G02Y1615794I0J1502D01*
G37*
G36*
G01X249197Y1579684D02*
X252597D01*
G02Y1576680I0J-1502D01*
G01X249197D01*
G02Y1579684I0J1502D01*
G37*
G36*
G01X1467595Y1615794D02*
X1470995D01*
G02Y1612790I0J-1502D01*
G01X1467595D01*
G02Y1615794I0J1502D01*
G37*
G36*
G01Y1603882D02*
X1470995D01*
G02Y1600878I0J-1502D01*
G01X1467595D01*
G02Y1603882I0J1502D01*
G37*
G36*
G01X1558775Y1591596D02*
X1562175D01*
G02Y1588592I0J-1502D01*
G01X1558775D01*
G02Y1591596I0J1502D01*
G37*
G36*
G01X1643195Y1579684D02*
X1646595D01*
G02Y1576680I0J-1502D01*
G01X1643195D01*
G02Y1579684I0J1502D01*
G37*
G36*
G01X188897Y1591596D02*
X192297D01*
G02Y1588592I0J-1502D01*
G01X188897D01*
G02Y1591596I0J1502D01*
G37*
G36*
G01X1607015D02*
X1610415D01*
G02Y1588592I0J-1502D01*
G01X1607015D01*
G02Y1591596I0J1502D01*
G37*
G36*
G01X1582895D02*
X1586295D01*
G02Y1588592I0J-1502D01*
G01X1582895D01*
G02Y1591596I0J1502D01*
G37*
G36*
G01X225077Y1579684D02*
X228477D01*
G02Y1576680I0J-1502D01*
G01X225077D01*
G02Y1579684I0J1502D01*
G37*
G36*
G01Y1591596D02*
X228477D01*
G02Y1588592I0J-1502D01*
G01X225077D01*
G02Y1591596I0J1502D01*
G37*
G36*
G01X218317Y1615794D02*
X221717D01*
G02Y1612790I0J-1502D01*
G01X218317D01*
G02Y1615794I0J1502D01*
G37*
G36*
G01X290677Y1603882D02*
X294077D01*
G02Y1600878I0J-1502D01*
G01X290677D01*
G02Y1603882I0J1502D01*
G37*
G36*
G01Y1615794D02*
X294077D01*
G02Y1612790I0J-1502D01*
G01X290677D01*
G02Y1615794I0J1502D01*
G37*
G36*
G01X237137Y1579684D02*
X240537D01*
G02Y1576680I0J-1502D01*
G01X237137D01*
G02Y1579684I0J1502D01*
G37*
G36*
G01X213017D02*
X216417D01*
G02Y1576680I0J-1502D01*
G01X213017D01*
G02Y1579684I0J1502D01*
G37*
G36*
G01X230377Y1603882D02*
X233777D01*
G02Y1600878I0J-1502D01*
G01X230377D01*
G02Y1603882I0J1502D01*
G37*
G36*
G01X1619075Y1591596D02*
X1622475D01*
G02Y1588592I0J-1502D01*
G01X1619075D01*
G02Y1591596I0J1502D01*
G37*
G36*
G01X242437Y1615794D02*
X245837D01*
G02Y1612790I0J-1502D01*
G01X242437D01*
G02Y1615794I0J1502D01*
G37*
G36*
G01X369797Y1579684D02*
X373197D01*
G02Y1576680I0J-1502D01*
G01X369797D01*
G02Y1579684I0J1502D01*
G37*
G36*
G01X473051Y1591596D02*
X476451D01*
G02Y1588592I0J-1502D01*
G01X473051D01*
G02Y1591596I0J1502D01*
G37*
G36*
G01Y1579684D02*
X476451D01*
G02Y1576680I0J-1502D01*
G01X473051D01*
G02Y1579684I0J1502D01*
G37*
G36*
G01X1588195Y1603882D02*
X1591595D01*
G02Y1600878I0J-1502D01*
G01X1588195D01*
G02Y1603882I0J1502D01*
G37*
G36*
G01Y1615794D02*
X1591595D01*
G02Y1612790I0J-1502D01*
G01X1588195D01*
G02Y1615794I0J1502D01*
G37*
G36*
G01X61470Y86124D02*
X64870D01*
G02Y83120I0J-1502D01*
G01X61470D01*
G02Y86124I0J1502D01*
G37*
G36*
G01X297437Y1579684D02*
X300837D01*
G02Y1576680I0J-1502D01*
G01X297437D01*
G02Y1579684I0J1502D01*
G37*
G36*
G01X350977Y1615794D02*
X354377D01*
G02Y1612790I0J-1502D01*
G01X350977D01*
G02Y1615794I0J1502D01*
G37*
G36*
G01X375097Y1603882D02*
X378497D01*
G02Y1600878I0J-1502D01*
G01X375097D01*
G02Y1603882I0J1502D01*
G37*
G36*
G01Y1615794D02*
X378497D01*
G02Y1612790I0J-1502D01*
G01X375097D01*
G02Y1615794I0J1502D01*
G37*
G36*
G01X363037Y1603882D02*
X366437D01*
G02Y1600878I0J-1502D01*
G01X363037D01*
G02Y1603882I0J1502D01*
G37*
G36*
G01X1336674Y883423D02*
G02X1339268I1297J0D01*
G01Y883421D01*
G02X1339196Y882994I-1298J-1D01*
G01X1339166Y882908D01*
X1339972Y881511D01*
X1340062Y881494D01*
G02X1341118Y880219I-242J-1275D01*
G02X1338522I-1298J0D01*
G02X1338595Y880647I1299J-1D01*
G01X1338625Y880733D01*
X1337819Y882131D01*
X1337729Y882148D01*
G02X1336674Y883423I243J1275D01*
G37*
G36*
G01X353132D02*
G02X355726I1297J0D01*
G01Y883421D01*
G02X355654Y882994I-1298J-1D01*
G01X355624Y882908D01*
X356430Y881511D01*
X356520Y881494D01*
G02X357576Y880219I-242J-1275D01*
G02X354980I-1298J0D01*
G02X355053Y880647I1299J-1D01*
G01X355083Y880733D01*
X354277Y882131D01*
X354187Y882148D01*
G02X353132Y883423I243J1275D01*
G37*
G36*
G01X1329274D02*
G02X1331868I1297J0D01*
G01Y883421D01*
G02X1331796Y882994I-1298J-1D01*
G01X1331766Y882908D01*
X1332572Y881511D01*
X1332662Y881494D01*
G02X1333718Y880219I-242J-1275D01*
G02X1331122I-1298J0D01*
G02X1331195Y880647I1299J-1D01*
G01X1331225Y880733D01*
X1330419Y882131D01*
X1330329Y882148D01*
G02X1329274Y883423I243J1275D01*
G37*
G36*
G01X358680Y886625D02*
Y886627D01*
G02X361276I1298J0D01*
G02X360220Y885352I-1298J0D01*
G01X360130Y885335D01*
X359324Y883938D01*
X359354Y883852D01*
G02X359426Y883425I-1226J-426D01*
G01Y883423D01*
G02X356832I-1297J0D01*
G02X357887Y884698I1298J0D01*
G01X357977Y884715D01*
X358783Y886112D01*
X358753Y886198D01*
G02X358680Y886625I1225J429D01*
G37*
G36*
G01X366080D02*
Y886627D01*
G02X368676I1298J0D01*
G02X367620Y885352I-1298J0D01*
G01X367530Y885335D01*
X366724Y883938D01*
X366754Y883852D01*
G02X366826Y883425I-1226J-426D01*
G01Y883423D01*
G02X364232I-1297J0D01*
G02X365287Y884698I1298J0D01*
G01X365377Y884715D01*
X366183Y886112D01*
X366153Y886198D01*
G02X366080Y886625I1225J429D01*
G37*
G36*
G01X1330101Y541552D02*
X1333143D01*
G02Y538546I0J-1503D01*
G01X1330101D01*
G02Y541552I0J1503D01*
G37*
G36*
G01X360532Y883423D02*
G02X363126I1297J0D01*
G01Y883421D01*
G02X363054Y882994I-1298J-1D01*
G01X363024Y882908D01*
X363830Y881511D01*
X363920Y881494D01*
G02X364976Y880219I-242J-1275D01*
G02X362380I-1298J0D01*
G02X362453Y880647I1299J-1D01*
G01X362483Y880733D01*
X361677Y882131D01*
X361587Y882148D01*
G02X360532Y883423I243J1275D01*
G37*
G36*
G01X1334822Y886625D02*
Y886627D01*
G02X1337418I1298J0D01*
G02X1336362Y885352I-1298J0D01*
G01X1336272Y885335D01*
X1335466Y883938D01*
X1335496Y883852D01*
G02X1335568Y883425I-1226J-426D01*
G01Y883423D01*
G02X1332974I-1297J0D01*
G02X1334029Y884698I1298J0D01*
G01X1334119Y884715D01*
X1334925Y886112D01*
X1334895Y886198D01*
G02X1334822Y886625I1225J429D01*
G37*
G36*
G01X1342222D02*
Y886627D01*
G02X1344818I1298J0D01*
G02X1343762Y885352I-1298J0D01*
G01X1343672Y885335D01*
X1342866Y883938D01*
X1342896Y883852D01*
G02X1342968Y883425I-1226J-426D01*
G01Y883423D01*
G02X1340374I-1297J0D01*
G02X1341429Y884698I1298J0D01*
G01X1341519Y884715D01*
X1342325Y886112D01*
X1342295Y886198D01*
G02X1342222Y886625I1225J429D01*
G37*
G36*
G01X1358624Y283142D02*
X1355224D01*
G02Y286146I0J1502D01*
G01X1358624D01*
G02Y283142I0J-1502D01*
G37*
G36*
G01X1348084Y278756D02*
X1344684D01*
G02Y281762I0J1503D01*
G01X1348084D01*
G02Y278756I0J-1503D01*
G37*
G36*
G01X1368524Y281242D02*
X1365124D01*
G02Y284246I0J1502D01*
G01X1368524D01*
G02Y281242I0J-1502D01*
G37*
G36*
G01X1328480Y322400D02*
X1325080D01*
G02Y325404I0J1502D01*
G01X1328480D01*
G02Y322400I0J-1502D01*
G37*
G36*
G01X613970Y190254D02*
X617370D01*
G02Y187250I0J-1502D01*
G01X613970D01*
G02Y190254I0J1502D01*
G37*
G36*
G01X64571Y427304D02*
X61171D01*
G02Y430308I0J1502D01*
G01X64571D01*
G02Y427304I0J-1502D01*
G37*
G36*
G01X626640Y190254D02*
X630040D01*
G02Y187250I0J-1502D01*
G01X626640D01*
G02Y190254I0J1502D01*
G37*
G36*
G01X423180Y1601300D02*
X419780D01*
G02Y1604304I0J1502D01*
G01X423180D01*
G02Y1601300I0J-1502D01*
G37*
G36*
G01X49360Y427304D02*
X45960D01*
G02Y430308I0J1502D01*
G01X49360D01*
G02Y427304I0J-1502D01*
G37*
G36*
G01X1400985Y242432D02*
X1404385D01*
G02Y239426I0J-1503D01*
G01X1400985D01*
G02Y242432I0J1503D01*
G37*
G36*
G01X930731Y531982D02*
X933773D01*
G02Y528976I0J-1503D01*
G01X930731D01*
G02Y531982I0J1503D01*
G37*
G36*
G01X285377Y1591596D02*
X288777D01*
G02Y1588592I0J-1502D01*
G01X285377D01*
G02Y1591596I0J1502D01*
G37*
G36*
G01X229131Y49144D02*
X225731D01*
G02Y52148I0J1502D01*
G01X229131D01*
G02Y49144I0J-1502D01*
G37*
G36*
G01X284230D02*
X280830D01*
G02Y52148I0J1502D01*
G01X284230D01*
G02Y49144I0J-1502D01*
G37*
G36*
G01X1755272Y27934D02*
X1758672D01*
G02Y24928I0J-1503D01*
G01X1755272D01*
G02Y27934I0J1503D01*
G37*
G36*
G01X1530660Y101664D02*
X1534060D01*
G02Y98660I0J-1502D01*
G01X1530660D01*
G02Y101664I0J1502D01*
G37*
G36*
G01X1549308Y27934D02*
X1552708D01*
G02Y24928I0J-1503D01*
G01X1549308D01*
G02Y27934I0J1503D01*
G37*
G36*
G01X1556413Y20998D02*
X1559813D01*
G02Y17992I0J-1503D01*
G01X1556413D01*
G02Y20998I0J1503D01*
G37*
G36*
G01X1563481Y27934D02*
X1566881D01*
G02Y24928I0J-1503D01*
G01X1563481D01*
G02Y27934I0J1503D01*
G37*
G36*
G01X1570586Y20998D02*
X1573986D01*
G02Y17992I0J-1503D01*
G01X1570586D01*
G02Y20998I0J1503D01*
G37*
G36*
G01X1577654Y27934D02*
X1581054D01*
G02Y24928I0J-1503D01*
G01X1577654D01*
G02Y27934I0J1503D01*
G37*
G36*
G01X1584759Y20998D02*
X1588159D01*
G02Y17992I0J-1503D01*
G01X1584759D01*
G02Y20998I0J1503D01*
G37*
G36*
G01X1591828Y27934D02*
X1595228D01*
G02Y24928I0J-1503D01*
G01X1591828D01*
G02Y27934I0J1503D01*
G37*
G36*
G01X1598933Y20998D02*
X1602333D01*
G02Y17992I0J-1503D01*
G01X1598933D01*
G02Y20998I0J1503D01*
G37*
G36*
G01X1627694Y27934D02*
X1631094D01*
G02Y24928I0J-1503D01*
G01X1627694D01*
G02Y27934I0J1503D01*
G37*
G36*
G01X1634799Y20998D02*
X1638199D01*
G02Y17992I0J-1503D01*
G01X1634799D01*
G02Y20998I0J1503D01*
G37*
G36*
G01X218667Y21040D02*
X222067D01*
G02Y18036I0J-1502D01*
G01X218667D01*
G02Y21040I0J1502D01*
G37*
G36*
G01X211562Y27976D02*
X214962D01*
G02Y24972I0J-1502D01*
G01X211562D01*
G02Y27976I0J1502D01*
G37*
G36*
G01X204494Y21040D02*
X207894D01*
G02Y18036I0J-1502D01*
G01X204494D01*
G02Y21040I0J1502D01*
G37*
G36*
G01X197389Y27976D02*
X200789D01*
G02Y24972I0J-1502D01*
G01X197389D01*
G02Y27976I0J1502D01*
G37*
G36*
G01X167428D02*
X170828D01*
G02Y24972I0J-1502D01*
G01X167428D01*
G02Y27976I0J1502D01*
G37*
G36*
G01X174533Y21040D02*
X177933D01*
G02Y18036I0J-1502D01*
G01X174533D01*
G02Y21040I0J1502D01*
G37*
G36*
G01X153255Y27976D02*
X156655D01*
G02Y24972I0J-1502D01*
G01X153255D01*
G02Y27976I0J1502D01*
G37*
G36*
G01X160360Y21040D02*
X163760D01*
G02Y18036I0J-1502D01*
G01X160360D01*
G02Y21040I0J1502D01*
G37*
G36*
G01X124494D02*
X127894D01*
G02Y18036I0J-1502D01*
G01X124494D01*
G02Y21040I0J1502D01*
G37*
G36*
G01X117389Y27976D02*
X120789D01*
G02Y24972I0J-1502D01*
G01X117389D01*
G02Y27976I0J1502D01*
G37*
G36*
G01X103215D02*
X106615D01*
G02Y24972I0J-1502D01*
G01X103215D01*
G02Y27976I0J1502D01*
G37*
G36*
G01X110320Y21040D02*
X113720D01*
G02Y18036I0J-1502D01*
G01X110320D01*
G02Y21040I0J1502D01*
G37*
G36*
G01X89042Y27976D02*
X92442D01*
G02Y24972I0J-1502D01*
G01X89042D01*
G02Y27976I0J1502D01*
G37*
G36*
G01X96147Y21040D02*
X99547D01*
G02Y18036I0J-1502D01*
G01X96147D01*
G02Y21040I0J1502D01*
G37*
G36*
G01X74869Y27976D02*
X78269D01*
G02Y24972I0J-1502D01*
G01X74869D01*
G02Y27976I0J1502D01*
G37*
G36*
G01X81974Y21040D02*
X85374D01*
G02Y18036I0J-1502D01*
G01X81974D01*
G02Y21040I0J1502D01*
G37*
G36*
G01X1641867Y27934D02*
X1645267D01*
G02Y24928I0J-1503D01*
G01X1641867D01*
G02Y27934I0J1503D01*
G37*
G36*
G01X1648972Y20998D02*
X1652372D01*
G02Y17992I0J-1503D01*
G01X1648972D01*
G02Y20998I0J1503D01*
G37*
G36*
G01X1671828Y27934D02*
X1675228D01*
G02Y24928I0J-1503D01*
G01X1671828D01*
G02Y27934I0J1503D01*
G37*
G36*
G01X1678933Y20998D02*
X1682333D01*
G02Y17992I0J-1503D01*
G01X1678933D01*
G02Y20998I0J1503D01*
G37*
G36*
G01X1686001Y27934D02*
X1689401D01*
G02Y24928I0J-1503D01*
G01X1686001D01*
G02Y27934I0J1503D01*
G37*
G36*
G01X1693106Y20998D02*
X1696506D01*
G02Y17992I0J-1503D01*
G01X1693106D01*
G02Y20998I0J1503D01*
G37*
G36*
G01X1700217Y27962D02*
X1703617D01*
G02Y24956I0J-1503D01*
G01X1700217D01*
G02Y27962I0J1503D01*
G37*
G36*
G01X1700170Y52152D02*
X1703570D01*
G02Y49146I0J-1503D01*
G01X1700170D01*
G02Y52152I0J1503D01*
G37*
G36*
G01X670612Y48766D02*
X674012D01*
G02Y45762I0J-1502D01*
G01X670612D01*
G02Y48766I0J1502D01*
G37*
G36*
G01X284233Y24972D02*
X280833D01*
G02Y27976I0J1502D01*
G01X284233D01*
G02Y24972I0J-1502D01*
G37*
G36*
G01X1307442Y305496D02*
X1304042D01*
G02Y308500I0J1502D01*
G01X1307442D01*
G02Y305496I0J-1502D01*
G37*
G36*
G01X1382972Y1603882D02*
X1386372D01*
G02Y1600878I0J-1502D01*
G01X1382972D01*
G02Y1603882I0J1502D01*
G37*
G36*
G01Y1615794D02*
X1386372D01*
G02Y1612790I0J-1502D01*
G01X1382972D01*
G02Y1615794I0J1502D01*
G37*
G36*
G01X229135Y24972D02*
X225735D01*
G02Y27976I0J1502D01*
G01X229135D01*
G02Y24972I0J-1502D01*
G37*
G36*
G01X350977Y1603882D02*
X354377D01*
G02Y1600878I0J-1502D01*
G01X350977D01*
G02Y1603882I0J1502D01*
G37*
G36*
G01X1307042Y291134D02*
X1303642D01*
G02Y294138I0J1502D01*
G01X1307042D01*
G02Y291134I0J-1502D01*
G37*
G36*
G01X405990Y1617450D02*
X402590D01*
G02Y1620454I0J1502D01*
G01X405990D01*
G02Y1617450I0J-1502D01*
G37*
G36*
G01X441740Y1650764D02*
X438340D01*
G02Y1653768I0J1502D01*
G01X441740D01*
G02Y1650764I0J-1502D01*
G37*
G36*
G01X49212Y450100D02*
X45812D01*
G02Y453104I0J1502D01*
G01X49212D01*
G02Y450100I0J-1502D01*
G37*
G36*
G01X1418630Y221520D02*
X1422030D01*
G02Y218516I0J-1502D01*
G01X1418630D01*
G02Y221520I0J1502D01*
G37*
G36*
G01X1407420D02*
X1410820D01*
G02Y218516I0J-1502D01*
G01X1407420D01*
G02Y221520I0J1502D01*
G37*
G36*
G01X1432660D02*
X1436060D01*
G02Y218516I0J-1502D01*
G01X1432660D01*
G02Y221520I0J1502D01*
G37*
G36*
G01X862930Y71574D02*
X866330D01*
G02Y68570I0J-1502D01*
G01X862930D01*
G02Y71574I0J1502D01*
G37*
G36*
G01X1348824Y327478D02*
X1345424D01*
G02Y330484I0J1503D01*
G01X1348824D01*
G02Y327478I0J-1503D01*
G37*
G36*
G01X1341431Y321190D02*
X1338031D01*
G02Y324196I0J1503D01*
G01X1341431D01*
G02Y321190I0J-1503D01*
G37*
G36*
G01X1335145Y331114D02*
X1331745D01*
G02Y334118I0J1502D01*
G01X1335145D01*
G02Y331114I0J-1502D01*
G37*
G36*
G01X1319618Y316570D02*
X1316218D01*
G02Y319576I0J1503D01*
G01X1319618D01*
G02Y316570I0J-1503D01*
G37*
G36*
G01X1311077Y321494D02*
X1307677D01*
G02Y324498I0J1502D01*
G01X1311077D01*
G02Y321494I0J-1502D01*
G37*
G36*
G01X1380602Y199170D02*
X1384002D01*
G02Y196166I0J-1502D01*
G01X1380602D01*
G02Y199170I0J1502D01*
G37*
G36*
G01X1398006D02*
X1401406D01*
G02Y196166I0J-1502D01*
G01X1398006D01*
G02Y199170I0J1502D01*
G37*
G36*
G01X1373591Y177932D02*
X1376991D01*
G02Y174928I0J-1502D01*
G01X1373591D01*
G02Y177932I0J1502D01*
G37*
G36*
G01X1169820Y637554D02*
X1173220D01*
G02Y634550I0J-1502D01*
G01X1169820D01*
G02Y637554I0J1502D01*
G37*
G36*
G01X519764Y41830D02*
X523164D01*
G02Y38826I0J-1502D01*
G01X519764D01*
G02Y41830I0J1502D01*
G37*
G36*
G01X732793Y72938D02*
X736193D01*
G02Y69934I0J-1502D01*
G01X732793D01*
G02Y72938I0J1502D01*
G37*
G36*
G01X1161860Y643614D02*
X1165260D01*
G02Y640610I0J-1502D01*
G01X1161860D01*
G02Y643614I0J1502D01*
G37*
G36*
G01X663543Y44830D02*
X666943D01*
G02Y41826I0J-1502D01*
G01X663543D01*
G02Y44830I0J1502D01*
G37*
G36*
G01X656439Y48766D02*
X659839D01*
G02Y45762I0J-1502D01*
G01X656439D01*
G02Y48766I0J1502D01*
G37*
G36*
G01X562771Y1603882D02*
X566171D01*
G02Y1600878I0J-1502D01*
G01X562771D01*
G02Y1603882I0J1502D01*
G37*
G36*
G01X538651D02*
X542051D01*
G02Y1600878I0J-1502D01*
G01X538651D01*
G02Y1603882I0J1502D01*
G37*
G36*
G01X1406970Y140244D02*
X1410370D01*
G02Y137240I0J-1502D01*
G01X1406970D01*
G02Y140244I0J1502D01*
G37*
G36*
G01X1323303Y297674D02*
X1319903D01*
G02Y300678I0J1502D01*
G01X1323303D01*
G02Y297674I0J-1502D01*
G37*
G36*
G01X1361771Y330772D02*
X1358371D01*
G02Y333778I0J1503D01*
G01X1361771D01*
G02Y330772I0J-1503D01*
G37*
G36*
G01X555175Y72938D02*
X558575D01*
G02Y69934I0J-1502D01*
G01X555175D01*
G02Y72938I0J1502D01*
G37*
G36*
G01X541002D02*
X544402D01*
G02Y69934I0J-1502D01*
G01X541002D01*
G02Y72938I0J1502D01*
G37*
G36*
G01X519742D02*
X523142D01*
G02Y69934I0J-1502D01*
G01X519742D01*
G02Y72938I0J1502D01*
G37*
G36*
G01X533915Y61324D02*
X537315D01*
G02Y58320I0J-1502D01*
G01X533915D01*
G02Y61324I0J1502D01*
G37*
G36*
G01X1294500Y298190D02*
X1291100D01*
G02Y301194I0J1502D01*
G01X1294500D01*
G02Y298190I0J-1502D01*
G37*
G36*
G01X1404829Y185766D02*
X1408229D01*
G02Y182760I0J-1503D01*
G01X1404829D01*
G02Y185766I0J1503D01*
G37*
G36*
G01X538651Y1615794D02*
X542051D01*
G02Y1612790I0J-1502D01*
G01X538651D01*
G02Y1615794I0J1502D01*
G37*
G36*
G01X526591Y1603882D02*
X529991D01*
G02Y1600878I0J-1502D01*
G01X526591D01*
G02Y1603882I0J1502D01*
G37*
G36*
G01X514531D02*
X517931D01*
G02Y1600878I0J-1502D01*
G01X514531D01*
G02Y1603882I0J1502D01*
G37*
G36*
G01X526591Y1615794D02*
X529991D01*
G02Y1612790I0J-1502D01*
G01X526591D01*
G02Y1615794I0J1502D01*
G37*
G36*
G01X514531D02*
X517931D01*
G02Y1612790I0J-1502D01*
G01X514531D01*
G02Y1615794I0J1502D01*
G37*
G36*
G01X490411Y1603882D02*
X493811D01*
G02Y1600878I0J-1502D01*
G01X490411D01*
G02Y1603882I0J1502D01*
G37*
G36*
G01X478351Y1615794D02*
X481751D01*
G02Y1612790I0J-1502D01*
G01X478351D01*
G02Y1615794I0J1502D01*
G37*
G36*
G01X502471D02*
X505871D01*
G02Y1612790I0J-1502D01*
G01X502471D01*
G02Y1615794I0J1502D01*
G37*
G36*
G01X478351Y1603882D02*
X481751D01*
G02Y1600878I0J-1502D01*
G01X478351D01*
G02Y1603882I0J1502D01*
G37*
G36*
G01X1412284Y173198D02*
X1415684D01*
G02Y170194I0J-1502D01*
G01X1412284D01*
G02Y173198I0J1502D01*
G37*
G36*
G01X598951Y1603882D02*
X602351D01*
G02Y1600878I0J-1502D01*
G01X598951D01*
G02Y1603882I0J1502D01*
G37*
G36*
G01Y1615794D02*
X602351D01*
G02Y1612790I0J-1502D01*
G01X598951D01*
G02Y1615794I0J1502D01*
G37*
G36*
G01X586891Y1603882D02*
X590291D01*
G02Y1600878I0J-1502D01*
G01X586891D01*
G02Y1603882I0J1502D01*
G37*
G36*
G01X647191D02*
X650591D01*
G02Y1600878I0J-1502D01*
G01X647191D01*
G02Y1603882I0J1502D01*
G37*
G36*
G01X635131Y1615794D02*
X638531D01*
G02Y1612790I0J-1502D01*
G01X635131D01*
G02Y1615794I0J1502D01*
G37*
G36*
G01X647191D02*
X650591D01*
G02Y1612790I0J-1502D01*
G01X647191D01*
G02Y1615794I0J1502D01*
G37*
G36*
G01X623071D02*
X626471D01*
G02Y1612790I0J-1502D01*
G01X623071D01*
G02Y1615794I0J1502D01*
G37*
G36*
G01X1355200Y336340D02*
X1351800D01*
G02Y339346I0J1503D01*
G01X1355200D01*
G02Y336340I0J-1503D01*
G37*
G36*
G01X1328814Y292054D02*
X1325414D01*
G02Y295058I0J1502D01*
G01X1328814D01*
G02Y292054I0J-1502D01*
G37*
G36*
G01X1340161Y291902D02*
X1336761D01*
G02Y294906I0J1502D01*
G01X1340161D01*
G02Y291902I0J-1502D01*
G37*
G36*
G01X1413950Y185766D02*
X1417350D01*
G02Y182760I0J-1503D01*
G01X1413950D01*
G02Y185766I0J1503D01*
G37*
G36*
G01X1423110D02*
X1426510D01*
G02Y182760I0J-1503D01*
G01X1423110D01*
G02Y185766I0J1503D01*
G37*
G36*
G01X1401341Y178662D02*
X1404741D01*
G02Y175656I0J-1503D01*
G01X1401341D01*
G02Y178662I0J1503D01*
G37*
G36*
G01X1403778Y173186D02*
X1407178D01*
G02Y170182I0J-1502D01*
G01X1403778D01*
G02Y173186I0J1502D01*
G37*
G36*
G01X1389256Y199170D02*
X1392656D01*
G02Y196166I0J-1502D01*
G01X1389256D01*
G02Y199170I0J1502D01*
G37*
G36*
G01X550711Y1603882D02*
X554111D01*
G02Y1600878I0J-1502D01*
G01X550711D01*
G02Y1603882I0J1502D01*
G37*
G36*
G01X502471D02*
X505871D01*
G02Y1600878I0J-1502D01*
G01X502471D01*
G02Y1603882I0J1502D01*
G37*
G36*
G01X490411Y1615794D02*
X493811D01*
G02Y1612790I0J-1502D01*
G01X490411D01*
G02Y1615794I0J1502D01*
G37*
G36*
G01X987440Y432696D02*
X990840D01*
G02Y429690I0J-1503D01*
G01X987440D01*
G02Y432696I0J1503D01*
G37*
G36*
G01X1471460Y631900D02*
X1468060D01*
G02Y634904I0J1502D01*
G01X1471460D01*
G02Y631900I0J-1502D01*
G37*
G36*
G01X934047Y459364D02*
X937447D01*
G02Y456360I0J-1502D01*
G01X934047D01*
G02Y459364I0J1502D01*
G37*
G36*
G01X942047Y464514D02*
X945447D01*
G02Y461510I0J-1502D01*
G01X942047D01*
G02Y464514I0J1502D01*
G37*
G36*
G01X550711Y1615794D02*
X554111D01*
G02Y1612790I0J-1502D01*
G01X550711D01*
G02Y1615794I0J1502D01*
G37*
G36*
G01X635131Y1603882D02*
X638531D01*
G02Y1600878I0J-1502D01*
G01X635131D01*
G02Y1603882I0J1502D01*
G37*
G36*
G01X909584Y459638D02*
X912984D01*
G02Y456632I0J-1503D01*
G01X909584D01*
G02Y459638I0J1503D01*
G37*
G36*
G01X913394Y523164D02*
X916794D01*
G02Y520160I0J-1502D01*
G01X913394D01*
G02Y523164I0J1502D01*
G37*
G36*
G01X574831Y1603882D02*
X578231D01*
G02Y1600878I0J-1502D01*
G01X574831D01*
G02Y1603882I0J1502D01*
G37*
G36*
G01X659251D02*
X662651D01*
G02Y1600878I0J-1502D01*
G01X659251D01*
G02Y1603882I0J1502D01*
G37*
G36*
G01X1153370Y639694D02*
X1156770D01*
G02Y636690I0J-1502D01*
G01X1153370D01*
G02Y639694I0J1502D01*
G37*
G36*
G01X1406786Y199170D02*
X1410186D01*
G02Y196166I0J-1502D01*
G01X1406786D01*
G02Y199170I0J1502D01*
G37*
G36*
G01X611011Y1615794D02*
X614411D01*
G02Y1612790I0J-1502D01*
G01X611011D01*
G02Y1615794I0J1502D01*
G37*
G36*
G01X1312136Y283446D02*
X1308736D01*
G02Y286450I0J1502D01*
G01X1312136D01*
G02Y283446I0J-1502D01*
G37*
G36*
G01X611011Y1603882D02*
X614411D01*
G02Y1600878I0J-1502D01*
G01X611011D01*
G02Y1603882I0J1502D01*
G37*
G36*
G01X586891Y1615794D02*
X590291D01*
G02Y1612790I0J-1502D01*
G01X586891D01*
G02Y1615794I0J1502D01*
G37*
G36*
G01X659251D02*
X662651D01*
G02Y1612790I0J-1502D01*
G01X659251D01*
G02Y1615794I0J1502D01*
G37*
G36*
G01X574831D02*
X578231D01*
G02Y1612790I0J-1502D01*
G01X574831D01*
G02Y1615794I0J1502D01*
G37*
G36*
G01X1183360Y643564D02*
X1186760D01*
G02Y640560I0J-1502D01*
G01X1183360D01*
G02Y643564I0J1502D01*
G37*
G36*
G01X562771Y1615794D02*
X566171D01*
G02Y1612790I0J-1502D01*
G01X562771D01*
G02Y1615794I0J1502D01*
G37*
G36*
G01X901230Y533114D02*
X904630D01*
G02Y530110I0J-1502D01*
G01X901230D01*
G02Y533114I0J1502D01*
G37*
G36*
G01X954390Y529098D02*
X957790D01*
G02Y526094I0J-1502D01*
G01X954390D01*
G02Y529098I0J1502D01*
G37*
G36*
G01X963930Y534864D02*
X967330D01*
G02Y531860I0J-1502D01*
G01X963930D01*
G02Y534864I0J1502D01*
G37*
G36*
G01X548070Y80874D02*
X551470D01*
G02Y77870I0J-1502D01*
G01X548070D01*
G02Y80874I0J1502D01*
G37*
G36*
G01X623071Y1603882D02*
X626471D01*
G02Y1600878I0J-1502D01*
G01X623071D01*
G02Y1603882I0J1502D01*
G37*
G36*
G01X888130Y534114D02*
X891530D01*
G02Y531110I0J-1502D01*
G01X888130D01*
G02Y534114I0J1502D01*
G37*
G36*
G01X297437Y1591596D02*
X300837D01*
G02Y1588592I0J-1502D01*
G01X297437D01*
G02Y1591596I0J1502D01*
G37*
G36*
G01X237137D02*
X240537D01*
G02Y1588592I0J-1502D01*
G01X237137D01*
G02Y1591596I0J1502D01*
G37*
G36*
G01X937340Y309612D02*
X920138D01*
G02X937340I8601J12041D01*
G37*
G36*
G01X921047Y464514D02*
X924447D01*
G02Y461510I0J-1502D01*
G01X921047D01*
G02Y464514I0J1502D01*
G37*
G36*
G01X371587Y173422D02*
X365287D01*
G02Y197050I0J11814D01*
G01X371587D01*
G02Y173422I0J-11814D01*
G37*
G36*
G01X253477D02*
X247176D01*
G02X247175Y197050I0J11814D01*
G01X253476D01*
G02X253477Y173422I0J-11814D01*
G37*
G36*
G01X1012861Y434390D02*
X1016261D01*
G02Y431386I0J-1502D01*
G01X1012861D01*
G02Y434390I0J1502D01*
G37*
G36*
G01X50772Y120610D02*
X55372Y124913D01*
G02X66448Y113076I5538J-5919D01*
G01X61848Y108773D01*
G02X50772Y120610I-5538J5918D01*
G37*
G36*
G01X62587Y23395D02*
G02X58024Y17311I-2280J-3043D01*
G02X62587Y23395I2279J3044D01*
G37*
G36*
G01X443227Y845968D02*
G02X444266Y845448I0J-1298D01*
G01X445888D01*
G02X446927Y845968I1039J-778D01*
G02Y843374I0J-1297D01*
G02X445888Y843894I0J1298D01*
G01X444266D01*
G02X443227Y843374I-1039J778D01*
G02Y845968I0J1297D01*
G37*
G36*
G01X356830Y844971D02*
G02X359424I1297J0D01*
G02X358362Y843695I-1298J0D01*
G01X358267Y843677D01*
X357426Y842082D01*
X357465Y841994D01*
G02X357576Y841467I-1186J-525D01*
G02X354982I-1297J0D01*
G02X356044Y842743I1298J0D01*
G01X356139Y842761D01*
X356980Y844356D01*
X356941Y844444D01*
G02X356830Y844971I1186J525D01*
G37*
G36*
G01X364230D02*
G02X366824I1297J0D01*
G02X365762Y843695I-1298J0D01*
G01X365667Y843677D01*
X364826Y842082D01*
X364865Y841994D01*
G02X364976Y841467I-1186J-525D01*
G02X362382I-1297J0D01*
G02X363444Y842743I1298J0D01*
G01X363539Y842761D01*
X364380Y844356D01*
X364341Y844444D01*
G02X364230Y844971I1186J525D01*
G37*
G36*
G01X371630D02*
G02X374224I1297J0D01*
G02X373162Y843695I-1298J0D01*
G01X373067Y843677D01*
X372226Y842082D01*
X372265Y841994D01*
G02X372376Y841467I-1186J-525D01*
G02X369782I-1297J0D01*
G02X370844Y842743I1298J0D01*
G01X370939Y842761D01*
X371780Y844356D01*
X371741Y844444D01*
G02X371630Y844971I1186J525D01*
G37*
G36*
G01X379030D02*
G02X381624I1297J0D01*
G02X380562Y843695I-1298J0D01*
G01X380467Y843677D01*
X379626Y842082D01*
X379665Y841994D01*
G02X379776Y841467I-1186J-525D01*
G02X377182I-1297J0D01*
G02X378244Y842743I1298J0D01*
G01X378339Y842761D01*
X379180Y844356D01*
X379141Y844444D01*
G02X379030Y844971I1186J525D01*
G37*
G36*
G01X386430D02*
G02X389024I1297J0D01*
G02X387962Y843695I-1298J0D01*
G01X387867Y843677D01*
X387026Y842082D01*
X387065Y841994D01*
G02X387176Y841467I-1186J-525D01*
G02X384582I-1297J0D01*
G02X385644Y842743I1298J0D01*
G01X385739Y842761D01*
X386580Y844356D01*
X386541Y844444D01*
G02X386430Y844971I1186J525D01*
G37*
G36*
G01X393830D02*
G02X396424I1297J0D01*
G02X395362Y843695I-1298J0D01*
G01X395267Y843677D01*
X394426Y842082D01*
X394465Y841994D01*
G02X394576Y841467I-1186J-525D01*
G02X391982I-1297J0D01*
G02X393044Y842743I1298J0D01*
G01X393139Y842761D01*
X393980Y844356D01*
X393941Y844444D01*
G02X393830Y844971I1186J525D01*
G37*
G36*
G01X401230D02*
G02X403824I1297J0D01*
G02X402762Y843695I-1298J0D01*
G01X402667Y843677D01*
X401826Y842082D01*
X401865Y841994D01*
G02X401976Y841467I-1186J-525D01*
G02X399382I-1297J0D01*
G02X400444Y842743I1298J0D01*
G01X400539Y842761D01*
X401380Y844356D01*
X401341Y844444D01*
G02X401230Y844971I1186J525D01*
G37*
G36*
G01X408630D02*
G02X411224I1297J0D01*
G02X410162Y843695I-1298J0D01*
G01X410067Y843677D01*
X409226Y842082D01*
X409265Y841994D01*
G02X409376Y841467I-1186J-525D01*
G02X406782I-1297J0D01*
G02X407844Y842743I1298J0D01*
G01X407939Y842761D01*
X408780Y844356D01*
X408741Y844444D01*
G02X408630Y844971I1186J525D01*
G37*
G36*
G01X416030D02*
G02X418624I1297J0D01*
G02X417562Y843695I-1298J0D01*
G01X417467Y843677D01*
X416626Y842082D01*
X416665Y841994D01*
G02X416776Y841467I-1186J-525D01*
G02X414182I-1297J0D01*
G02X415244Y842743I1298J0D01*
G01X415339Y842761D01*
X416180Y844356D01*
X416141Y844444D01*
G02X416030Y844971I1186J525D01*
G37*
G36*
G01X423430D02*
G02X426024I1297J0D01*
G02X424962Y843695I-1298J0D01*
G01X424867Y843677D01*
X424026Y842082D01*
X424065Y841994D01*
G02X424176Y841467I-1186J-525D01*
G02X421582I-1297J0D01*
G02X422644Y842743I1298J0D01*
G01X422739Y842761D01*
X423580Y844356D01*
X423541Y844444D01*
G02X423430Y844971I1186J525D01*
G37*
G36*
G01X453030D02*
G02X455624I1297J0D01*
G02X454562Y843695I-1298J0D01*
G01X454467Y843677D01*
X453626Y842082D01*
X453665Y841994D01*
G02X453776Y841467I-1186J-525D01*
G02X451182I-1297J0D01*
G02X452244Y842743I1298J0D01*
G01X452339Y842761D01*
X453180Y844356D01*
X453141Y844444D01*
G02X453030Y844971I1186J525D01*
G37*
G36*
G01X460430D02*
G02X463024I1297J0D01*
G02X461962Y843695I-1298J0D01*
G01X461867Y843677D01*
X461026Y842082D01*
X461065Y841994D01*
G02X461176Y841467I-1186J-525D01*
G02X458582I-1297J0D01*
G02X459644Y842743I1298J0D01*
G01X459739Y842761D01*
X460580Y844356D01*
X460541Y844444D01*
G02X460430Y844971I1186J525D01*
G37*
G36*
G01X467830D02*
G02X470424I1297J0D01*
G02X469362Y843695I-1298J0D01*
G01X469267Y843677D01*
X468426Y842082D01*
X468465Y841994D01*
G02X468576Y841467I-1186J-525D01*
G02X465982I-1297J0D01*
G02X467044Y842743I1298J0D01*
G01X467139Y842761D01*
X467980Y844356D01*
X467941Y844444D01*
G02X467830Y844971I1186J525D01*
G37*
G36*
G01X475230D02*
G02X477824I1297J0D01*
G02X476762Y843695I-1298J0D01*
G01X476667Y843677D01*
X475826Y842082D01*
X475865Y841994D01*
G02X475976Y841467I-1186J-525D01*
G02X473382I-1297J0D01*
G02X474444Y842743I1298J0D01*
G01X474539Y842761D01*
X475380Y844356D01*
X475341Y844444D01*
G02X475230Y844971I1186J525D01*
G37*
G36*
G01X482630D02*
G02X485224I1297J0D01*
G02X484162Y843695I-1298J0D01*
G01X484067Y843677D01*
X483226Y842082D01*
X483265Y841994D01*
G02X483376Y841467I-1186J-525D01*
G02X480782I-1297J0D01*
G02X481844Y842743I1298J0D01*
G01X481939Y842761D01*
X482780Y844356D01*
X482741Y844444D01*
G02X482630Y844971I1186J525D01*
G37*
G36*
G01X490030D02*
G02X492624I1297J0D01*
G02X491519Y843688I-1297J0D01*
G01X491418Y843673D01*
X490608Y842112D01*
X490651Y842023D01*
G02X490776Y841467I-1174J-556D01*
G02X488180I-1298J0D01*
G02X489315Y842754I1297J0D01*
G01X489420Y842767D01*
X490213Y844297D01*
X490168Y844389D01*
G02X490030Y844971I1158J582D01*
G37*
G36*
G01X497430D02*
G02X500024I1297J0D01*
G02X498962Y843695I-1298J0D01*
G01X498867Y843677D01*
X498025Y842081D01*
X498064Y841993D01*
G02X498176Y841467I-1186J-527D01*
G02X495580I-1298J0D01*
G02X496644Y842743I1297J0D01*
G01X496739Y842761D01*
X497580Y844356D01*
X497541Y844444D01*
G02X497430Y844971I1186J525D01*
G37*
G36*
G01X504830D02*
G02X507424I1297J0D01*
G02X506362Y843695I-1298J0D01*
G01X506267Y843677D01*
X505426Y842082D01*
X505465Y841994D01*
G02X505576Y841467I-1186J-525D01*
G02X502982I-1297J0D01*
G02X504044Y842743I1298J0D01*
G01X504139Y842761D01*
X504980Y844356D01*
X504941Y844444D01*
G02X504830Y844971I1186J525D01*
G37*
G36*
G01X512230D02*
G02X514824I1297J0D01*
G02X513762Y843695I-1298J0D01*
G01X513667Y843677D01*
X512826Y842082D01*
X512865Y841994D01*
G02X512976Y841467I-1186J-525D01*
G02X510382I-1297J0D01*
G02X511444Y842743I1298J0D01*
G01X511539Y842761D01*
X512380Y844356D01*
X512341Y844444D01*
G02X512230Y844971I1186J525D01*
G37*
G36*
G01X519630D02*
G02X522224I1297J0D01*
G02X521162Y843695I-1298J0D01*
G01X521067Y843677D01*
X520226Y842082D01*
X520265Y841994D01*
G02X520376Y841467I-1186J-525D01*
G02X517782I-1297J0D01*
G02X518844Y842743I1298J0D01*
G01X518939Y842761D01*
X519780Y844356D01*
X519741Y844444D01*
G02X519630Y844971I1186J525D01*
G37*
G36*
G01X1332972D02*
G02X1335566I1297J0D01*
G02X1334504Y843695I-1298J0D01*
G01X1334409Y843677D01*
X1333568Y842082D01*
X1333607Y841994D01*
G02X1333718Y841467I-1186J-525D01*
G02X1331124I-1297J0D01*
G02X1332186Y842743I1298J0D01*
G01X1332281Y842761D01*
X1333122Y844356D01*
X1333083Y844444D01*
G02X1332972Y844971I1186J525D01*
G37*
G36*
G01X1340372D02*
G02X1342966I1297J0D01*
G02X1341904Y843695I-1298J0D01*
G01X1341809Y843677D01*
X1340968Y842082D01*
X1341007Y841994D01*
G02X1341118Y841467I-1186J-525D01*
G02X1338524I-1297J0D01*
G02X1339586Y842743I1298J0D01*
G01X1339681Y842761D01*
X1340522Y844356D01*
X1340483Y844444D01*
G02X1340372Y844971I1186J525D01*
G37*
G36*
G01X1347772D02*
G02X1350366I1297J0D01*
G02X1349304Y843695I-1298J0D01*
G01X1349209Y843677D01*
X1348368Y842082D01*
X1348407Y841994D01*
G02X1348518Y841467I-1186J-525D01*
G02X1345924I-1297J0D01*
G02X1346986Y842743I1298J0D01*
G01X1347081Y842761D01*
X1347922Y844356D01*
X1347883Y844444D01*
G02X1347772Y844971I1186J525D01*
G37*
G36*
G01X1355172D02*
G02X1357766I1297J0D01*
G02X1356704Y843695I-1298J0D01*
G01X1356609Y843677D01*
X1355768Y842082D01*
X1355807Y841994D01*
G02X1355918Y841467I-1186J-525D01*
G02X1353324I-1297J0D01*
G02X1354386Y842743I1298J0D01*
G01X1354481Y842761D01*
X1355322Y844356D01*
X1355283Y844444D01*
G02X1355172Y844971I1186J525D01*
G37*
G36*
G01X1362572D02*
G02X1365166I1297J0D01*
G02X1364104Y843695I-1298J0D01*
G01X1364009Y843677D01*
X1363168Y842082D01*
X1363207Y841994D01*
G02X1363318Y841467I-1186J-525D01*
G02X1360724I-1297J0D01*
G02X1361786Y842743I1298J0D01*
G01X1361881Y842761D01*
X1362722Y844356D01*
X1362683Y844444D01*
G02X1362572Y844971I1186J525D01*
G37*
G36*
G01X1369972D02*
G02X1372566I1297J0D01*
G02X1371504Y843695I-1298J0D01*
G01X1371409Y843677D01*
X1370568Y842082D01*
X1370607Y841994D01*
G02X1370718Y841467I-1186J-525D01*
G02X1368124I-1297J0D01*
G02X1369186Y842743I1298J0D01*
G01X1369281Y842761D01*
X1370122Y844356D01*
X1370083Y844444D01*
G02X1369972Y844971I1186J525D01*
G37*
G36*
G01X1377372D02*
G02X1379966I1297J0D01*
G02X1378904Y843695I-1298J0D01*
G01X1378809Y843677D01*
X1377968Y842082D01*
X1378007Y841994D01*
G02X1378118Y841467I-1186J-525D01*
G02X1375524I-1297J0D01*
G02X1376586Y842743I1298J0D01*
G01X1376681Y842761D01*
X1377522Y844356D01*
X1377483Y844444D01*
G02X1377372Y844971I1186J525D01*
G37*
G36*
G01X1384772D02*
G02X1387366I1297J0D01*
G02X1386304Y843695I-1298J0D01*
G01X1386209Y843677D01*
X1385368Y842082D01*
X1385407Y841994D01*
G02X1385518Y841467I-1186J-525D01*
G02X1382924I-1297J0D01*
G02X1383986Y842743I1298J0D01*
G01X1384081Y842761D01*
X1384922Y844356D01*
X1384883Y844444D01*
G02X1384772Y844971I1186J525D01*
G37*
G36*
G01X1392172D02*
G02X1394766I1297J0D01*
G02X1393704Y843695I-1298J0D01*
G01X1393609Y843677D01*
X1392768Y842082D01*
X1392807Y841994D01*
G02X1392918Y841467I-1186J-525D01*
G02X1390324I-1297J0D01*
G02X1391386Y842743I1298J0D01*
G01X1391481Y842761D01*
X1392322Y844356D01*
X1392283Y844444D01*
G02X1392172Y844971I1186J525D01*
G37*
G36*
G01X1399572D02*
G02X1402166I1297J0D01*
G02X1401104Y843695I-1298J0D01*
G01X1401009Y843677D01*
X1400168Y842082D01*
X1400207Y841994D01*
G02X1400318Y841467I-1186J-525D01*
G02X1397724I-1297J0D01*
G02X1398786Y842743I1298J0D01*
G01X1398881Y842761D01*
X1399722Y844356D01*
X1399683Y844444D01*
G02X1399572Y844971I1186J525D01*
G37*
G36*
G01X351280Y848176D02*
G02X353876I1298J0D01*
G02X353803Y847747I-1297J0D01*
G01X353772Y847661D01*
X354579Y846263D01*
X354669Y846246D01*
G02X355724Y844971I-243J-1275D01*
G02X353130I-1297J0D01*
G02X353202Y845400I1297J3D01*
G01X353233Y845486D01*
X352426Y846884D01*
X352336Y846901D01*
G02X351280Y848176I242J1275D01*
G37*
G36*
G01X358680D02*
G02X361276I1298J0D01*
G02X361203Y847747I-1297J0D01*
G01X361172Y847661D01*
X361979Y846263D01*
X362069Y846246D01*
G02X363124Y844971I-243J-1275D01*
G02X360530I-1297J0D01*
G02X360602Y845400I1297J3D01*
G01X360633Y845486D01*
X359826Y846884D01*
X359736Y846901D01*
G02X358680Y848176I242J1275D01*
G37*
G36*
G01X366080D02*
G02X368676I1298J0D01*
G02X368603Y847747I-1297J0D01*
G01X368572Y847661D01*
X369379Y846263D01*
X369469Y846246D01*
G02X370524Y844971I-243J-1275D01*
G02X367930I-1297J0D01*
G02X368002Y845400I1297J3D01*
G01X368033Y845486D01*
X367226Y846884D01*
X367136Y846901D01*
G02X366080Y848176I242J1275D01*
G37*
G36*
G01X373480D02*
G02X376076I1298J0D01*
G02X376003Y847747I-1297J0D01*
G01X375972Y847661D01*
X376779Y846263D01*
X376869Y846246D01*
G02X377924Y844971I-243J-1275D01*
G02X375330I-1297J0D01*
G02X375402Y845400I1297J3D01*
G01X375433Y845486D01*
X374626Y846884D01*
X374536Y846901D01*
G02X373480Y848176I242J1275D01*
G37*
G36*
G01X380880D02*
G02X383476I1298J0D01*
G02X383403Y847747I-1297J0D01*
G01X383372Y847661D01*
X384179Y846263D01*
X384269Y846246D01*
G02X385324Y844971I-243J-1275D01*
G02X382730I-1297J0D01*
G02X382802Y845400I1297J3D01*
G01X382833Y845486D01*
X382026Y846884D01*
X381936Y846901D01*
G02X380880Y848176I242J1275D01*
G37*
G36*
G01X388280D02*
G02X390876I1298J0D01*
G02X390803Y847747I-1297J0D01*
G01X390772Y847661D01*
X391579Y846263D01*
X391669Y846246D01*
G02X392724Y844971I-243J-1275D01*
G02X390130I-1297J0D01*
G02X390202Y845400I1297J3D01*
G01X390233Y845486D01*
X389426Y846884D01*
X389336Y846901D01*
G02X388280Y848176I242J1275D01*
G37*
G36*
G01X395680D02*
G02X398276I1298J0D01*
G02X398203Y847747I-1297J0D01*
G01X398172Y847661D01*
X398979Y846263D01*
X399069Y846246D01*
G02X400124Y844971I-243J-1275D01*
G02X397530I-1297J0D01*
G02X397602Y845400I1297J3D01*
G01X397633Y845486D01*
X396826Y846884D01*
X396736Y846901D01*
G02X395680Y848176I242J1275D01*
G37*
G36*
G01X403080D02*
G02X405676I1298J0D01*
G02X405603Y847747I-1297J0D01*
G01X405572Y847661D01*
X406379Y846263D01*
X406469Y846246D01*
G02X407524Y844971I-243J-1275D01*
G02X404930I-1297J0D01*
G02X405002Y845400I1297J3D01*
G01X405033Y845486D01*
X404226Y846884D01*
X404136Y846901D01*
G02X403080Y848176I242J1275D01*
G37*
G36*
G01X410480D02*
G02X413076I1298J0D01*
G02X413003Y847747I-1297J0D01*
G01X412972Y847661D01*
X413779Y846263D01*
X413869Y846246D01*
G02X414924Y844971I-243J-1275D01*
G02X412330I-1297J0D01*
G02X412402Y845400I1297J3D01*
G01X412433Y845486D01*
X411626Y846884D01*
X411536Y846901D01*
G02X410480Y848176I242J1275D01*
G37*
G36*
G01X417880D02*
G02X420476I1298J0D01*
G02X420403Y847747I-1297J0D01*
G01X420372Y847661D01*
X421179Y846263D01*
X421269Y846246D01*
G02X422324Y844971I-243J-1275D01*
G02X419730I-1297J0D01*
G02X419802Y845400I1297J3D01*
G01X419833Y845486D01*
X419026Y846884D01*
X418936Y846901D01*
G02X417880Y848176I242J1275D01*
G37*
G36*
G01X425280D02*
G02X427876I1298J0D01*
G02X427803Y847747I-1297J0D01*
G01X427772Y847661D01*
X428579Y846263D01*
X428669Y846246D01*
G02X429724Y844971I-243J-1275D01*
G02X427130I-1297J0D01*
G02X427202Y845400I1297J3D01*
G01X427233Y845486D01*
X426426Y846884D01*
X426336Y846901D01*
G02X425280Y848176I242J1275D01*
G37*
G36*
G01X430278Y849474D02*
G02X431317Y848954I0J-1298D01*
G01X432939D01*
G02X433978Y849474I1039J-778D01*
G02Y846878I0J-1298D01*
G02X432939Y847398I0J1298D01*
G01X431317D01*
G02X430278Y846878I-1039J778D01*
G02Y849474I0J1298D01*
G37*
G36*
G01X436380Y848176D02*
G02X438976I1298J0D01*
G02X437913Y846900I-1297J0D01*
G01X437818Y846882D01*
X436976Y845286D01*
X437015Y845197D01*
G02X437126Y844673I-1186J-525D01*
G01Y844671D01*
G02X434532I-1297J0D01*
G02X435594Y845947I1298J0D01*
G01X435689Y845965D01*
X436531Y847561D01*
X436492Y847650D01*
G02X436380Y848176I1186J527D01*
G37*
G36*
G01X447480D02*
G02X450076I1298J0D01*
G02X450003Y847748I-1298J1D01*
G01X449972Y847661D01*
X450780Y846263D01*
X450870Y846246D01*
G02X451926Y844971I-242J-1275D01*
G02X449330I-1298J0D01*
G02X449403Y845399I1298J-1D01*
G01X449434Y845486D01*
X448626Y846884D01*
X448536Y846901D01*
G02X447480Y848176I242J1275D01*
G37*
G36*
G01X454880D02*
G02X457476I1298J0D01*
G02X457403Y847747I-1297J0D01*
G01X457372Y847661D01*
X458179Y846263D01*
X458269Y846246D01*
G02X459324Y844971I-243J-1275D01*
G02X456730I-1297J0D01*
G02X456802Y845400I1297J3D01*
G01X456833Y845486D01*
X456026Y846884D01*
X455936Y846901D01*
G02X454880Y848176I242J1275D01*
G37*
G36*
G01X462280D02*
G02X464876I1298J0D01*
G02X464803Y847747I-1297J0D01*
G01X464772Y847661D01*
X465579Y846263D01*
X465669Y846246D01*
G02X466724Y844971I-243J-1275D01*
G02X464130I-1297J0D01*
G02X464202Y845400I1297J3D01*
G01X464233Y845486D01*
X463426Y846884D01*
X463336Y846901D01*
G02X462280Y848176I242J1275D01*
G37*
G36*
G01X469680D02*
G02X472276I1298J0D01*
G02X472203Y847747I-1297J0D01*
G01X472172Y847661D01*
X472979Y846263D01*
X473069Y846246D01*
G02X474124Y844971I-243J-1275D01*
G02X471530I-1297J0D01*
G02X471602Y845400I1297J3D01*
G01X471633Y845486D01*
X470826Y846884D01*
X470736Y846901D01*
G02X469680Y848176I242J1275D01*
G37*
G36*
G01X477080D02*
G02X479676I1298J0D01*
G02X479603Y847747I-1297J0D01*
G01X479572Y847661D01*
X480379Y846263D01*
X480469Y846246D01*
G02X481524Y844971I-243J-1275D01*
G02X478930I-1297J0D01*
G02X479002Y845400I1297J3D01*
G01X479033Y845486D01*
X478226Y846884D01*
X478136Y846901D01*
G02X477080Y848176I242J1275D01*
G37*
G36*
G01X484480D02*
G02X487076I1298J0D01*
G02X487003Y847747I-1297J0D01*
G01X486972Y847661D01*
X487779Y846263D01*
X487869Y846246D01*
G02X488924Y844971I-243J-1275D01*
G02X486330I-1297J0D01*
G02X486402Y845400I1297J3D01*
G01X486433Y845486D01*
X485626Y846884D01*
X485536Y846901D01*
G02X484480Y848176I242J1275D01*
G37*
G36*
G01X491880D02*
G02X494476I1298J0D01*
G02X494403Y847747I-1297J0D01*
G01X494372Y847661D01*
X495179Y846263D01*
X495269Y846246D01*
G02X496324Y844971I-243J-1275D01*
G02X493730I-1297J0D01*
G02X493802Y845400I1297J3D01*
G01X493833Y845486D01*
X493026Y846884D01*
X492936Y846901D01*
G02X491880Y848176I242J1275D01*
G37*
G36*
G01X499280D02*
G02X501876I1298J0D01*
G02X501803Y847747I-1297J0D01*
G01X501772Y847661D01*
X502579Y846263D01*
X502669Y846246D01*
G02X503724Y844971I-243J-1275D01*
G02X501130I-1297J0D01*
G02X501202Y845400I1297J3D01*
G01X501233Y845486D01*
X500426Y846884D01*
X500336Y846901D01*
G02X499280Y848176I242J1275D01*
G37*
G36*
G01X506680D02*
G02X509276I1298J0D01*
G02X509203Y847747I-1297J0D01*
G01X509172Y847661D01*
X509979Y846263D01*
X510069Y846246D01*
G02X511124Y844971I-243J-1275D01*
G02X508530I-1297J0D01*
G02X508602Y845400I1297J3D01*
G01X508633Y845486D01*
X507826Y846884D01*
X507736Y846901D01*
G02X506680Y848176I242J1275D01*
G37*
G36*
G01X514080D02*
G02X516676I1298J0D01*
G02X516603Y847747I-1297J0D01*
G01X516572Y847661D01*
X517379Y846263D01*
X517469Y846246D01*
G02X518524Y844971I-243J-1275D01*
G02X515930I-1297J0D01*
G02X516002Y845400I1297J3D01*
G01X516033Y845486D01*
X515226Y846884D01*
X515136Y846901D01*
G02X514080Y848176I242J1275D01*
G37*
G36*
G01X521480D02*
G02X524076I1298J0D01*
G02X524003Y847747I-1297J0D01*
G01X523972Y847661D01*
X524779Y846263D01*
X524869Y846246D01*
G02X525924Y844971I-243J-1275D01*
G02X523330I-1297J0D01*
G02X523402Y845400I1297J3D01*
G01X523433Y845486D01*
X522626Y846884D01*
X522536Y846901D01*
G02X521480Y848176I242J1275D01*
G37*
G36*
G01X526478Y849474D02*
G02X527517Y848954I0J-1298D01*
G01X529139D01*
G02X530178Y849474I1039J-778D01*
G02Y846878I0J-1298D01*
G02X529139Y847398I0J1298D01*
G01X527517D01*
G02X526478Y846878I-1039J778D01*
G02Y849474I0J1298D01*
G37*
G36*
G01X532580Y848176D02*
G02X535176I1298J0D01*
G02X534168Y846911I-1298J0D01*
G01X534079Y846891D01*
X533202Y845231D01*
X533236Y845145D01*
G02X533326Y844671I-1208J-475D01*
G02X530730I-1298J0D01*
G02X531738Y845936I1298J0D01*
G01X531827Y845956D01*
X532704Y847616D01*
X532670Y847702D01*
G02X532580Y848176I1208J475D01*
G37*
G36*
G01X1327422D02*
G02X1330018I1298J0D01*
G02X1329945Y847747I-1297J0D01*
G01X1329914Y847661D01*
X1330721Y846263D01*
X1330811Y846246D01*
G02X1331866Y844971I-243J-1275D01*
G02X1329272I-1297J0D01*
G02X1329344Y845400I1297J3D01*
G01X1329375Y845486D01*
X1328568Y846884D01*
X1328478Y846901D01*
G02X1327422Y848176I242J1275D01*
G37*
G36*
G01X1334822D02*
G02X1337418I1298J0D01*
G02X1337345Y847747I-1297J0D01*
G01X1337314Y847661D01*
X1338121Y846263D01*
X1338211Y846246D01*
G02X1339266Y844971I-243J-1275D01*
G02X1336672I-1297J0D01*
G02X1336744Y845400I1297J3D01*
G01X1336775Y845486D01*
X1335968Y846884D01*
X1335878Y846901D01*
G02X1334822Y848176I242J1275D01*
G37*
G36*
G01X1342222D02*
G02X1344818I1298J0D01*
G02X1344745Y847747I-1297J0D01*
G01X1344714Y847661D01*
X1345521Y846263D01*
X1345611Y846246D01*
G02X1346666Y844971I-243J-1275D01*
G02X1344072I-1297J0D01*
G02X1344144Y845400I1297J3D01*
G01X1344175Y845486D01*
X1343368Y846884D01*
X1343278Y846901D01*
G02X1342222Y848176I242J1275D01*
G37*
G36*
G01X1349622D02*
G02X1352218I1298J0D01*
G02X1352145Y847747I-1297J0D01*
G01X1352114Y847661D01*
X1352921Y846263D01*
X1353011Y846246D01*
G02X1354066Y844971I-243J-1275D01*
G02X1351472I-1297J0D01*
G02X1351544Y845400I1297J3D01*
G01X1351575Y845486D01*
X1350768Y846884D01*
X1350678Y846901D01*
G02X1349622Y848176I242J1275D01*
G37*
G36*
G01X1357022D02*
G02X1359618I1298J0D01*
G02X1359545Y847747I-1297J0D01*
G01X1359514Y847661D01*
X1360321Y846263D01*
X1360411Y846246D01*
G02X1361466Y844971I-243J-1275D01*
G02X1358872I-1297J0D01*
G02X1358944Y845400I1297J3D01*
G01X1358975Y845486D01*
X1358168Y846884D01*
X1358078Y846901D01*
G02X1357022Y848176I242J1275D01*
G37*
G36*
G01X1364422D02*
G02X1367018I1298J0D01*
G02X1366945Y847747I-1297J0D01*
G01X1366914Y847661D01*
X1367721Y846263D01*
X1367811Y846246D01*
G02X1368866Y844971I-243J-1275D01*
G02X1366272I-1297J0D01*
G02X1366344Y845400I1297J3D01*
G01X1366375Y845486D01*
X1365568Y846884D01*
X1365478Y846901D01*
G02X1364422Y848176I242J1275D01*
G37*
G36*
G01X1371822D02*
G02X1374418I1298J0D01*
G02X1374345Y847747I-1297J0D01*
G01X1374314Y847661D01*
X1375121Y846263D01*
X1375211Y846246D01*
G02X1376266Y844971I-243J-1275D01*
G02X1373672I-1297J0D01*
G02X1373744Y845400I1297J3D01*
G01X1373775Y845486D01*
X1372968Y846884D01*
X1372878Y846901D01*
G02X1371822Y848176I242J1275D01*
G37*
G36*
G01X1379222D02*
G02X1381818I1298J0D01*
G02X1381745Y847747I-1297J0D01*
G01X1381714Y847661D01*
X1382521Y846263D01*
X1382611Y846246D01*
G02X1383666Y844971I-243J-1275D01*
G02X1381072I-1297J0D01*
G02X1381144Y845400I1297J3D01*
G01X1381175Y845486D01*
X1380368Y846884D01*
X1380278Y846901D01*
G02X1379222Y848176I242J1275D01*
G37*
G36*
G01X1386622D02*
G02X1389218I1298J0D01*
G02X1389145Y847747I-1297J0D01*
G01X1389114Y847661D01*
X1389921Y846263D01*
X1390011Y846246D01*
G02X1391066Y844971I-243J-1275D01*
G02X1388472I-1297J0D01*
G02X1388544Y845400I1297J3D01*
G01X1388575Y845486D01*
X1387768Y846884D01*
X1387678Y846901D01*
G02X1386622Y848176I242J1275D01*
G37*
G36*
G01X1394022D02*
G02X1396618I1298J0D01*
G02X1396545Y847747I-1297J0D01*
G01X1396514Y847661D01*
X1397321Y846263D01*
X1397411Y846246D01*
G02X1398466Y844971I-243J-1275D01*
G02X1395872I-1297J0D01*
G02X1395944Y845400I1297J3D01*
G01X1395975Y845486D01*
X1395168Y846884D01*
X1395078Y846901D01*
G02X1394022Y848176I242J1275D01*
G37*
G36*
G01X1401422D02*
G02X1404018I1298J0D01*
G02X1403945Y847747I-1297J0D01*
G01X1403914Y847661D01*
X1404721Y846263D01*
X1404811Y846246D01*
G02X1405866Y844971I-243J-1275D01*
G02X1403272I-1297J0D01*
G02X1403344Y845400I1297J3D01*
G01X1403375Y845486D01*
X1402568Y846884D01*
X1402478Y846901D01*
G02X1401422Y848176I242J1275D01*
G37*
G36*
G01X1406420Y849474D02*
G02X1407459Y848954I0J-1298D01*
G01X1409081D01*
G02X1410120Y849474I1039J-778D01*
G02Y846878I0J-1298D01*
G02X1409081Y847398I0J1298D01*
G01X1407459D01*
G02X1406420Y846878I-1039J778D01*
G02Y849474I0J1298D01*
G37*
G36*
G01X1412522Y848176D02*
G02X1415118I1298J0D01*
G02X1414062Y846901I-1298J0D01*
G01X1413972Y846884D01*
X1413164Y845485D01*
X1413194Y845398D01*
G02X1413266Y844973I-1225J-426D01*
G01Y844971D01*
G02X1410672I-1297J0D01*
G02X1411728Y846246I1298J0D01*
G01X1411818Y846263D01*
X1412625Y847662D01*
X1412595Y847748D01*
G02X1412522Y848176I1225J429D01*
G37*
G36*
G01X349430Y851380D02*
G02X352024I1297J0D01*
G02X350969Y850105I-1298J0D01*
G01X350879Y850088D01*
X350072Y848691D01*
X350103Y848604D01*
G02X350176Y848176I-1225J-429D01*
G02X347580I-1298J0D01*
G02X348636Y849451I1298J0D01*
G01X348726Y849468D01*
X349533Y850865D01*
X349502Y850952D01*
G02X349430Y851380I1225J426D01*
G37*
G36*
G01X1325572D02*
G02X1328166I1297J0D01*
G02X1327111Y850105I-1298J0D01*
G01X1327021Y850088D01*
X1326214Y848691D01*
X1326245Y848604D01*
G02X1326318Y848176I-1225J-429D01*
G02X1323722I-1298J0D01*
G02X1324778Y849451I1298J0D01*
G01X1324868Y849468D01*
X1325675Y850865D01*
X1325644Y850952D01*
G02X1325572Y851380I1225J426D01*
G37*
G36*
G01X353132Y857789D02*
G02X355726I1297J0D01*
G02X355654Y857360I-1297J-3D01*
G01X355623Y857274D01*
X356430Y855876D01*
X356520Y855859D01*
G02X357576Y854584I-242J-1275D01*
G02X354980I-1298J0D01*
G02X355053Y855013I1297J0D01*
G01X355084Y855099D01*
X354277Y856497D01*
X354187Y856514D01*
G02X353132Y857789I243J1275D01*
G37*
G36*
G01X360532D02*
G02X363126I1297J0D01*
G02X363054Y857360I-1297J-3D01*
G01X363023Y857274D01*
X363830Y855876D01*
X363920Y855859D01*
G02X364976Y854584I-242J-1275D01*
G02X362380I-1298J0D01*
G02X362453Y855013I1297J0D01*
G01X362484Y855099D01*
X361677Y856497D01*
X361587Y856514D01*
G02X360532Y857789I243J1275D01*
G37*
G36*
G01X367932D02*
G02X370526I1297J0D01*
G02X370454Y857360I-1297J-3D01*
G01X370423Y857274D01*
X371230Y855876D01*
X371320Y855859D01*
G02X372376Y854584I-242J-1275D01*
G02X369780I-1298J0D01*
G02X369853Y855013I1297J0D01*
G01X369884Y855099D01*
X369077Y856497D01*
X368987Y856514D01*
G02X367932Y857789I243J1275D01*
G37*
G36*
G01X375332D02*
G02X377926I1297J0D01*
G02X377854Y857360I-1297J-3D01*
G01X377823Y857274D01*
X378630Y855876D01*
X378720Y855859D01*
G02X379776Y854584I-242J-1275D01*
G02X377180I-1298J0D01*
G02X377253Y855013I1297J0D01*
G01X377284Y855099D01*
X376477Y856497D01*
X376387Y856514D01*
G02X375332Y857789I243J1275D01*
G37*
G36*
G01X382732D02*
G02X385326I1297J0D01*
G02X385254Y857360I-1297J-3D01*
G01X385223Y857274D01*
X386030Y855876D01*
X386120Y855859D01*
G02X387176Y854584I-242J-1275D01*
G02X384580I-1298J0D01*
G02X384653Y855013I1297J0D01*
G01X384684Y855099D01*
X383877Y856497D01*
X383787Y856514D01*
G02X382732Y857789I243J1275D01*
G37*
G36*
G01X390132D02*
G02X392726I1297J0D01*
G02X392654Y857360I-1297J-3D01*
G01X392623Y857274D01*
X393430Y855876D01*
X393520Y855859D01*
G02X394576Y854584I-242J-1275D01*
G02X391980I-1298J0D01*
G02X392053Y855013I1297J0D01*
G01X392084Y855099D01*
X391277Y856497D01*
X391187Y856514D01*
G02X390132Y857789I243J1275D01*
G37*
G36*
G01X397532D02*
G02X400126I1297J0D01*
G02X400054Y857360I-1297J-3D01*
G01X400023Y857274D01*
X400830Y855876D01*
X400920Y855859D01*
G02X401976Y854584I-242J-1275D01*
G02X399380I-1298J0D01*
G02X399453Y855013I1297J0D01*
G01X399484Y855099D01*
X398677Y856497D01*
X398587Y856514D01*
G02X397532Y857789I243J1275D01*
G37*
G36*
G01X404932D02*
G02X407526I1297J0D01*
G02X407454Y857360I-1297J-3D01*
G01X407423Y857274D01*
X408230Y855876D01*
X408320Y855859D01*
G02X409376Y854584I-242J-1275D01*
G02X406780I-1298J0D01*
G02X406853Y855013I1297J0D01*
G01X406884Y855099D01*
X406077Y856497D01*
X405987Y856514D01*
G02X404932Y857789I243J1275D01*
G37*
G36*
G01X412332D02*
G02X414926I1297J0D01*
G02X414854Y857360I-1297J-3D01*
G01X414823Y857274D01*
X415630Y855876D01*
X415720Y855859D01*
G02X416776Y854584I-242J-1275D01*
G02X414180I-1298J0D01*
G02X414253Y855013I1297J0D01*
G01X414284Y855099D01*
X413477Y856497D01*
X413387Y856514D01*
G02X412332Y857789I243J1275D01*
G37*
G36*
G01X419732D02*
G02X422326I1297J0D01*
G02X422254Y857360I-1297J-3D01*
G01X422223Y857274D01*
X423030Y855876D01*
X423120Y855859D01*
G02X424176Y854584I-242J-1275D01*
G02X421580I-1298J0D01*
G02X421653Y855013I1297J0D01*
G01X421684Y855099D01*
X420877Y856497D01*
X420787Y856514D01*
G02X419732Y857789I243J1275D01*
G37*
G36*
G01X427132D02*
G02X429726I1297J0D01*
G02X429654Y857360I-1297J-3D01*
G01X429623Y857274D01*
X430430Y855876D01*
X430520Y855859D01*
G02X431576Y854584I-242J-1275D01*
G02X428980I-1298J0D01*
G02X429053Y855013I1297J0D01*
G01X429084Y855099D01*
X428277Y856497D01*
X428187Y856514D01*
G02X427132Y857789I243J1275D01*
G37*
G36*
G01X434532D02*
G02X437126I1297J0D01*
G02X437054Y857360I-1297J-3D01*
G01X437023Y857274D01*
X437830Y855876D01*
X437920Y855859D01*
G02X438976Y854584I-242J-1275D01*
G02X436382I-1297J0D01*
G02X436454Y855012I1297J2D01*
G01X436484Y855098D01*
X435677Y856497D01*
X435587Y856514D01*
G02X434532Y857789I243J1275D01*
G37*
G36*
G01X445632D02*
G02X448226I1297J0D01*
G02X447171Y856514I-1298J0D01*
G01X447081Y856497D01*
X446273Y855098D01*
X446303Y855011D01*
G02X446376Y854584I-1225J-429D01*
G02X443780I-1298J0D01*
G02X444838Y855859I1297J0D01*
G01X444928Y855876D01*
X445735Y857274D01*
X445704Y857361D01*
G02X445632Y857789I1225J426D01*
G37*
G36*
G01X453032D02*
G02X455626I1297J0D01*
G02X454571Y856514I-1298J0D01*
G01X454481Y856497D01*
X453673Y855098D01*
X453703Y855011D01*
G02X453776Y854584I-1225J-429D01*
G02X451180I-1298J0D01*
G02X452238Y855859I1297J0D01*
G01X452328Y855876D01*
X453135Y857274D01*
X453104Y857361D01*
G02X453032Y857789I1225J426D01*
G37*
G36*
G01X460432D02*
G02X463026I1297J0D01*
G02X461971Y856514I-1298J0D01*
G01X461881Y856497D01*
X461073Y855098D01*
X461103Y855011D01*
G02X461176Y854584I-1225J-429D01*
G02X458580I-1298J0D01*
G02X459638Y855859I1297J0D01*
G01X459728Y855876D01*
X460535Y857274D01*
X460504Y857361D01*
G02X460432Y857789I1225J426D01*
G37*
G36*
G01X467832D02*
G02X470426I1297J0D01*
G02X469371Y856514I-1298J0D01*
G01X469281Y856497D01*
X468473Y855098D01*
X468503Y855011D01*
G02X468576Y854584I-1225J-429D01*
G02X465980I-1298J0D01*
G02X467038Y855859I1297J0D01*
G01X467128Y855876D01*
X467935Y857274D01*
X467904Y857361D01*
G02X467832Y857789I1225J426D01*
G37*
G36*
G01X475232D02*
G02X477826I1297J0D01*
G02X476771Y856514I-1298J0D01*
G01X476681Y856497D01*
X475873Y855098D01*
X475903Y855011D01*
G02X475976Y854584I-1225J-429D01*
G02X473380I-1298J0D01*
G02X474438Y855859I1297J0D01*
G01X474528Y855876D01*
X475335Y857274D01*
X475304Y857361D01*
G02X475232Y857789I1225J426D01*
G37*
G36*
G01X482632D02*
G02X485226I1297J0D01*
G02X484171Y856514I-1298J0D01*
G01X484081Y856497D01*
X483273Y855098D01*
X483303Y855011D01*
G02X483376Y854584I-1225J-429D01*
G02X480780I-1298J0D01*
G02X481838Y855859I1297J0D01*
G01X481928Y855876D01*
X482735Y857274D01*
X482704Y857361D01*
G02X482632Y857789I1225J426D01*
G37*
G36*
G01X490032D02*
G02X492626I1297J0D01*
G02X491571Y856514I-1298J0D01*
G01X491481Y856497D01*
X490673Y855098D01*
X490703Y855011D01*
G02X490776Y854584I-1225J-429D01*
G02X488180I-1298J0D01*
G02X489238Y855859I1297J0D01*
G01X489328Y855876D01*
X490135Y857274D01*
X490104Y857361D01*
G02X490032Y857789I1225J426D01*
G37*
G36*
G01X497432D02*
G02X500026I1297J0D01*
G02X498971Y856514I-1298J0D01*
G01X498881Y856497D01*
X498073Y855098D01*
X498103Y855011D01*
G02X498176Y854584I-1225J-429D01*
G02X495580I-1298J0D01*
G02X496638Y855859I1297J0D01*
G01X496728Y855876D01*
X497535Y857274D01*
X497504Y857361D01*
G02X497432Y857789I1225J426D01*
G37*
G36*
G01X504832D02*
G02X507426I1297J0D01*
G02X506371Y856514I-1298J0D01*
G01X506281Y856497D01*
X505473Y855098D01*
X505503Y855011D01*
G02X505576Y854584I-1225J-429D01*
G02X502980I-1298J0D01*
G02X504038Y855859I1297J0D01*
G01X504128Y855876D01*
X504935Y857274D01*
X504904Y857361D01*
G02X504832Y857789I1225J426D01*
G37*
G36*
G01X512232D02*
G02X514826I1297J0D01*
G02X513771Y856514I-1298J0D01*
G01X513681Y856497D01*
X512873Y855098D01*
X512903Y855011D01*
G02X512976Y854584I-1225J-429D01*
G02X510380I-1298J0D01*
G02X511438Y855859I1297J0D01*
G01X511528Y855876D01*
X512335Y857274D01*
X512304Y857361D01*
G02X512232Y857789I1225J426D01*
G37*
G36*
G01X519632D02*
G02X522226I1297J0D01*
G02X521171Y856514I-1298J0D01*
G01X521081Y856497D01*
X520273Y855098D01*
X520303Y855011D01*
G02X520376Y854584I-1225J-429D01*
G02X517780I-1298J0D01*
G02X518838Y855859I1297J0D01*
G01X518928Y855876D01*
X519735Y857274D01*
X519704Y857361D01*
G02X519632Y857789I1225J426D01*
G37*
G36*
G01X527032D02*
G02X529626I1297J0D01*
G02X528571Y856514I-1298J0D01*
G01X528481Y856497D01*
X527673Y855098D01*
X527703Y855011D01*
G02X527776Y854584I-1225J-429D01*
G02X525180I-1298J0D01*
G02X526238Y855859I1297J0D01*
G01X526328Y855876D01*
X527135Y857274D01*
X527104Y857361D01*
G02X527032Y857789I1225J426D01*
G37*
G36*
G01X1329274D02*
G02X1331868I1297J0D01*
G02X1331796Y857360I-1297J-3D01*
G01X1331765Y857274D01*
X1332572Y855876D01*
X1332662Y855859D01*
G02X1333718Y854584I-242J-1275D01*
G02X1331122I-1298J0D01*
G02X1331195Y855013I1297J0D01*
G01X1331226Y855099D01*
X1330419Y856497D01*
X1330329Y856514D01*
G02X1329274Y857789I243J1275D01*
G37*
G36*
G01X1336674D02*
G02X1339268I1297J0D01*
G02X1339196Y857360I-1297J-3D01*
G01X1339165Y857274D01*
X1339972Y855876D01*
X1340062Y855859D01*
G02X1341118Y854584I-242J-1275D01*
G02X1338522I-1298J0D01*
G02X1338595Y855013I1297J0D01*
G01X1338626Y855099D01*
X1337819Y856497D01*
X1337729Y856514D01*
G02X1336674Y857789I243J1275D01*
G37*
G36*
G01X1344074D02*
G02X1346668I1297J0D01*
G02X1346596Y857360I-1297J-3D01*
G01X1346565Y857274D01*
X1347372Y855876D01*
X1347462Y855859D01*
G02X1348518Y854584I-242J-1275D01*
G02X1345922I-1298J0D01*
G02X1345995Y855013I1297J0D01*
G01X1346026Y855099D01*
X1345219Y856497D01*
X1345129Y856514D01*
G02X1344074Y857789I243J1275D01*
G37*
G36*
G01X1351474D02*
G02X1354068I1297J0D01*
G02X1353996Y857360I-1297J-3D01*
G01X1353965Y857274D01*
X1354772Y855876D01*
X1354862Y855859D01*
G02X1355918Y854584I-242J-1275D01*
G02X1353322I-1298J0D01*
G02X1353395Y855013I1297J0D01*
G01X1353426Y855099D01*
X1352619Y856497D01*
X1352529Y856514D01*
G02X1351474Y857789I243J1275D01*
G37*
G36*
G01X1358874D02*
G02X1361468I1297J0D01*
G02X1361396Y857360I-1297J-3D01*
G01X1361365Y857274D01*
X1362172Y855876D01*
X1362262Y855859D01*
G02X1363318Y854584I-242J-1275D01*
G02X1360722I-1298J0D01*
G02X1360795Y855013I1297J0D01*
G01X1360826Y855099D01*
X1360019Y856497D01*
X1359929Y856514D01*
G02X1358874Y857789I243J1275D01*
G37*
G36*
G01X1366274D02*
G02X1368868I1297J0D01*
G02X1368796Y857360I-1297J-3D01*
G01X1368765Y857274D01*
X1369572Y855876D01*
X1369662Y855859D01*
G02X1370718Y854584I-242J-1275D01*
G02X1368122I-1298J0D01*
G02X1368195Y855013I1297J0D01*
G01X1368226Y855099D01*
X1367419Y856497D01*
X1367329Y856514D01*
G02X1366274Y857789I243J1275D01*
G37*
G36*
G01X1373674D02*
G02X1376268I1297J0D01*
G02X1376196Y857360I-1297J-3D01*
G01X1376165Y857274D01*
X1376972Y855876D01*
X1377062Y855859D01*
G02X1378118Y854584I-242J-1275D01*
G02X1375522I-1298J0D01*
G02X1375595Y855013I1297J0D01*
G01X1375626Y855099D01*
X1374819Y856497D01*
X1374729Y856514D01*
G02X1373674Y857789I243J1275D01*
G37*
G36*
G01X1381074D02*
G02X1383668I1297J0D01*
G02X1383596Y857360I-1297J-3D01*
G01X1383565Y857274D01*
X1384372Y855876D01*
X1384462Y855859D01*
G02X1385518Y854584I-242J-1275D01*
G02X1382922I-1298J0D01*
G02X1382995Y855013I1297J0D01*
G01X1383026Y855099D01*
X1382219Y856497D01*
X1382129Y856514D01*
G02X1381074Y857789I243J1275D01*
G37*
G36*
G01X1388474D02*
G02X1391068I1297J0D01*
G02X1390996Y857360I-1297J-3D01*
G01X1390965Y857274D01*
X1391772Y855876D01*
X1391862Y855859D01*
G02X1392918Y854584I-242J-1275D01*
G02X1390322I-1298J0D01*
G02X1390395Y855013I1297J0D01*
G01X1390426Y855099D01*
X1389619Y856497D01*
X1389529Y856514D01*
G02X1388474Y857789I243J1275D01*
G37*
G36*
G01X1395874D02*
G02X1398468I1297J0D01*
G02X1398396Y857360I-1297J-3D01*
G01X1398365Y857274D01*
X1399172Y855876D01*
X1399262Y855859D01*
G02X1400318Y854584I-242J-1275D01*
G02X1397722I-1298J0D01*
G02X1397795Y855013I1297J0D01*
G01X1397826Y855099D01*
X1397019Y856497D01*
X1396929Y856514D01*
G02X1395874Y857789I243J1275D01*
G37*
G36*
G01X1403274D02*
G02X1405868I1297J0D01*
G02X1405796Y857360I-1297J-3D01*
G01X1405765Y857274D01*
X1406572Y855876D01*
X1406662Y855859D01*
G02X1407718Y854584I-242J-1275D01*
G02X1405122I-1298J0D01*
G02X1405195Y855013I1297J0D01*
G01X1405226Y855099D01*
X1404419Y856497D01*
X1404329Y856514D01*
G02X1403274Y857789I243J1275D01*
G37*
G36*
G01X1410674D02*
G02X1413268I1297J0D01*
G02X1413196Y857360I-1297J-3D01*
G01X1413165Y857274D01*
X1413972Y855876D01*
X1414062Y855859D01*
G02X1415118Y854584I-242J-1275D01*
G02X1412524I-1297J0D01*
G02X1412596Y855012I1297J2D01*
G01X1412626Y855098D01*
X1411819Y856497D01*
X1411729Y856514D01*
G02X1410674Y857789I243J1275D01*
G37*
G36*
G01X1421774D02*
G02X1424368I1297J0D01*
G02X1423313Y856514I-1298J0D01*
G01X1423223Y856497D01*
X1422415Y855098D01*
X1422445Y855011D01*
G02X1422518Y854584I-1225J-429D01*
G02X1419922I-1298J0D01*
G02X1420980Y855859I1297J0D01*
G01X1421070Y855876D01*
X1421877Y857274D01*
X1421846Y857361D01*
G02X1421774Y857789I1225J426D01*
G37*
G36*
G01X1429174D02*
G02X1431768I1297J0D01*
G02X1430713Y856514I-1298J0D01*
G01X1430623Y856497D01*
X1429815Y855098D01*
X1429845Y855011D01*
G02X1429918Y854584I-1225J-429D01*
G02X1427322I-1298J0D01*
G02X1428380Y855859I1297J0D01*
G01X1428470Y855876D01*
X1429277Y857274D01*
X1429246Y857361D01*
G02X1429174Y857789I1225J426D01*
G37*
G36*
G01X1436574D02*
G02X1439168I1297J0D01*
G02X1438113Y856514I-1298J0D01*
G01X1438023Y856497D01*
X1437215Y855098D01*
X1437245Y855011D01*
G02X1437318Y854584I-1225J-429D01*
G02X1434722I-1298J0D01*
G02X1435780Y855859I1297J0D01*
G01X1435870Y855876D01*
X1436677Y857274D01*
X1436646Y857361D01*
G02X1436574Y857789I1225J426D01*
G37*
G36*
G01X1443974D02*
G02X1446568I1297J0D01*
G02X1445513Y856514I-1298J0D01*
G01X1445423Y856497D01*
X1444615Y855098D01*
X1444645Y855011D01*
G02X1444718Y854584I-1225J-429D01*
G02X1442122I-1298J0D01*
G02X1443180Y855859I1297J0D01*
G01X1443270Y855876D01*
X1444077Y857274D01*
X1444046Y857361D01*
G02X1443974Y857789I1225J426D01*
G37*
G36*
G01X1451374D02*
G02X1453968I1297J0D01*
G02X1452913Y856514I-1298J0D01*
G01X1452823Y856497D01*
X1452015Y855098D01*
X1452045Y855011D01*
G02X1452118Y854584I-1225J-429D01*
G02X1449522I-1298J0D01*
G02X1450580Y855859I1297J0D01*
G01X1450670Y855876D01*
X1451477Y857274D01*
X1451446Y857361D01*
G02X1451374Y857789I1225J426D01*
G37*
G36*
G01X1458774D02*
G02X1461368I1297J0D01*
G02X1460313Y856514I-1298J0D01*
G01X1460223Y856497D01*
X1459415Y855098D01*
X1459445Y855011D01*
G02X1459518Y854584I-1225J-429D01*
G02X1456922I-1298J0D01*
G02X1457980Y855859I1297J0D01*
G01X1458070Y855876D01*
X1458877Y857274D01*
X1458846Y857361D01*
G02X1458774Y857789I1225J426D01*
G37*
G36*
G01X1466174D02*
G02X1468768I1297J0D01*
G02X1467713Y856514I-1298J0D01*
G01X1467623Y856497D01*
X1466815Y855098D01*
X1466845Y855011D01*
G02X1466918Y854584I-1225J-429D01*
G02X1464322I-1298J0D01*
G02X1465380Y855859I1297J0D01*
G01X1465470Y855876D01*
X1466277Y857274D01*
X1466246Y857361D01*
G02X1466174Y857789I1225J426D01*
G37*
G36*
G01X1473574D02*
G02X1476168I1297J0D01*
G02X1475113Y856514I-1298J0D01*
G01X1475023Y856497D01*
X1474215Y855098D01*
X1474245Y855011D01*
G02X1474318Y854584I-1225J-429D01*
G02X1471722I-1298J0D01*
G02X1472780Y855859I1297J0D01*
G01X1472870Y855876D01*
X1473677Y857274D01*
X1473646Y857361D01*
G02X1473574Y857789I1225J426D01*
G37*
G36*
G01X1480974D02*
G02X1483568I1297J0D01*
G02X1482513Y856514I-1298J0D01*
G01X1482423Y856497D01*
X1481615Y855098D01*
X1481645Y855011D01*
G02X1481718Y854584I-1225J-429D01*
G02X1479122I-1298J0D01*
G02X1480180Y855859I1297J0D01*
G01X1480270Y855876D01*
X1481077Y857274D01*
X1481046Y857361D01*
G02X1480974Y857789I1225J426D01*
G37*
G36*
G01X1488374D02*
G02X1490968I1297J0D01*
G02X1489913Y856514I-1298J0D01*
G01X1489823Y856497D01*
X1489015Y855098D01*
X1489045Y855011D01*
G02X1489118Y854584I-1225J-429D01*
G02X1486522I-1298J0D01*
G02X1487580Y855859I1297J0D01*
G01X1487670Y855876D01*
X1488477Y857274D01*
X1488446Y857361D01*
G02X1488374Y857789I1225J426D01*
G37*
G36*
G01X1495774D02*
G02X1498368I1297J0D01*
G02X1497313Y856514I-1298J0D01*
G01X1497223Y856497D01*
X1496415Y855098D01*
X1496445Y855011D01*
G02X1496518Y854584I-1225J-429D01*
G02X1493922I-1298J0D01*
G02X1494980Y855859I1297J0D01*
G01X1495070Y855876D01*
X1495877Y857274D01*
X1495846Y857361D01*
G02X1495774Y857789I1225J426D01*
G37*
G36*
G01X1503174D02*
G02X1505768I1297J0D01*
G02X1504713Y856514I-1298J0D01*
G01X1504623Y856497D01*
X1503815Y855098D01*
X1503845Y855011D01*
G02X1503918Y854584I-1225J-429D01*
G02X1501322I-1298J0D01*
G02X1502380Y855859I1297J0D01*
G01X1502470Y855876D01*
X1503277Y857274D01*
X1503246Y857361D01*
G02X1503174Y857789I1225J426D01*
G37*
G36*
G01X351280Y860993D02*
G02X353876I1298J0D01*
G02X352820Y859718I-1298J0D01*
G01X352730Y859701D01*
X351923Y858304D01*
X351954Y858217D01*
G02X352026Y857789I-1225J-426D01*
G02X349432I-1297J0D01*
G02X350487Y859064I1298J0D01*
G01X350577Y859081D01*
X351384Y860478D01*
X351353Y860565D01*
G02X351280Y860993I1225J429D01*
G37*
G36*
G01X358680D02*
G02X361276I1298J0D01*
G02X360220Y859718I-1298J0D01*
G01X360130Y859701D01*
X359323Y858304D01*
X359354Y858217D01*
G02X359426Y857789I-1225J-426D01*
G02X356832I-1297J0D01*
G02X357887Y859064I1298J0D01*
G01X357977Y859081D01*
X358784Y860478D01*
X358753Y860565D01*
G02X358680Y860993I1225J429D01*
G37*
G36*
G01X366080D02*
G02X368676I1298J0D01*
G02X367620Y859718I-1298J0D01*
G01X367530Y859701D01*
X366723Y858304D01*
X366754Y858217D01*
G02X366826Y857789I-1225J-426D01*
G02X364232I-1297J0D01*
G02X365287Y859064I1298J0D01*
G01X365377Y859081D01*
X366184Y860478D01*
X366153Y860565D01*
G02X366080Y860993I1225J429D01*
G37*
G36*
G01X373480D02*
G02X376076I1298J0D01*
G02X375020Y859718I-1298J0D01*
G01X374930Y859701D01*
X374123Y858304D01*
X374154Y858217D01*
G02X374226Y857789I-1225J-426D01*
G02X371632I-1297J0D01*
G02X372687Y859064I1298J0D01*
G01X372777Y859081D01*
X373584Y860478D01*
X373553Y860565D01*
G02X373480Y860993I1225J429D01*
G37*
G36*
G01X380880D02*
G02X383476I1298J0D01*
G02X382420Y859718I-1298J0D01*
G01X382330Y859701D01*
X381523Y858304D01*
X381554Y858217D01*
G02X381626Y857789I-1225J-426D01*
G02X379032I-1297J0D01*
G02X380087Y859064I1298J0D01*
G01X380177Y859081D01*
X380984Y860478D01*
X380953Y860565D01*
G02X380880Y860993I1225J429D01*
G37*
G36*
G01X388280D02*
G02X390876I1298J0D01*
G02X389820Y859718I-1298J0D01*
G01X389730Y859701D01*
X388923Y858304D01*
X388954Y858217D01*
G02X389026Y857789I-1225J-426D01*
G02X386432I-1297J0D01*
G02X387487Y859064I1298J0D01*
G01X387577Y859081D01*
X388384Y860478D01*
X388353Y860565D01*
G02X388280Y860993I1225J429D01*
G37*
G36*
G01X395680D02*
G02X398276I1298J0D01*
G02X397220Y859718I-1298J0D01*
G01X397130Y859701D01*
X396323Y858304D01*
X396354Y858217D01*
G02X396426Y857789I-1225J-426D01*
G02X393832I-1297J0D01*
G02X394887Y859064I1298J0D01*
G01X394977Y859081D01*
X395784Y860478D01*
X395753Y860565D01*
G02X395680Y860993I1225J429D01*
G37*
G36*
G01X403080D02*
G02X405676I1298J0D01*
G02X404620Y859718I-1298J0D01*
G01X404530Y859701D01*
X403723Y858304D01*
X403754Y858217D01*
G02X403826Y857789I-1225J-426D01*
G02X401232I-1297J0D01*
G02X402287Y859064I1298J0D01*
G01X402377Y859081D01*
X403184Y860478D01*
X403153Y860565D01*
G02X403080Y860993I1225J429D01*
G37*
G36*
G01X410480D02*
G02X413076I1298J0D01*
G02X412020Y859718I-1298J0D01*
G01X411930Y859701D01*
X411123Y858304D01*
X411154Y858217D01*
G02X411226Y857789I-1225J-426D01*
G02X408632I-1297J0D01*
G02X409687Y859064I1298J0D01*
G01X409777Y859081D01*
X410584Y860478D01*
X410553Y860565D01*
G02X410480Y860993I1225J429D01*
G37*
G36*
G01X417880D02*
G02X420476I1298J0D01*
G02X419420Y859718I-1298J0D01*
G01X419330Y859701D01*
X418523Y858304D01*
X418554Y858217D01*
G02X418626Y857789I-1225J-426D01*
G02X416032I-1297J0D01*
G02X417087Y859064I1298J0D01*
G01X417177Y859081D01*
X417984Y860478D01*
X417953Y860565D01*
G02X417880Y860993I1225J429D01*
G37*
G36*
G01X425280D02*
G02X427876I1298J0D01*
G02X426820Y859718I-1298J0D01*
G01X426730Y859701D01*
X425923Y858304D01*
X425954Y858217D01*
G02X426026Y857789I-1225J-426D01*
G02X423432I-1297J0D01*
G02X424487Y859064I1298J0D01*
G01X424577Y859081D01*
X425384Y860478D01*
X425353Y860565D01*
G02X425280Y860993I1225J429D01*
G37*
G36*
G01X432682D02*
G02X435276I1297J0D01*
G02X434221Y859718I-1298J0D01*
G01X434131Y859701D01*
X433324Y858303D01*
X433354Y858217D01*
G02X433426Y857789I-1225J-426D01*
G02X430832I-1297J0D01*
G02X431888Y859064I1298J0D01*
G01X431978Y859081D01*
X432785Y860478D01*
X432754Y860565D01*
G02X432682Y860993I1225J426D01*
G37*
G36*
G01X440080D02*
G02X442676I1298J0D01*
G02X442603Y860564I-1297J0D01*
G01X442572Y860478D01*
X443378Y859081D01*
X443468Y859064D01*
G02X444526Y857789I-239J-1275D01*
G02X441932I-1297J0D01*
G02X442003Y858215I1297J3D01*
G01X442034Y858302D01*
X441226Y859701D01*
X441136Y859718D01*
G02X440080Y860993I242J1275D01*
G37*
G36*
G01X447482D02*
G02X450076I1297J0D01*
G02X450004Y860564I-1297J-3D01*
G01X449973Y860478D01*
X450779Y859081D01*
X450869Y859064D01*
G02X451926Y857789I-240J-1275D01*
G02X449332I-1297J0D01*
G01Y857791D01*
G02X449404Y858216I1297J-1D01*
G01X449434Y858303D01*
X448627Y859701D01*
X448537Y859718D01*
G02X447482Y860993I243J1275D01*
G37*
G36*
G01X454880D02*
G02X457476I1298J0D01*
G02X457403Y860564I-1297J0D01*
G01X457372Y860478D01*
X458178Y859081D01*
X458268Y859064D01*
G02X459326Y857789I-239J-1275D01*
G02X456732I-1297J0D01*
G02X456803Y858215I1297J3D01*
G01X456834Y858302D01*
X456026Y859701D01*
X455936Y859718D01*
G02X454880Y860993I242J1275D01*
G37*
G36*
G01X462280D02*
G02X464876I1298J0D01*
G02X464803Y860564I-1297J0D01*
G01X464772Y860478D01*
X465578Y859081D01*
X465668Y859064D01*
G02X466726Y857789I-239J-1275D01*
G02X464132I-1297J0D01*
G02X464203Y858215I1297J3D01*
G01X464234Y858302D01*
X463426Y859701D01*
X463336Y859718D01*
G02X462280Y860993I242J1275D01*
G37*
G36*
G01X469680D02*
G02X472276I1298J0D01*
G02X472203Y860564I-1297J0D01*
G01X472172Y860478D01*
X472978Y859081D01*
X473068Y859064D01*
G02X474126Y857789I-239J-1275D01*
G02X471532I-1297J0D01*
G02X471603Y858215I1297J3D01*
G01X471634Y858302D01*
X470826Y859701D01*
X470736Y859718D01*
G02X469680Y860993I242J1275D01*
G37*
G36*
G01X477080D02*
G02X479676I1298J0D01*
G02X479603Y860564I-1297J0D01*
G01X479572Y860478D01*
X480378Y859081D01*
X480468Y859064D01*
G02X481526Y857789I-239J-1275D01*
G02X478932I-1297J0D01*
G02X479003Y858215I1297J3D01*
G01X479034Y858302D01*
X478226Y859701D01*
X478136Y859718D01*
G02X477080Y860993I242J1275D01*
G37*
G36*
G01X484480D02*
G02X487076I1298J0D01*
G02X487003Y860564I-1297J0D01*
G01X486972Y860478D01*
X487778Y859081D01*
X487868Y859064D01*
G02X488926Y857789I-239J-1275D01*
G02X486332I-1297J0D01*
G02X486403Y858215I1297J3D01*
G01X486434Y858302D01*
X485626Y859701D01*
X485536Y859718D01*
G02X484480Y860993I242J1275D01*
G37*
G36*
G01X491880D02*
G02X494476I1298J0D01*
G02X494403Y860564I-1297J0D01*
G01X494372Y860478D01*
X495178Y859081D01*
X495268Y859064D01*
G02X496326Y857789I-239J-1275D01*
G02X493732I-1297J0D01*
G02X493803Y858215I1297J3D01*
G01X493834Y858302D01*
X493026Y859701D01*
X492936Y859718D01*
G02X491880Y860993I242J1275D01*
G37*
G36*
G01X499280D02*
G02X501876I1298J0D01*
G02X501803Y860564I-1297J0D01*
G01X501772Y860478D01*
X502578Y859081D01*
X502668Y859064D01*
G02X503726Y857789I-239J-1275D01*
G02X501132I-1297J0D01*
G02X501203Y858215I1297J3D01*
G01X501234Y858302D01*
X500426Y859701D01*
X500336Y859718D01*
G02X499280Y860993I242J1275D01*
G37*
G36*
G01X506680D02*
G02X509276I1298J0D01*
G02X509203Y860564I-1297J0D01*
G01X509172Y860478D01*
X509978Y859081D01*
X510068Y859064D01*
G02X511126Y857789I-239J-1275D01*
G02X508532I-1297J0D01*
G02X508603Y858215I1297J3D01*
G01X508634Y858302D01*
X507826Y859701D01*
X507736Y859718D01*
G02X506680Y860993I242J1275D01*
G37*
G36*
G01X514080D02*
G02X516676I1298J0D01*
G02X516603Y860564I-1297J0D01*
G01X516572Y860478D01*
X517378Y859081D01*
X517468Y859064D01*
G02X518526Y857789I-239J-1275D01*
G02X515932I-1297J0D01*
G02X516003Y858215I1297J3D01*
G01X516034Y858302D01*
X515226Y859701D01*
X515136Y859718D01*
G02X514080Y860993I242J1275D01*
G37*
G36*
G01X521480D02*
G02X524076I1298J0D01*
G02X524003Y860564I-1297J0D01*
G01X523972Y860478D01*
X524778Y859081D01*
X524868Y859064D01*
G02X525926Y857789I-239J-1275D01*
G02X523332I-1297J0D01*
G02X523403Y858215I1297J3D01*
G01X523434Y858302D01*
X522626Y859701D01*
X522536Y859718D01*
G02X521480Y860993I242J1275D01*
G37*
G36*
G01X1327422D02*
G02X1330018I1298J0D01*
G02X1328962Y859718I-1298J0D01*
G01X1328872Y859701D01*
X1328065Y858304D01*
X1328096Y858217D01*
G02X1328168Y857789I-1225J-426D01*
G02X1325574I-1297J0D01*
G02X1326629Y859064I1298J0D01*
G01X1326719Y859081D01*
X1327526Y860478D01*
X1327495Y860565D01*
G02X1327422Y860993I1225J429D01*
G37*
G36*
G01X1334822D02*
G02X1337418I1298J0D01*
G02X1336362Y859718I-1298J0D01*
G01X1336272Y859701D01*
X1335465Y858304D01*
X1335496Y858217D01*
G02X1335568Y857789I-1225J-426D01*
G02X1332974I-1297J0D01*
G02X1334029Y859064I1298J0D01*
G01X1334119Y859081D01*
X1334926Y860478D01*
X1334895Y860565D01*
G02X1334822Y860993I1225J429D01*
G37*
G36*
G01X1342222D02*
G02X1344818I1298J0D01*
G02X1343762Y859718I-1298J0D01*
G01X1343672Y859701D01*
X1342865Y858304D01*
X1342896Y858217D01*
G02X1342968Y857789I-1225J-426D01*
G02X1340374I-1297J0D01*
G02X1341429Y859064I1298J0D01*
G01X1341519Y859081D01*
X1342326Y860478D01*
X1342295Y860565D01*
G02X1342222Y860993I1225J429D01*
G37*
G36*
G01X1349622D02*
G02X1352218I1298J0D01*
G02X1351162Y859718I-1298J0D01*
G01X1351072Y859701D01*
X1350265Y858304D01*
X1350296Y858217D01*
G02X1350368Y857789I-1225J-426D01*
G02X1347774I-1297J0D01*
G02X1348829Y859064I1298J0D01*
G01X1348919Y859081D01*
X1349726Y860478D01*
X1349695Y860565D01*
G02X1349622Y860993I1225J429D01*
G37*
G36*
G01X1357022D02*
G02X1359618I1298J0D01*
G02X1358562Y859718I-1298J0D01*
G01X1358472Y859701D01*
X1357665Y858304D01*
X1357696Y858217D01*
G02X1357768Y857789I-1225J-426D01*
G02X1355174I-1297J0D01*
G02X1356229Y859064I1298J0D01*
G01X1356319Y859081D01*
X1357126Y860478D01*
X1357095Y860565D01*
G02X1357022Y860993I1225J429D01*
G37*
G36*
G01X1364422D02*
G02X1367018I1298J0D01*
G02X1365962Y859718I-1298J0D01*
G01X1365872Y859701D01*
X1365065Y858304D01*
X1365096Y858217D01*
G02X1365168Y857789I-1225J-426D01*
G02X1362574I-1297J0D01*
G02X1363629Y859064I1298J0D01*
G01X1363719Y859081D01*
X1364526Y860478D01*
X1364495Y860565D01*
G02X1364422Y860993I1225J429D01*
G37*
G36*
G01X1371822D02*
G02X1374418I1298J0D01*
G02X1373362Y859718I-1298J0D01*
G01X1373272Y859701D01*
X1372465Y858304D01*
X1372496Y858217D01*
G02X1372568Y857789I-1225J-426D01*
G02X1369974I-1297J0D01*
G02X1371029Y859064I1298J0D01*
G01X1371119Y859081D01*
X1371926Y860478D01*
X1371895Y860565D01*
G02X1371822Y860993I1225J429D01*
G37*
G36*
G01X1379222D02*
G02X1381818I1298J0D01*
G02X1380762Y859718I-1298J0D01*
G01X1380672Y859701D01*
X1379865Y858304D01*
X1379896Y858217D01*
G02X1379968Y857789I-1225J-426D01*
G02X1377374I-1297J0D01*
G02X1378429Y859064I1298J0D01*
G01X1378519Y859081D01*
X1379326Y860478D01*
X1379295Y860565D01*
G02X1379222Y860993I1225J429D01*
G37*
G36*
G01X1386622D02*
G02X1389218I1298J0D01*
G02X1388162Y859718I-1298J0D01*
G01X1388072Y859701D01*
X1387265Y858304D01*
X1387296Y858217D01*
G02X1387368Y857789I-1225J-426D01*
G02X1384774I-1297J0D01*
G02X1385829Y859064I1298J0D01*
G01X1385919Y859081D01*
X1386726Y860478D01*
X1386695Y860565D01*
G02X1386622Y860993I1225J429D01*
G37*
G36*
G01X1394022D02*
G02X1396618I1298J0D01*
G02X1395562Y859718I-1298J0D01*
G01X1395472Y859701D01*
X1394665Y858304D01*
X1394696Y858217D01*
G02X1394768Y857789I-1225J-426D01*
G02X1392174I-1297J0D01*
G02X1393229Y859064I1298J0D01*
G01X1393319Y859081D01*
X1394126Y860478D01*
X1394095Y860565D01*
G02X1394022Y860993I1225J429D01*
G37*
G36*
G01X1401422D02*
G02X1404018I1298J0D01*
G02X1402962Y859718I-1298J0D01*
G01X1402872Y859701D01*
X1402065Y858304D01*
X1402096Y858217D01*
G02X1402168Y857789I-1225J-426D01*
G02X1399574I-1297J0D01*
G02X1400629Y859064I1298J0D01*
G01X1400719Y859081D01*
X1401526Y860478D01*
X1401495Y860565D01*
G02X1401422Y860993I1225J429D01*
G37*
G36*
G01X1408824D02*
G02X1411418I1297J0D01*
G02X1410363Y859718I-1298J0D01*
G01X1410273Y859701D01*
X1409466Y858303D01*
X1409496Y858217D01*
G02X1409568Y857789I-1225J-426D01*
G02X1406974I-1297J0D01*
G02X1408030Y859064I1298J0D01*
G01X1408120Y859081D01*
X1408927Y860478D01*
X1408896Y860565D01*
G02X1408824Y860993I1225J426D01*
G37*
G36*
G01X1416222D02*
G02X1418818I1298J0D01*
G02X1418745Y860564I-1297J0D01*
G01X1418714Y860478D01*
X1419520Y859081D01*
X1419610Y859064D01*
G02X1420668Y857789I-239J-1275D01*
G02X1418074I-1297J0D01*
G02X1418145Y858215I1297J3D01*
G01X1418176Y858302D01*
X1417368Y859701D01*
X1417278Y859718D01*
G02X1416222Y860993I242J1275D01*
G37*
G36*
G01X1423624D02*
G02X1426218I1297J0D01*
G02X1426146Y860564I-1297J-3D01*
G01X1426115Y860478D01*
X1426921Y859081D01*
X1427011Y859064D01*
G02X1428068Y857789I-240J-1275D01*
G02X1425474I-1297J0D01*
G01Y857791D01*
G02X1425546Y858216I1297J-1D01*
G01X1425576Y858303D01*
X1424769Y859701D01*
X1424679Y859718D01*
G02X1423624Y860993I243J1275D01*
G37*
G36*
G01X1431022D02*
G02X1433618I1298J0D01*
G02X1433545Y860564I-1297J0D01*
G01X1433514Y860478D01*
X1434320Y859081D01*
X1434410Y859064D01*
G02X1435468Y857789I-239J-1275D01*
G02X1432874I-1297J0D01*
G02X1432945Y858215I1297J3D01*
G01X1432976Y858302D01*
X1432168Y859701D01*
X1432078Y859718D01*
G02X1431022Y860993I242J1275D01*
G37*
G36*
G01X1438422D02*
G02X1441018I1298J0D01*
G02X1440945Y860564I-1297J0D01*
G01X1440914Y860478D01*
X1441720Y859081D01*
X1441810Y859064D01*
G02X1442868Y857789I-239J-1275D01*
G02X1440274I-1297J0D01*
G02X1440345Y858215I1297J3D01*
G01X1440376Y858302D01*
X1439568Y859701D01*
X1439478Y859718D01*
G02X1438422Y860993I242J1275D01*
G37*
G36*
G01X1445822D02*
G02X1448418I1298J0D01*
G02X1448345Y860564I-1297J0D01*
G01X1448314Y860478D01*
X1449120Y859081D01*
X1449210Y859064D01*
G02X1450268Y857789I-239J-1275D01*
G02X1447674I-1297J0D01*
G02X1447745Y858215I1297J3D01*
G01X1447776Y858302D01*
X1446968Y859701D01*
X1446878Y859718D01*
G02X1445822Y860993I242J1275D01*
G37*
G36*
G01X1453222D02*
G02X1455818I1298J0D01*
G02X1455745Y860564I-1297J0D01*
G01X1455714Y860478D01*
X1456520Y859081D01*
X1456610Y859064D01*
G02X1457668Y857789I-239J-1275D01*
G02X1455074I-1297J0D01*
G02X1455145Y858215I1297J3D01*
G01X1455176Y858302D01*
X1454368Y859701D01*
X1454278Y859718D01*
G02X1453222Y860993I242J1275D01*
G37*
G36*
G01X1460622D02*
G02X1463218I1298J0D01*
G02X1463145Y860564I-1297J0D01*
G01X1463114Y860478D01*
X1463920Y859081D01*
X1464010Y859064D01*
G02X1465068Y857789I-239J-1275D01*
G02X1462474I-1297J0D01*
G02X1462545Y858215I1297J3D01*
G01X1462576Y858302D01*
X1461768Y859701D01*
X1461678Y859718D01*
G02X1460622Y860993I242J1275D01*
G37*
G36*
G01X1468022D02*
G02X1470618I1298J0D01*
G02X1470545Y860564I-1297J0D01*
G01X1470514Y860478D01*
X1471320Y859081D01*
X1471410Y859064D01*
G02X1472468Y857789I-239J-1275D01*
G02X1469874I-1297J0D01*
G02X1469945Y858215I1297J3D01*
G01X1469976Y858302D01*
X1469168Y859701D01*
X1469078Y859718D01*
G02X1468022Y860993I242J1275D01*
G37*
G36*
G01X1475422D02*
G02X1478018I1298J0D01*
G02X1477945Y860564I-1297J0D01*
G01X1477914Y860478D01*
X1478720Y859081D01*
X1478810Y859064D01*
G02X1479868Y857789I-239J-1275D01*
G02X1477274I-1297J0D01*
G02X1477345Y858215I1297J3D01*
G01X1477376Y858302D01*
X1476568Y859701D01*
X1476478Y859718D01*
G02X1475422Y860993I242J1275D01*
G37*
G36*
G01X1482822D02*
G02X1485418I1298J0D01*
G02X1485345Y860564I-1297J0D01*
G01X1485314Y860478D01*
X1486120Y859081D01*
X1486210Y859064D01*
G02X1487268Y857789I-239J-1275D01*
G02X1484674I-1297J0D01*
G02X1484745Y858215I1297J3D01*
G01X1484776Y858302D01*
X1483968Y859701D01*
X1483878Y859718D01*
G02X1482822Y860993I242J1275D01*
G37*
G36*
G01X1490222D02*
G02X1492818I1298J0D01*
G02X1492745Y860564I-1297J0D01*
G01X1492714Y860478D01*
X1493520Y859081D01*
X1493610Y859064D01*
G02X1494668Y857789I-239J-1275D01*
G02X1492074I-1297J0D01*
G02X1492145Y858215I1297J3D01*
G01X1492176Y858302D01*
X1491368Y859701D01*
X1491278Y859718D01*
G02X1490222Y860993I242J1275D01*
G37*
G36*
G01X1497622D02*
G02X1500218I1298J0D01*
G02X1500145Y860564I-1297J0D01*
G01X1500114Y860478D01*
X1500920Y859081D01*
X1501010Y859064D01*
G02X1502068Y857789I-239J-1275D01*
G02X1499474I-1297J0D01*
G02X1499545Y858215I1297J3D01*
G01X1499576Y858302D01*
X1498768Y859701D01*
X1498678Y859718D01*
G02X1497622Y860993I242J1275D01*
G37*
G36*
G01X353132Y870606D02*
G02X355726I1297J0D01*
G02X355654Y870177I-1297J-3D01*
G01X355623Y870091D01*
X356430Y868693D01*
X356520Y868676D01*
G02X357576Y867401I-242J-1275D01*
G02X354980I-1298J0D01*
G02X355053Y867830I1297J0D01*
G01X355084Y867916D01*
X354277Y869314D01*
X354187Y869331D01*
G02X353132Y870606I243J1275D01*
G37*
G36*
G01X360532D02*
G02X363126I1297J0D01*
G02X363054Y870177I-1297J-3D01*
G01X363023Y870091D01*
X363830Y868693D01*
X363920Y868676D01*
G02X364976Y867401I-242J-1275D01*
G02X362380I-1298J0D01*
G02X362453Y867830I1297J0D01*
G01X362484Y867916D01*
X361677Y869314D01*
X361587Y869331D01*
G02X360532Y870606I243J1275D01*
G37*
G36*
G01X367932D02*
G02X370526I1297J0D01*
G02X370454Y870177I-1297J-3D01*
G01X370423Y870091D01*
X371230Y868693D01*
X371320Y868676D01*
G02X372376Y867401I-242J-1275D01*
G02X369780I-1298J0D01*
G02X369853Y867830I1297J0D01*
G01X369884Y867916D01*
X369077Y869314D01*
X368987Y869331D01*
G02X367932Y870606I243J1275D01*
G37*
G36*
G01X375332D02*
G02X377926I1297J0D01*
G02X377854Y870177I-1297J-3D01*
G01X377823Y870091D01*
X378630Y868693D01*
X378720Y868676D01*
G02X379776Y867401I-242J-1275D01*
G02X377180I-1298J0D01*
G02X377253Y867830I1297J0D01*
G01X377284Y867916D01*
X376477Y869314D01*
X376387Y869331D01*
G02X375332Y870606I243J1275D01*
G37*
G36*
G01X382732D02*
G02X385326I1297J0D01*
G02X385254Y870177I-1297J-3D01*
G01X385223Y870091D01*
X386030Y868693D01*
X386120Y868676D01*
G02X387176Y867401I-242J-1275D01*
G02X384580I-1298J0D01*
G02X384653Y867830I1297J0D01*
G01X384684Y867916D01*
X383877Y869314D01*
X383787Y869331D01*
G02X382732Y870606I243J1275D01*
G37*
G36*
G01X390132D02*
G02X392726I1297J0D01*
G02X392654Y870177I-1297J-3D01*
G01X392623Y870091D01*
X393430Y868693D01*
X393520Y868676D01*
G02X394576Y867401I-242J-1275D01*
G02X391980I-1298J0D01*
G02X392053Y867830I1297J0D01*
G01X392084Y867916D01*
X391277Y869314D01*
X391187Y869331D01*
G02X390132Y870606I243J1275D01*
G37*
G36*
G01X397532D02*
G02X400126I1297J0D01*
G02X400054Y870177I-1297J-3D01*
G01X400023Y870091D01*
X400830Y868693D01*
X400920Y868676D01*
G02X401976Y867401I-242J-1275D01*
G02X399380I-1298J0D01*
G02X399453Y867830I1297J0D01*
G01X399484Y867916D01*
X398677Y869314D01*
X398587Y869331D01*
G02X397532Y870606I243J1275D01*
G37*
G36*
G01X404932D02*
G02X407526I1297J0D01*
G02X407454Y870177I-1297J-3D01*
G01X407423Y870091D01*
X408230Y868693D01*
X408320Y868676D01*
G02X409376Y867401I-242J-1275D01*
G02X406780I-1298J0D01*
G02X406853Y867830I1297J0D01*
G01X406884Y867916D01*
X406077Y869314D01*
X405987Y869331D01*
G02X404932Y870606I243J1275D01*
G37*
G36*
G01X416032D02*
G02X418626I1297J0D01*
G02X417571Y869331I-1298J0D01*
G01X417481Y869314D01*
X416673Y867915D01*
X416703Y867828D01*
G02X416776Y867401I-1225J-429D01*
G02X414180I-1298J0D01*
G02X415238Y868676I1297J0D01*
G01X415328Y868693D01*
X416135Y870091D01*
X416104Y870178D01*
G02X416032Y870606I1225J426D01*
G37*
G36*
G01X423432D02*
G02X426026I1297J0D01*
G02X424971Y869331I-1298J0D01*
G01X424881Y869314D01*
X424073Y867915D01*
X424103Y867828D01*
G02X424176Y867401I-1225J-429D01*
G02X421580I-1298J0D01*
G02X422638Y868676I1297J0D01*
G01X422728Y868693D01*
X423535Y870091D01*
X423504Y870178D01*
G02X423432Y870606I1225J426D01*
G37*
G36*
G01X430832D02*
G02X433426I1297J0D01*
G02X432371Y869331I-1298J0D01*
G01X432281Y869314D01*
X431473Y867915D01*
X431503Y867828D01*
G02X431576Y867401I-1225J-429D01*
G02X428980I-1298J0D01*
G02X430038Y868676I1297J0D01*
G01X430128Y868693D01*
X430935Y870091D01*
X430904Y870178D01*
G02X430832Y870606I1225J426D01*
G37*
G36*
G01X438232D02*
G02X440826I1297J0D01*
G02X439771Y869331I-1298J0D01*
G01X439681Y869314D01*
X438873Y867915D01*
X438903Y867828D01*
G02X438976Y867401I-1225J-429D01*
G02X436380I-1298J0D01*
G02X437438Y868676I1297J0D01*
G01X437528Y868693D01*
X438335Y870091D01*
X438304Y870178D01*
G02X438232Y870606I1225J426D01*
G37*
G36*
G01X445632D02*
G02X448226I1297J0D01*
G02X447171Y869331I-1298J0D01*
G01X447081Y869314D01*
X446273Y867915D01*
X446303Y867828D01*
G02X446376Y867401I-1225J-429D01*
G02X443780I-1298J0D01*
G02X444838Y868676I1297J0D01*
G01X444928Y868693D01*
X445735Y870091D01*
X445704Y870178D01*
G02X445632Y870606I1225J426D01*
G37*
G36*
G01X453032D02*
G02X455626I1297J0D01*
G02X454571Y869331I-1298J0D01*
G01X454481Y869314D01*
X453673Y867915D01*
X453703Y867828D01*
G02X453776Y867401I-1225J-429D01*
G02X451180I-1298J0D01*
G02X452238Y868676I1297J0D01*
G01X452328Y868693D01*
X453135Y870091D01*
X453104Y870178D01*
G02X453032Y870606I1225J426D01*
G37*
G36*
G01X460432D02*
G02X463026I1297J0D01*
G02X461971Y869331I-1298J0D01*
G01X461881Y869314D01*
X461073Y867915D01*
X461103Y867828D01*
G02X461176Y867401I-1225J-429D01*
G02X458580I-1298J0D01*
G02X459638Y868676I1297J0D01*
G01X459728Y868693D01*
X460535Y870091D01*
X460504Y870178D01*
G02X460432Y870606I1225J426D01*
G37*
G36*
G01X467832D02*
G02X470426I1297J0D01*
G02X469371Y869331I-1298J0D01*
G01X469281Y869314D01*
X468473Y867915D01*
X468503Y867828D01*
G02X468576Y867401I-1225J-429D01*
G02X465980I-1298J0D01*
G02X467038Y868676I1297J0D01*
G01X467128Y868693D01*
X467935Y870091D01*
X467904Y870178D01*
G02X467832Y870606I1225J426D01*
G37*
G36*
G01X475232D02*
G02X477826I1297J0D01*
G02X476771Y869331I-1298J0D01*
G01X476681Y869314D01*
X475873Y867915D01*
X475903Y867828D01*
G02X475976Y867401I-1225J-429D01*
G02X473380I-1298J0D01*
G02X474438Y868676I1297J0D01*
G01X474528Y868693D01*
X475335Y870091D01*
X475304Y870178D01*
G02X475232Y870606I1225J426D01*
G37*
G36*
G01X482632D02*
G02X485226I1297J0D01*
G02X484171Y869331I-1298J0D01*
G01X484081Y869314D01*
X483273Y867915D01*
X483303Y867828D01*
G02X483376Y867401I-1225J-429D01*
G02X480780I-1298J0D01*
G02X481838Y868676I1297J0D01*
G01X481928Y868693D01*
X482735Y870091D01*
X482704Y870178D01*
G02X482632Y870606I1225J426D01*
G37*
G36*
G01X490032D02*
G02X492626I1297J0D01*
G02X491571Y869331I-1298J0D01*
G01X491481Y869314D01*
X490673Y867915D01*
X490703Y867828D01*
G02X490776Y867401I-1225J-429D01*
G02X488180I-1298J0D01*
G02X489238Y868676I1297J0D01*
G01X489328Y868693D01*
X490135Y870091D01*
X490104Y870178D01*
G02X490032Y870606I1225J426D01*
G37*
G36*
G01X497432D02*
G02X500026I1297J0D01*
G02X498971Y869331I-1298J0D01*
G01X498881Y869314D01*
X498073Y867915D01*
X498103Y867828D01*
G02X498176Y867401I-1225J-429D01*
G02X495580I-1298J0D01*
G02X496638Y868676I1297J0D01*
G01X496728Y868693D01*
X497535Y870091D01*
X497504Y870178D01*
G02X497432Y870606I1225J426D01*
G37*
G36*
G01X504832D02*
G02X507426I1297J0D01*
G02X506371Y869331I-1298J0D01*
G01X506281Y869314D01*
X505473Y867915D01*
X505503Y867828D01*
G02X505576Y867401I-1225J-429D01*
G02X502980I-1298J0D01*
G02X504038Y868676I1297J0D01*
G01X504128Y868693D01*
X504935Y870091D01*
X504904Y870178D01*
G02X504832Y870606I1225J426D01*
G37*
G36*
G01X512232D02*
G02X514826I1297J0D01*
G02X513771Y869331I-1298J0D01*
G01X513681Y869314D01*
X512873Y867915D01*
X512903Y867828D01*
G02X512976Y867401I-1225J-429D01*
G02X510380I-1298J0D01*
G02X511438Y868676I1297J0D01*
G01X511528Y868693D01*
X512335Y870091D01*
X512304Y870178D01*
G02X512232Y870606I1225J426D01*
G37*
G36*
G01X519632D02*
G02X522226I1297J0D01*
G02X521171Y869331I-1298J0D01*
G01X521081Y869314D01*
X520273Y867915D01*
X520303Y867828D01*
G02X520376Y867401I-1225J-429D01*
G02X517780I-1298J0D01*
G02X518838Y868676I1297J0D01*
G01X518928Y868693D01*
X519735Y870091D01*
X519704Y870178D01*
G02X519632Y870606I1225J426D01*
G37*
G36*
G01X527032D02*
G02X529626I1297J0D01*
G02X528571Y869331I-1298J0D01*
G01X528481Y869314D01*
X527674Y867916D01*
X527704Y867829D01*
G02X527776Y867401I-1225J-426D01*
G02X525182I-1297J0D01*
G02X526238Y868676I1298J0D01*
G01X526328Y868693D01*
X527135Y870091D01*
X527104Y870178D01*
G02X527032Y870606I1225J426D01*
G37*
G36*
G01X1329274D02*
G02X1331868I1297J0D01*
G02X1331796Y870177I-1297J-3D01*
G01X1331765Y870091D01*
X1332572Y868693D01*
X1332662Y868676D01*
G02X1333718Y867401I-242J-1275D01*
G02X1331122I-1298J0D01*
G02X1331195Y867830I1297J0D01*
G01X1331226Y867916D01*
X1330419Y869314D01*
X1330329Y869331D01*
G02X1329274Y870606I243J1275D01*
G37*
G36*
G01X1336674D02*
G02X1339268I1297J0D01*
G02X1339196Y870177I-1297J-3D01*
G01X1339165Y870091D01*
X1339972Y868693D01*
X1340062Y868676D01*
G02X1341118Y867401I-242J-1275D01*
G02X1338522I-1298J0D01*
G02X1338595Y867830I1297J0D01*
G01X1338626Y867916D01*
X1337819Y869314D01*
X1337729Y869331D01*
G02X1336674Y870606I243J1275D01*
G37*
G36*
G01X1344074D02*
G02X1346668I1297J0D01*
G02X1346596Y870177I-1297J-3D01*
G01X1346565Y870091D01*
X1347372Y868693D01*
X1347462Y868676D01*
G02X1348518Y867401I-242J-1275D01*
G02X1345922I-1298J0D01*
G02X1345995Y867830I1297J0D01*
G01X1346026Y867916D01*
X1345219Y869314D01*
X1345129Y869331D01*
G02X1344074Y870606I243J1275D01*
G37*
G36*
G01X1351474D02*
G02X1354068I1297J0D01*
G02X1353996Y870177I-1297J-3D01*
G01X1353965Y870091D01*
X1354772Y868693D01*
X1354862Y868676D01*
G02X1355918Y867401I-242J-1275D01*
G02X1353322I-1298J0D01*
G02X1353395Y867830I1297J0D01*
G01X1353426Y867916D01*
X1352619Y869314D01*
X1352529Y869331D01*
G02X1351474Y870606I243J1275D01*
G37*
G36*
G01X1358874D02*
G02X1361468I1297J0D01*
G02X1361396Y870177I-1297J-3D01*
G01X1361365Y870091D01*
X1362172Y868693D01*
X1362262Y868676D01*
G02X1363318Y867401I-242J-1275D01*
G02X1360722I-1298J0D01*
G02X1360795Y867830I1297J0D01*
G01X1360826Y867916D01*
X1360019Y869314D01*
X1359929Y869331D01*
G02X1358874Y870606I243J1275D01*
G37*
G36*
G01X1366274D02*
G02X1368868I1297J0D01*
G02X1368796Y870177I-1297J-3D01*
G01X1368765Y870091D01*
X1369572Y868693D01*
X1369662Y868676D01*
G02X1370718Y867401I-242J-1275D01*
G02X1368122I-1298J0D01*
G02X1368195Y867830I1297J0D01*
G01X1368226Y867916D01*
X1367419Y869314D01*
X1367329Y869331D01*
G02X1366274Y870606I243J1275D01*
G37*
G36*
G01X1373674D02*
G02X1376268I1297J0D01*
G02X1376196Y870177I-1297J-3D01*
G01X1376165Y870091D01*
X1376972Y868693D01*
X1377062Y868676D01*
G02X1378118Y867401I-242J-1275D01*
G02X1375522I-1298J0D01*
G02X1375595Y867830I1297J0D01*
G01X1375626Y867916D01*
X1374819Y869314D01*
X1374729Y869331D01*
G02X1373674Y870606I243J1275D01*
G37*
G36*
G01X1381074D02*
G02X1383668I1297J0D01*
G02X1383596Y870177I-1297J-3D01*
G01X1383565Y870091D01*
X1384372Y868693D01*
X1384462Y868676D01*
G02X1385518Y867401I-242J-1275D01*
G02X1382922I-1298J0D01*
G02X1382995Y867830I1297J0D01*
G01X1383026Y867916D01*
X1382219Y869314D01*
X1382129Y869331D01*
G02X1381074Y870606I243J1275D01*
G37*
G36*
G01X1392174D02*
G02X1394768I1297J0D01*
G02X1393713Y869331I-1298J0D01*
G01X1393623Y869314D01*
X1392815Y867915D01*
X1392845Y867828D01*
G02X1392918Y867401I-1225J-429D01*
G02X1390322I-1298J0D01*
G02X1391380Y868676I1297J0D01*
G01X1391470Y868693D01*
X1392277Y870091D01*
X1392246Y870178D01*
G02X1392174Y870606I1225J426D01*
G37*
G36*
G01X1399574D02*
G02X1402168I1297J0D01*
G02X1401113Y869331I-1298J0D01*
G01X1401023Y869314D01*
X1400215Y867915D01*
X1400245Y867828D01*
G02X1400318Y867401I-1225J-429D01*
G02X1397722I-1298J0D01*
G02X1398780Y868676I1297J0D01*
G01X1398870Y868693D01*
X1399677Y870091D01*
X1399646Y870178D01*
G02X1399574Y870606I1225J426D01*
G37*
G36*
G01X1406974D02*
G02X1409568I1297J0D01*
G02X1408513Y869331I-1298J0D01*
G01X1408423Y869314D01*
X1407615Y867915D01*
X1407645Y867828D01*
G02X1407718Y867401I-1225J-429D01*
G02X1405122I-1298J0D01*
G02X1406180Y868676I1297J0D01*
G01X1406270Y868693D01*
X1407077Y870091D01*
X1407046Y870178D01*
G02X1406974Y870606I1225J426D01*
G37*
G36*
G01X1414374D02*
G02X1416968I1297J0D01*
G02X1415913Y869331I-1298J0D01*
G01X1415823Y869314D01*
X1415015Y867915D01*
X1415045Y867828D01*
G02X1415118Y867401I-1225J-429D01*
G02X1412522I-1298J0D01*
G02X1413580Y868676I1297J0D01*
G01X1413670Y868693D01*
X1414477Y870091D01*
X1414446Y870178D01*
G02X1414374Y870606I1225J426D01*
G37*
G36*
G01X1421774D02*
G02X1424368I1297J0D01*
G02X1423313Y869331I-1298J0D01*
G01X1423223Y869314D01*
X1422415Y867915D01*
X1422445Y867828D01*
G02X1422518Y867401I-1225J-429D01*
G02X1419922I-1298J0D01*
G02X1420980Y868676I1297J0D01*
G01X1421070Y868693D01*
X1421877Y870091D01*
X1421846Y870178D01*
G02X1421774Y870606I1225J426D01*
G37*
G36*
G01X1429174D02*
G02X1431768I1297J0D01*
G02X1430713Y869331I-1298J0D01*
G01X1430623Y869314D01*
X1429815Y867915D01*
X1429845Y867828D01*
G02X1429918Y867401I-1225J-429D01*
G02X1427322I-1298J0D01*
G02X1428380Y868676I1297J0D01*
G01X1428470Y868693D01*
X1429277Y870091D01*
X1429246Y870178D01*
G02X1429174Y870606I1225J426D01*
G37*
G36*
G01X1436574D02*
G02X1439168I1297J0D01*
G02X1438113Y869331I-1298J0D01*
G01X1438023Y869314D01*
X1437215Y867915D01*
X1437245Y867828D01*
G02X1437318Y867401I-1225J-429D01*
G02X1434722I-1298J0D01*
G02X1435780Y868676I1297J0D01*
G01X1435870Y868693D01*
X1436677Y870091D01*
X1436646Y870178D01*
G02X1436574Y870606I1225J426D01*
G37*
G36*
G01X1443974D02*
G02X1446568I1297J0D01*
G02X1445513Y869331I-1298J0D01*
G01X1445423Y869314D01*
X1444615Y867915D01*
X1444645Y867828D01*
G02X1444718Y867401I-1225J-429D01*
G02X1442122I-1298J0D01*
G02X1443180Y868676I1297J0D01*
G01X1443270Y868693D01*
X1444077Y870091D01*
X1444046Y870178D01*
G02X1443974Y870606I1225J426D01*
G37*
G36*
G01X1451374D02*
G02X1453968I1297J0D01*
G02X1452913Y869331I-1298J0D01*
G01X1452823Y869314D01*
X1452015Y867915D01*
X1452045Y867828D01*
G02X1452118Y867401I-1225J-429D01*
G02X1449522I-1298J0D01*
G02X1450580Y868676I1297J0D01*
G01X1450670Y868693D01*
X1451477Y870091D01*
X1451446Y870178D01*
G02X1451374Y870606I1225J426D01*
G37*
G36*
G01X1458774D02*
G02X1461368I1297J0D01*
G02X1460313Y869331I-1298J0D01*
G01X1460223Y869314D01*
X1459415Y867915D01*
X1459445Y867828D01*
G02X1459518Y867401I-1225J-429D01*
G02X1456922I-1298J0D01*
G02X1457980Y868676I1297J0D01*
G01X1458070Y868693D01*
X1458877Y870091D01*
X1458846Y870178D01*
G02X1458774Y870606I1225J426D01*
G37*
G36*
G01X1466174D02*
G02X1468768I1297J0D01*
G02X1467713Y869331I-1298J0D01*
G01X1467623Y869314D01*
X1466815Y867915D01*
X1466845Y867828D01*
G02X1466918Y867401I-1225J-429D01*
G02X1464322I-1298J0D01*
G02X1465380Y868676I1297J0D01*
G01X1465470Y868693D01*
X1466277Y870091D01*
X1466246Y870178D01*
G02X1466174Y870606I1225J426D01*
G37*
G36*
G01X1473574D02*
G02X1476168I1297J0D01*
G02X1475113Y869331I-1298J0D01*
G01X1475023Y869314D01*
X1474215Y867915D01*
X1474245Y867828D01*
G02X1474318Y867401I-1225J-429D01*
G02X1471722I-1298J0D01*
G02X1472780Y868676I1297J0D01*
G01X1472870Y868693D01*
X1473677Y870091D01*
X1473646Y870178D01*
G02X1473574Y870606I1225J426D01*
G37*
G36*
G01X1480974D02*
G02X1483568I1297J0D01*
G02X1482513Y869331I-1298J0D01*
G01X1482423Y869314D01*
X1481615Y867915D01*
X1481645Y867828D01*
G02X1481718Y867401I-1225J-429D01*
G02X1479122I-1298J0D01*
G02X1480180Y868676I1297J0D01*
G01X1480270Y868693D01*
X1481077Y870091D01*
X1481046Y870178D01*
G02X1480974Y870606I1225J426D01*
G37*
G36*
G01X1488374D02*
G02X1490968I1297J0D01*
G02X1489913Y869331I-1298J0D01*
G01X1489823Y869314D01*
X1489015Y867915D01*
X1489045Y867828D01*
G02X1489118Y867401I-1225J-429D01*
G02X1486522I-1298J0D01*
G02X1487580Y868676I1297J0D01*
G01X1487670Y868693D01*
X1488477Y870091D01*
X1488446Y870178D01*
G02X1488374Y870606I1225J426D01*
G37*
G36*
G01X1495774D02*
G02X1498368I1297J0D01*
G02X1497313Y869331I-1298J0D01*
G01X1497223Y869314D01*
X1496415Y867915D01*
X1496445Y867828D01*
G02X1496518Y867401I-1225J-429D01*
G02X1493922I-1298J0D01*
G02X1494980Y868676I1297J0D01*
G01X1495070Y868693D01*
X1495877Y870091D01*
X1495846Y870178D01*
G02X1495774Y870606I1225J426D01*
G37*
G36*
G01X1503174D02*
G02X1505768I1297J0D01*
G02X1504713Y869331I-1298J0D01*
G01X1504623Y869314D01*
X1503816Y867916D01*
X1503846Y867829D01*
G02X1503918Y867401I-1225J-426D01*
G02X1501324I-1297J0D01*
G02X1502380Y868676I1298J0D01*
G01X1502470Y868693D01*
X1503277Y870091D01*
X1503246Y870178D01*
G02X1503174Y870606I1225J426D01*
G37*
G36*
G01X351280Y873810D02*
G02X353876I1298J0D01*
G02X352820Y872535I-1298J0D01*
G01X352730Y872518D01*
X351923Y871121D01*
X351954Y871034D01*
G02X352026Y870606I-1225J-426D01*
G02X349432I-1297J0D01*
G02X350487Y871881I1298J0D01*
G01X350577Y871898D01*
X351384Y873295D01*
X351353Y873382D01*
G02X351280Y873810I1225J429D01*
G37*
G36*
G01X358680D02*
G02X361276I1298J0D01*
G02X360220Y872535I-1298J0D01*
G01X360130Y872518D01*
X359323Y871121D01*
X359354Y871034D01*
G02X359426Y870606I-1225J-426D01*
G02X356832I-1297J0D01*
G02X357887Y871881I1298J0D01*
G01X357977Y871898D01*
X358784Y873295D01*
X358753Y873382D01*
G02X358680Y873810I1225J429D01*
G37*
G36*
G01X366080D02*
G02X368676I1298J0D01*
G02X367620Y872535I-1298J0D01*
G01X367530Y872518D01*
X366723Y871121D01*
X366754Y871034D01*
G02X366826Y870606I-1225J-426D01*
G02X364232I-1297J0D01*
G02X365287Y871881I1298J0D01*
G01X365377Y871898D01*
X366184Y873295D01*
X366153Y873382D01*
G02X366080Y873810I1225J429D01*
G37*
G36*
G01X373480D02*
G02X376076I1298J0D01*
G02X375020Y872535I-1298J0D01*
G01X374930Y872518D01*
X374123Y871121D01*
X374154Y871034D01*
G02X374226Y870606I-1225J-426D01*
G02X371632I-1297J0D01*
G02X372687Y871881I1298J0D01*
G01X372777Y871898D01*
X373584Y873295D01*
X373553Y873382D01*
G02X373480Y873810I1225J429D01*
G37*
G36*
G01X380880D02*
G02X383476I1298J0D01*
G02X382420Y872535I-1298J0D01*
G01X382330Y872518D01*
X381523Y871121D01*
X381554Y871034D01*
G02X381626Y870606I-1225J-426D01*
G02X379032I-1297J0D01*
G02X380087Y871881I1298J0D01*
G01X380177Y871898D01*
X380984Y873295D01*
X380953Y873382D01*
G02X380880Y873810I1225J429D01*
G37*
G36*
G01X388280D02*
G02X390876I1298J0D01*
G02X389820Y872535I-1298J0D01*
G01X389730Y872518D01*
X388923Y871121D01*
X388954Y871034D01*
G02X389026Y870606I-1225J-426D01*
G02X386432I-1297J0D01*
G02X387487Y871881I1298J0D01*
G01X387577Y871898D01*
X388384Y873295D01*
X388353Y873382D01*
G02X388280Y873810I1225J429D01*
G37*
G36*
G01X395680D02*
G02X398276I1298J0D01*
G02X397220Y872535I-1298J0D01*
G01X397130Y872518D01*
X396323Y871121D01*
X396354Y871034D01*
G02X396426Y870606I-1225J-426D01*
G02X393832I-1297J0D01*
G02X394887Y871881I1298J0D01*
G01X394977Y871898D01*
X395784Y873295D01*
X395753Y873382D01*
G02X395680Y873810I1225J429D01*
G37*
G36*
G01X403080D02*
G02X405676I1298J0D01*
G02X404620Y872535I-1298J0D01*
G01X404530Y872518D01*
X403723Y871121D01*
X403754Y871034D01*
G02X403826Y870606I-1225J-426D01*
G02X401232I-1297J0D01*
G02X402287Y871881I1298J0D01*
G01X402377Y871898D01*
X403184Y873295D01*
X403153Y873382D01*
G02X403080Y873810I1225J429D01*
G37*
G36*
G01X410480D02*
G02X413076I1298J0D01*
G02X413003Y873381I-1297J0D01*
G01X412972Y873295D01*
X413778Y871898D01*
X413868Y871881D01*
G02X414926Y870606I-239J-1275D01*
G02X412332I-1297J0D01*
G02X412403Y871032I1297J3D01*
G01X412434Y871119D01*
X411626Y872518D01*
X411536Y872535D01*
G02X410480Y873810I242J1275D01*
G37*
G36*
G01X417880D02*
G02X420476I1298J0D01*
G02X420403Y873381I-1297J0D01*
G01X420372Y873295D01*
X421178Y871898D01*
X421268Y871881D01*
G02X422326Y870606I-239J-1275D01*
G02X419732I-1297J0D01*
G02X419803Y871032I1297J3D01*
G01X419834Y871119D01*
X419026Y872518D01*
X418936Y872535D01*
G02X417880Y873810I242J1275D01*
G37*
G36*
G01X425280D02*
G02X427876I1298J0D01*
G02X427803Y873381I-1297J0D01*
G01X427772Y873295D01*
X428578Y871898D01*
X428668Y871881D01*
G02X429726Y870606I-239J-1275D01*
G02X427132I-1297J0D01*
G02X427203Y871032I1297J3D01*
G01X427234Y871119D01*
X426426Y872518D01*
X426336Y872535D01*
G02X425280Y873810I242J1275D01*
G37*
G36*
G01X432682D02*
G02X435276I1297J0D01*
G02X435204Y873381I-1297J-3D01*
G01X435173Y873295D01*
X435979Y871898D01*
X436069Y871881D01*
G02X437126Y870606I-240J-1275D01*
G02X434532I-1297J0D01*
G01Y870608D01*
G02X434604Y871033I1297J-1D01*
G01X434634Y871120D01*
X433827Y872518D01*
X433737Y872535D01*
G02X432682Y873810I243J1275D01*
G37*
G36*
G01X440080D02*
G02X442676I1298J0D01*
G02X442603Y873381I-1297J0D01*
G01X442572Y873295D01*
X443378Y871898D01*
X443468Y871881D01*
G02X444526Y870606I-239J-1275D01*
G02X441932I-1297J0D01*
G02X442003Y871032I1297J3D01*
G01X442034Y871119D01*
X441226Y872518D01*
X441136Y872535D01*
G02X440080Y873810I242J1275D01*
G37*
G36*
G01X447482D02*
G02X450076I1297J0D01*
G02X450004Y873381I-1297J-3D01*
G01X449973Y873295D01*
X450779Y871898D01*
X450869Y871881D01*
G02X451926Y870606I-240J-1275D01*
G02X449332I-1297J0D01*
G01Y870608D01*
G02X449404Y871033I1297J-1D01*
G01X449434Y871120D01*
X448627Y872518D01*
X448537Y872535D01*
G02X447482Y873810I243J1275D01*
G37*
G36*
G01X454880D02*
G02X457476I1298J0D01*
G02X457403Y873381I-1297J0D01*
G01X457372Y873295D01*
X458178Y871898D01*
X458268Y871881D01*
G02X459326Y870606I-239J-1275D01*
G02X456732I-1297J0D01*
G02X456803Y871032I1297J3D01*
G01X456834Y871119D01*
X456026Y872518D01*
X455936Y872535D01*
G02X454880Y873810I242J1275D01*
G37*
G36*
G01X462280D02*
G02X464876I1298J0D01*
G02X464803Y873381I-1297J0D01*
G01X464772Y873295D01*
X465578Y871898D01*
X465668Y871881D01*
G02X466726Y870606I-239J-1275D01*
G02X464132I-1297J0D01*
G02X464203Y871032I1297J3D01*
G01X464234Y871119D01*
X463426Y872518D01*
X463336Y872535D01*
G02X462280Y873810I242J1275D01*
G37*
G36*
G01X477080D02*
G02X479676I1298J0D01*
G02X479603Y873381I-1297J0D01*
G01X479572Y873295D01*
X480378Y871898D01*
X480468Y871881D01*
G02X481526Y870606I-239J-1275D01*
G02X478932I-1297J0D01*
G02X479003Y871032I1297J3D01*
G01X479034Y871119D01*
X478226Y872518D01*
X478136Y872535D01*
G02X477080Y873810I242J1275D01*
G37*
G36*
G01X484480D02*
G02X487076I1298J0D01*
G02X487003Y873381I-1297J0D01*
G01X486972Y873295D01*
X487778Y871898D01*
X487868Y871881D01*
G02X488926Y870606I-239J-1275D01*
G02X486332I-1297J0D01*
G02X486403Y871032I1297J3D01*
G01X486434Y871119D01*
X485626Y872518D01*
X485536Y872535D01*
G02X484480Y873810I242J1275D01*
G37*
G36*
G01X491880D02*
G02X494476I1298J0D01*
G02X494403Y873381I-1297J0D01*
G01X494372Y873295D01*
X495178Y871898D01*
X495268Y871881D01*
G02X496326Y870606I-239J-1275D01*
G02X493732I-1297J0D01*
G02X493803Y871032I1297J3D01*
G01X493834Y871119D01*
X493026Y872518D01*
X492936Y872535D01*
G02X491880Y873810I242J1275D01*
G37*
G36*
G01X499280D02*
G02X501876I1298J0D01*
G02X501803Y873381I-1297J0D01*
G01X501772Y873295D01*
X502578Y871898D01*
X502668Y871881D01*
G02X503726Y870606I-239J-1275D01*
G02X501132I-1297J0D01*
G02X501203Y871032I1297J3D01*
G01X501234Y871119D01*
X500426Y872518D01*
X500336Y872535D01*
G02X499280Y873810I242J1275D01*
G37*
G36*
G01X506680D02*
G02X509276I1298J0D01*
G02X509203Y873381I-1297J0D01*
G01X509172Y873295D01*
X509978Y871898D01*
X510068Y871881D01*
G02X511126Y870606I-239J-1275D01*
G02X508532I-1297J0D01*
G02X508603Y871032I1297J3D01*
G01X508634Y871119D01*
X507826Y872518D01*
X507736Y872535D01*
G02X506680Y873810I242J1275D01*
G37*
G36*
G01X514080D02*
G02X516676I1298J0D01*
G02X516603Y873381I-1297J0D01*
G01X516572Y873295D01*
X517378Y871898D01*
X517468Y871881D01*
G02X518526Y870606I-239J-1275D01*
G02X515932I-1297J0D01*
G02X516003Y871032I1297J3D01*
G01X516034Y871119D01*
X515226Y872518D01*
X515136Y872535D01*
G02X514080Y873810I242J1275D01*
G37*
G36*
G01X1327422D02*
G02X1330018I1298J0D01*
G02X1328962Y872535I-1298J0D01*
G01X1328872Y872518D01*
X1328065Y871121D01*
X1328096Y871034D01*
G02X1328168Y870606I-1225J-426D01*
G02X1325574I-1297J0D01*
G02X1326629Y871881I1298J0D01*
G01X1326719Y871898D01*
X1327526Y873295D01*
X1327495Y873382D01*
G02X1327422Y873810I1225J429D01*
G37*
G36*
G01X1334822D02*
G02X1337418I1298J0D01*
G02X1336362Y872535I-1298J0D01*
G01X1336272Y872518D01*
X1335465Y871121D01*
X1335496Y871034D01*
G02X1335568Y870606I-1225J-426D01*
G02X1332974I-1297J0D01*
G02X1334029Y871881I1298J0D01*
G01X1334119Y871898D01*
X1334926Y873295D01*
X1334895Y873382D01*
G02X1334822Y873810I1225J429D01*
G37*
G36*
G01X1342222D02*
G02X1344818I1298J0D01*
G02X1343762Y872535I-1298J0D01*
G01X1343672Y872518D01*
X1342865Y871121D01*
X1342896Y871034D01*
G02X1342968Y870606I-1225J-426D01*
G02X1340374I-1297J0D01*
G02X1341429Y871881I1298J0D01*
G01X1341519Y871898D01*
X1342326Y873295D01*
X1342295Y873382D01*
G02X1342222Y873810I1225J429D01*
G37*
G36*
G01X1349622D02*
G02X1352218I1298J0D01*
G02X1351162Y872535I-1298J0D01*
G01X1351072Y872518D01*
X1350265Y871121D01*
X1350296Y871034D01*
G02X1350368Y870606I-1225J-426D01*
G02X1347774I-1297J0D01*
G02X1348829Y871881I1298J0D01*
G01X1348919Y871898D01*
X1349726Y873295D01*
X1349695Y873382D01*
G02X1349622Y873810I1225J429D01*
G37*
G36*
G01X1357022D02*
G02X1359618I1298J0D01*
G02X1358562Y872535I-1298J0D01*
G01X1358472Y872518D01*
X1357665Y871121D01*
X1357696Y871034D01*
G02X1357768Y870606I-1225J-426D01*
G02X1355174I-1297J0D01*
G02X1356229Y871881I1298J0D01*
G01X1356319Y871898D01*
X1357126Y873295D01*
X1357095Y873382D01*
G02X1357022Y873810I1225J429D01*
G37*
G36*
G01X1364422D02*
G02X1367018I1298J0D01*
G02X1365962Y872535I-1298J0D01*
G01X1365872Y872518D01*
X1365065Y871121D01*
X1365096Y871034D01*
G02X1365168Y870606I-1225J-426D01*
G02X1362574I-1297J0D01*
G02X1363629Y871881I1298J0D01*
G01X1363719Y871898D01*
X1364526Y873295D01*
X1364495Y873382D01*
G02X1364422Y873810I1225J429D01*
G37*
G36*
G01X1371822D02*
G02X1374418I1298J0D01*
G02X1373362Y872535I-1298J0D01*
G01X1373272Y872518D01*
X1372465Y871121D01*
X1372496Y871034D01*
G02X1372568Y870606I-1225J-426D01*
G02X1369974I-1297J0D01*
G02X1371029Y871881I1298J0D01*
G01X1371119Y871898D01*
X1371926Y873295D01*
X1371895Y873382D01*
G02X1371822Y873810I1225J429D01*
G37*
G36*
G01X1379222D02*
G02X1381818I1298J0D01*
G02X1380762Y872535I-1298J0D01*
G01X1380672Y872518D01*
X1379865Y871121D01*
X1379896Y871034D01*
G02X1379968Y870606I-1225J-426D01*
G02X1377374I-1297J0D01*
G02X1378429Y871881I1298J0D01*
G01X1378519Y871898D01*
X1379326Y873295D01*
X1379295Y873382D01*
G02X1379222Y873810I1225J429D01*
G37*
G36*
G01X1386622D02*
G02X1389218I1298J0D01*
G02X1389145Y873381I-1297J0D01*
G01X1389114Y873295D01*
X1389920Y871898D01*
X1390010Y871881D01*
G02X1391068Y870606I-239J-1275D01*
G02X1388474I-1297J0D01*
G02X1388545Y871032I1297J3D01*
G01X1388576Y871119D01*
X1387768Y872518D01*
X1387678Y872535D01*
G02X1386622Y873810I242J1275D01*
G37*
G36*
G01X1394022D02*
G02X1396618I1298J0D01*
G02X1396545Y873381I-1297J0D01*
G01X1396514Y873295D01*
X1397320Y871898D01*
X1397410Y871881D01*
G02X1398468Y870606I-239J-1275D01*
G02X1395874I-1297J0D01*
G02X1395945Y871032I1297J3D01*
G01X1395976Y871119D01*
X1395168Y872518D01*
X1395078Y872535D01*
G02X1394022Y873810I242J1275D01*
G37*
G36*
G01X1401422D02*
G02X1404018I1298J0D01*
G02X1403945Y873381I-1297J0D01*
G01X1403914Y873295D01*
X1404720Y871898D01*
X1404810Y871881D01*
G02X1405868Y870606I-239J-1275D01*
G02X1403274I-1297J0D01*
G02X1403345Y871032I1297J3D01*
G01X1403376Y871119D01*
X1402568Y872518D01*
X1402478Y872535D01*
G02X1401422Y873810I242J1275D01*
G37*
G36*
G01X1408824D02*
G02X1411418I1297J0D01*
G02X1411346Y873381I-1297J-3D01*
G01X1411315Y873295D01*
X1412121Y871898D01*
X1412211Y871881D01*
G02X1413268Y870606I-240J-1275D01*
G02X1410674I-1297J0D01*
G01Y870608D01*
G02X1410746Y871033I1297J-1D01*
G01X1410776Y871120D01*
X1409969Y872518D01*
X1409879Y872535D01*
G02X1408824Y873810I243J1275D01*
G37*
G36*
G01X1416222D02*
G02X1418818I1298J0D01*
G02X1418745Y873381I-1297J0D01*
G01X1418714Y873295D01*
X1419520Y871898D01*
X1419610Y871881D01*
G02X1420668Y870606I-239J-1275D01*
G02X1418074I-1297J0D01*
G02X1418145Y871032I1297J3D01*
G01X1418176Y871119D01*
X1417368Y872518D01*
X1417278Y872535D01*
G02X1416222Y873810I242J1275D01*
G37*
G36*
G01X1423624D02*
G02X1426218I1297J0D01*
G02X1426146Y873381I-1297J-3D01*
G01X1426115Y873295D01*
X1426921Y871898D01*
X1427011Y871881D01*
G02X1428068Y870606I-240J-1275D01*
G02X1425474I-1297J0D01*
G01Y870608D01*
G02X1425546Y871033I1297J-1D01*
G01X1425576Y871120D01*
X1424769Y872518D01*
X1424679Y872535D01*
G02X1423624Y873810I243J1275D01*
G37*
G36*
G01X1431022D02*
G02X1433618I1298J0D01*
G02X1433545Y873381I-1297J0D01*
G01X1433514Y873295D01*
X1434320Y871898D01*
X1434410Y871881D01*
G02X1435468Y870606I-239J-1275D01*
G02X1432874I-1297J0D01*
G02X1432945Y871032I1297J3D01*
G01X1432976Y871119D01*
X1432168Y872518D01*
X1432078Y872535D01*
G02X1431022Y873810I242J1275D01*
G37*
G36*
G01X1438422D02*
G02X1441018I1298J0D01*
G02X1440945Y873381I-1297J0D01*
G01X1440914Y873295D01*
X1441720Y871898D01*
X1441810Y871881D01*
G02X1442868Y870606I-239J-1275D01*
G02X1440274I-1297J0D01*
G02X1440345Y871032I1297J3D01*
G01X1440376Y871119D01*
X1439568Y872518D01*
X1439478Y872535D01*
G02X1438422Y873810I242J1275D01*
G37*
G36*
G01X1453222D02*
G02X1455818I1298J0D01*
G02X1455745Y873381I-1297J0D01*
G01X1455714Y873295D01*
X1456520Y871898D01*
X1456610Y871881D01*
G02X1457668Y870606I-239J-1275D01*
G02X1455074I-1297J0D01*
G02X1455145Y871032I1297J3D01*
G01X1455176Y871119D01*
X1454368Y872518D01*
X1454278Y872535D01*
G02X1453222Y873810I242J1275D01*
G37*
G36*
G01X1460622D02*
G02X1463218I1298J0D01*
G02X1463145Y873381I-1297J0D01*
G01X1463114Y873295D01*
X1463920Y871898D01*
X1464010Y871881D01*
G02X1465068Y870606I-239J-1275D01*
G02X1462474I-1297J0D01*
G02X1462545Y871032I1297J3D01*
G01X1462576Y871119D01*
X1461768Y872518D01*
X1461678Y872535D01*
G02X1460622Y873810I242J1275D01*
G37*
G36*
G01X1468022D02*
G02X1470618I1298J0D01*
G02X1470545Y873381I-1297J0D01*
G01X1470514Y873295D01*
X1471320Y871898D01*
X1471410Y871881D01*
G02X1472468Y870606I-239J-1275D01*
G02X1469874I-1297J0D01*
G02X1469945Y871032I1297J3D01*
G01X1469976Y871119D01*
X1469168Y872518D01*
X1469078Y872535D01*
G02X1468022Y873810I242J1275D01*
G37*
G36*
G01X1475422D02*
G02X1478018I1298J0D01*
G02X1477945Y873381I-1297J0D01*
G01X1477914Y873295D01*
X1478720Y871898D01*
X1478810Y871881D01*
G02X1479868Y870606I-239J-1275D01*
G02X1477274I-1297J0D01*
G02X1477345Y871032I1297J3D01*
G01X1477376Y871119D01*
X1476568Y872518D01*
X1476478Y872535D01*
G02X1475422Y873810I242J1275D01*
G37*
G36*
G01X1482822D02*
G02X1485418I1298J0D01*
G02X1485345Y873381I-1297J0D01*
G01X1485314Y873295D01*
X1486120Y871898D01*
X1486210Y871881D01*
G02X1487268Y870606I-239J-1275D01*
G02X1484674I-1297J0D01*
G02X1484745Y871032I1297J3D01*
G01X1484776Y871119D01*
X1483968Y872518D01*
X1483878Y872535D01*
G02X1482822Y873810I242J1275D01*
G37*
G36*
G01X1490222D02*
G02X1492818I1298J0D01*
G02X1492745Y873381I-1297J0D01*
G01X1492714Y873295D01*
X1493520Y871898D01*
X1493610Y871881D01*
G02X1494668Y870606I-239J-1275D01*
G02X1492074I-1297J0D01*
G02X1492145Y871032I1297J3D01*
G01X1492176Y871119D01*
X1491368Y872518D01*
X1491278Y872535D01*
G02X1490222Y873810I242J1275D01*
G37*
G36*
G01X367932Y883423D02*
G02X370526I1297J0D01*
G02X370454Y882994I-1297J-3D01*
G01X370423Y882908D01*
X371229Y881511D01*
X371319Y881494D01*
G02X372376Y880219I-240J-1275D01*
G02X369780I-1298J0D01*
G02X369853Y880647I1298J-1D01*
G01X369883Y880734D01*
X369077Y882131D01*
X368987Y882148D01*
G02X367932Y883423I243J1275D01*
G37*
G36*
G01X375332D02*
G02X377926I1297J0D01*
G02X377854Y882994I-1297J-3D01*
G01X377823Y882908D01*
X378629Y881511D01*
X378719Y881494D01*
G02X379776Y880219I-240J-1275D01*
G02X377180I-1298J0D01*
G02X377253Y880647I1298J-1D01*
G01X377283Y880734D01*
X376477Y882131D01*
X376387Y882148D01*
G02X375332Y883423I243J1275D01*
G37*
G36*
G01X382732D02*
G02X385326I1297J0D01*
G02X385254Y882994I-1297J-3D01*
G01X385223Y882908D01*
X386029Y881511D01*
X386119Y881494D01*
G02X387176Y880219I-240J-1275D01*
G02X384580I-1298J0D01*
G02X384653Y880647I1298J-1D01*
G01X384683Y880734D01*
X383877Y882131D01*
X383787Y882148D01*
G02X382732Y883423I243J1275D01*
G37*
G36*
G01X390132D02*
G02X392726I1297J0D01*
G02X392654Y882994I-1297J-3D01*
G01X392623Y882908D01*
X393429Y881511D01*
X393519Y881494D01*
G02X394576Y880219I-240J-1275D01*
G02X391980I-1298J0D01*
G02X392053Y880647I1298J-1D01*
G01X392083Y880734D01*
X391277Y882131D01*
X391187Y882148D01*
G02X390132Y883423I243J1275D01*
G37*
G36*
G01X397532D02*
G02X400126I1297J0D01*
G02X400054Y882994I-1297J-3D01*
G01X400023Y882908D01*
X400829Y881511D01*
X400919Y881494D01*
G02X401976Y880219I-240J-1275D01*
G02X399380I-1298J0D01*
G02X399453Y880647I1298J-1D01*
G01X399483Y880734D01*
X398677Y882131D01*
X398587Y882148D01*
G02X397532Y883423I243J1275D01*
G37*
G36*
G01X404932D02*
G02X407526I1297J0D01*
G02X407454Y882994I-1297J-3D01*
G01X407423Y882908D01*
X408229Y881511D01*
X408319Y881494D01*
G02X409376Y880219I-240J-1275D01*
G02X406780I-1298J0D01*
G02X406853Y880647I1298J-1D01*
G01X406883Y880734D01*
X406077Y882131D01*
X405987Y882148D01*
G02X404932Y883423I243J1275D01*
G37*
G36*
G01X412332D02*
G02X414926I1297J0D01*
G02X414854Y882994I-1297J-3D01*
G01X414823Y882908D01*
X415629Y881511D01*
X415719Y881494D01*
G02X416776Y880219I-240J-1275D01*
G02X414180I-1298J0D01*
G02X414253Y880647I1298J-1D01*
G01X414283Y880734D01*
X413477Y882131D01*
X413387Y882148D01*
G02X412332Y883423I243J1275D01*
G37*
G36*
G01X419732D02*
G02X422326I1297J0D01*
G02X422254Y882994I-1297J-3D01*
G01X422223Y882908D01*
X423029Y881511D01*
X423119Y881494D01*
G02X424176Y880219I-240J-1275D01*
G02X421580I-1298J0D01*
G02X421653Y880647I1298J-1D01*
G01X421683Y880734D01*
X420877Y882131D01*
X420787Y882148D01*
G02X419732Y883423I243J1275D01*
G37*
G36*
G01X427132D02*
G02X429726I1297J0D01*
G02X429654Y882994I-1297J-3D01*
G01X429623Y882908D01*
X430429Y881511D01*
X430519Y881494D01*
G02X431576Y880219I-240J-1275D01*
G02X428980I-1298J0D01*
G02X429053Y880647I1298J-1D01*
G01X429083Y880734D01*
X428277Y882131D01*
X428187Y882148D01*
G02X427132Y883423I243J1275D01*
G37*
G36*
G01X434532D02*
G02X437126I1297J0D01*
G02X437054Y882994I-1297J-3D01*
G01X437023Y882908D01*
X437829Y881511D01*
X437919Y881494D01*
G02X438976Y880219I-240J-1275D01*
G02X436380I-1298J0D01*
G02X436453Y880647I1298J-1D01*
G01X436483Y880734D01*
X435677Y882131D01*
X435587Y882148D01*
G02X434532Y883423I243J1275D01*
G37*
G36*
G01X441932D02*
G02X444526I1297J0D01*
G02X444454Y882994I-1297J-3D01*
G01X444423Y882908D01*
X445229Y881511D01*
X445319Y881494D01*
G02X446376Y880219I-240J-1275D01*
G02X443780I-1298J0D01*
G02X443853Y880647I1298J-1D01*
G01X443883Y880734D01*
X443077Y882131D01*
X442987Y882148D01*
G02X441932Y883423I243J1275D01*
G37*
G36*
G01X449332D02*
G02X451926I1297J0D01*
G02X451854Y882994I-1297J-3D01*
G01X451823Y882908D01*
X452629Y881511D01*
X452719Y881494D01*
G02X453776Y880219I-240J-1275D01*
G02X451182I-1297J0D01*
G01Y880221D01*
G02X451254Y880646I1297J-1D01*
G01X451284Y880733D01*
X450477Y882131D01*
X450387Y882148D01*
G02X449332Y883423I243J1275D01*
G37*
G36*
G01X456732D02*
G02X459326I1297J0D01*
G02X459254Y882994I-1297J-3D01*
G01X459223Y882908D01*
X460029Y881511D01*
X460119Y881494D01*
G02X461176Y880219I-240J-1275D01*
G02X458580I-1298J0D01*
G02X458653Y880647I1298J-1D01*
G01X458683Y880734D01*
X457877Y882131D01*
X457787Y882148D01*
G02X456732Y883423I243J1275D01*
G37*
G36*
G01X464132D02*
G02X466726I1297J0D01*
G02X466654Y882994I-1297J-3D01*
G01X466623Y882908D01*
X467429Y881511D01*
X467519Y881494D01*
G02X468576Y880219I-240J-1275D01*
G02X465980I-1298J0D01*
G02X466053Y880647I1298J-1D01*
G01X466083Y880734D01*
X465277Y882131D01*
X465187Y882148D01*
G02X464132Y883423I243J1275D01*
G37*
G36*
G01X471532D02*
G02X474126I1297J0D01*
G02X474054Y882994I-1297J-3D01*
G01X474023Y882908D01*
X474829Y881511D01*
X474919Y881494D01*
G02X475976Y880219I-240J-1275D01*
G02X473380I-1298J0D01*
G02X473453Y880647I1298J-1D01*
G01X473483Y880734D01*
X472677Y882131D01*
X472587Y882148D01*
G02X471532Y883423I243J1275D01*
G37*
G36*
G01X478932D02*
G02X481526I1297J0D01*
G02X481454Y882994I-1297J-3D01*
G01X481423Y882908D01*
X482229Y881511D01*
X482319Y881494D01*
G02X483376Y880219I-240J-1275D01*
G02X480780I-1298J0D01*
G02X480853Y880647I1298J-1D01*
G01X480883Y880734D01*
X480077Y882131D01*
X479987Y882148D01*
G02X478932Y883423I243J1275D01*
G37*
G36*
G01X486332D02*
G02X488926I1297J0D01*
G02X488854Y882994I-1297J-3D01*
G01X488823Y882908D01*
X489629Y881511D01*
X489719Y881494D01*
G02X490776Y880219I-240J-1275D01*
G02X488180I-1298J0D01*
G02X488253Y880647I1298J-1D01*
G01X488283Y880734D01*
X487477Y882131D01*
X487387Y882148D01*
G02X486332Y883423I243J1275D01*
G37*
G36*
G01X493732D02*
G02X496326I1297J0D01*
G02X496254Y882994I-1297J-3D01*
G01X496223Y882908D01*
X497029Y881511D01*
X497119Y881494D01*
G02X498176Y880219I-240J-1275D01*
G02X495580I-1298J0D01*
G02X495653Y880647I1298J-1D01*
G01X495683Y880734D01*
X494877Y882131D01*
X494787Y882148D01*
G02X493732Y883423I243J1275D01*
G37*
G36*
G01X501132D02*
G02X503726I1297J0D01*
G02X503654Y882994I-1297J-3D01*
G01X503623Y882908D01*
X504429Y881511D01*
X504519Y881494D01*
G02X505576Y880219I-240J-1275D01*
G02X502980I-1298J0D01*
G02X503053Y880647I1298J-1D01*
G01X503083Y880734D01*
X502277Y882131D01*
X502187Y882148D01*
G02X501132Y883423I243J1275D01*
G37*
G36*
G01X508532D02*
G02X511126I1297J0D01*
G02X511054Y882994I-1297J-3D01*
G01X511023Y882908D01*
X511829Y881511D01*
X511919Y881494D01*
G02X512976Y880219I-240J-1275D01*
G02X510380I-1298J0D01*
G02X510453Y880647I1298J-1D01*
G01X510483Y880734D01*
X509677Y882131D01*
X509587Y882148D01*
G02X508532Y883423I243J1275D01*
G37*
G36*
G01X1344074D02*
G02X1346668I1297J0D01*
G02X1346596Y882994I-1297J-3D01*
G01X1346565Y882908D01*
X1347371Y881511D01*
X1347461Y881494D01*
G02X1348518Y880219I-240J-1275D01*
G02X1345922I-1298J0D01*
G02X1345995Y880647I1298J-1D01*
G01X1346025Y880734D01*
X1345219Y882131D01*
X1345129Y882148D01*
G02X1344074Y883423I243J1275D01*
G37*
G36*
G01X1351474D02*
G02X1354068I1297J0D01*
G02X1353996Y882994I-1297J-3D01*
G01X1353965Y882908D01*
X1354771Y881511D01*
X1354861Y881494D01*
G02X1355918Y880219I-240J-1275D01*
G02X1353322I-1298J0D01*
G02X1353395Y880647I1298J-1D01*
G01X1353425Y880734D01*
X1352619Y882131D01*
X1352529Y882148D01*
G02X1351474Y883423I243J1275D01*
G37*
G36*
G01X1358874D02*
G02X1361468I1297J0D01*
G02X1361396Y882994I-1297J-3D01*
G01X1361365Y882908D01*
X1362171Y881511D01*
X1362261Y881494D01*
G02X1363318Y880219I-240J-1275D01*
G02X1360722I-1298J0D01*
G02X1360795Y880647I1298J-1D01*
G01X1360825Y880734D01*
X1360019Y882131D01*
X1359929Y882148D01*
G02X1358874Y883423I243J1275D01*
G37*
G36*
G01X1366274D02*
G02X1368868I1297J0D01*
G02X1368796Y882994I-1297J-3D01*
G01X1368765Y882908D01*
X1369571Y881511D01*
X1369661Y881494D01*
G02X1370718Y880219I-240J-1275D01*
G02X1368122I-1298J0D01*
G02X1368195Y880647I1298J-1D01*
G01X1368225Y880734D01*
X1367419Y882131D01*
X1367329Y882148D01*
G02X1366274Y883423I243J1275D01*
G37*
G36*
G01X1373674D02*
G02X1376268I1297J0D01*
G02X1376196Y882994I-1297J-3D01*
G01X1376165Y882908D01*
X1376971Y881511D01*
X1377061Y881494D01*
G02X1378118Y880219I-240J-1275D01*
G02X1375522I-1298J0D01*
G02X1375595Y880647I1298J-1D01*
G01X1375625Y880734D01*
X1374819Y882131D01*
X1374729Y882148D01*
G02X1373674Y883423I243J1275D01*
G37*
G36*
G01X1381074D02*
G02X1383668I1297J0D01*
G02X1383596Y882994I-1297J-3D01*
G01X1383565Y882908D01*
X1384371Y881511D01*
X1384461Y881494D01*
G02X1385518Y880219I-240J-1275D01*
G02X1382922I-1298J0D01*
G02X1382995Y880647I1298J-1D01*
G01X1383025Y880734D01*
X1382219Y882131D01*
X1382129Y882148D01*
G02X1381074Y883423I243J1275D01*
G37*
G36*
G01X1388474D02*
G02X1391068I1297J0D01*
G02X1390996Y882994I-1297J-3D01*
G01X1390965Y882908D01*
X1391771Y881511D01*
X1391861Y881494D01*
G02X1392918Y880219I-240J-1275D01*
G02X1390322I-1298J0D01*
G02X1390395Y880647I1298J-1D01*
G01X1390425Y880734D01*
X1389619Y882131D01*
X1389529Y882148D01*
G02X1388474Y883423I243J1275D01*
G37*
G36*
G01X1395874D02*
G02X1398468I1297J0D01*
G02X1398396Y882994I-1297J-3D01*
G01X1398365Y882908D01*
X1399171Y881511D01*
X1399261Y881494D01*
G02X1400318Y880219I-240J-1275D01*
G02X1397722I-1298J0D01*
G02X1397795Y880647I1298J-1D01*
G01X1397825Y880734D01*
X1397019Y882131D01*
X1396929Y882148D01*
G02X1395874Y883423I243J1275D01*
G37*
G36*
G01X1403274D02*
G02X1405868I1297J0D01*
G02X1405796Y882994I-1297J-3D01*
G01X1405765Y882908D01*
X1406571Y881511D01*
X1406661Y881494D01*
G02X1407718Y880219I-240J-1275D01*
G02X1405122I-1298J0D01*
G02X1405195Y880647I1298J-1D01*
G01X1405225Y880734D01*
X1404419Y882131D01*
X1404329Y882148D01*
G02X1403274Y883423I243J1275D01*
G37*
G36*
G01X1410674D02*
G02X1413268I1297J0D01*
G02X1413196Y882994I-1297J-3D01*
G01X1413165Y882908D01*
X1413971Y881511D01*
X1414061Y881494D01*
G02X1415118Y880219I-240J-1275D01*
G02X1412522I-1298J0D01*
G02X1412595Y880647I1298J-1D01*
G01X1412625Y880734D01*
X1411819Y882131D01*
X1411729Y882148D01*
G02X1410674Y883423I243J1275D01*
G37*
G36*
G01X1418074D02*
G02X1420668I1297J0D01*
G02X1420596Y882994I-1297J-3D01*
G01X1420565Y882908D01*
X1421371Y881511D01*
X1421461Y881494D01*
G02X1422518Y880219I-240J-1275D01*
G02X1419922I-1298J0D01*
G02X1419995Y880647I1298J-1D01*
G01X1420025Y880734D01*
X1419219Y882131D01*
X1419129Y882148D01*
G02X1418074Y883423I243J1275D01*
G37*
G36*
G01X1425474D02*
G02X1428068I1297J0D01*
G02X1427996Y882994I-1297J-3D01*
G01X1427965Y882908D01*
X1428771Y881511D01*
X1428861Y881494D01*
G02X1429918Y880219I-240J-1275D01*
G02X1427324I-1297J0D01*
G01Y880221D01*
G02X1427396Y880646I1297J-1D01*
G01X1427426Y880733D01*
X1426619Y882131D01*
X1426529Y882148D01*
G02X1425474Y883423I243J1275D01*
G37*
G36*
G01X1432874D02*
G02X1435468I1297J0D01*
G02X1435396Y882994I-1297J-3D01*
G01X1435365Y882908D01*
X1436171Y881511D01*
X1436261Y881494D01*
G02X1437318Y880219I-240J-1275D01*
G02X1434722I-1298J0D01*
G02X1434795Y880647I1298J-1D01*
G01X1434825Y880734D01*
X1434019Y882131D01*
X1433929Y882148D01*
G02X1432874Y883423I243J1275D01*
G37*
G36*
G01X1440274D02*
G02X1442868I1297J0D01*
G02X1442796Y882994I-1297J-3D01*
G01X1442765Y882908D01*
X1443571Y881511D01*
X1443661Y881494D01*
G02X1444718Y880219I-240J-1275D01*
G02X1442122I-1298J0D01*
G02X1442195Y880647I1298J-1D01*
G01X1442225Y880734D01*
X1441419Y882131D01*
X1441329Y882148D01*
G02X1440274Y883423I243J1275D01*
G37*
G36*
G01X1447674D02*
G02X1450268I1297J0D01*
G02X1450196Y882994I-1297J-3D01*
G01X1450165Y882908D01*
X1450971Y881511D01*
X1451061Y881494D01*
G02X1452118Y880219I-240J-1275D01*
G02X1449522I-1298J0D01*
G02X1449595Y880647I1298J-1D01*
G01X1449625Y880734D01*
X1448819Y882131D01*
X1448729Y882148D01*
G02X1447674Y883423I243J1275D01*
G37*
G36*
G01X1455074D02*
G02X1457668I1297J0D01*
G02X1457596Y882994I-1297J-3D01*
G01X1457565Y882908D01*
X1458371Y881511D01*
X1458461Y881494D01*
G02X1459518Y880219I-240J-1275D01*
G02X1456922I-1298J0D01*
G02X1456995Y880647I1298J-1D01*
G01X1457025Y880734D01*
X1456219Y882131D01*
X1456129Y882148D01*
G02X1455074Y883423I243J1275D01*
G37*
G36*
G01X1462474D02*
G02X1465068I1297J0D01*
G02X1464996Y882994I-1297J-3D01*
G01X1464965Y882908D01*
X1465771Y881511D01*
X1465861Y881494D01*
G02X1466918Y880219I-240J-1275D01*
G02X1464322I-1298J0D01*
G02X1464395Y880647I1298J-1D01*
G01X1464425Y880734D01*
X1463619Y882131D01*
X1463529Y882148D01*
G02X1462474Y883423I243J1275D01*
G37*
G36*
G01X1469874D02*
G02X1472468I1297J0D01*
G02X1472396Y882994I-1297J-3D01*
G01X1472365Y882908D01*
X1473171Y881511D01*
X1473261Y881494D01*
G02X1474318Y880219I-240J-1275D01*
G02X1471722I-1298J0D01*
G02X1471795Y880647I1298J-1D01*
G01X1471825Y880734D01*
X1471019Y882131D01*
X1470929Y882148D01*
G02X1469874Y883423I243J1275D01*
G37*
G36*
G01X1477274D02*
G02X1479868I1297J0D01*
G02X1479796Y882994I-1297J-3D01*
G01X1479765Y882908D01*
X1480571Y881511D01*
X1480661Y881494D01*
G02X1481718Y880219I-240J-1275D01*
G02X1479122I-1298J0D01*
G02X1479195Y880647I1298J-1D01*
G01X1479225Y880734D01*
X1478419Y882131D01*
X1478329Y882148D01*
G02X1477274Y883423I243J1275D01*
G37*
G36*
G01X1484674D02*
G02X1487268I1297J0D01*
G02X1487196Y882994I-1297J-3D01*
G01X1487165Y882908D01*
X1487971Y881511D01*
X1488061Y881494D01*
G02X1489118Y880219I-240J-1275D01*
G02X1486522I-1298J0D01*
G02X1486595Y880647I1298J-1D01*
G01X1486625Y880734D01*
X1485819Y882131D01*
X1485729Y882148D01*
G02X1484674Y883423I243J1275D01*
G37*
G36*
G01X373480Y886627D02*
G02X376076I1298J0D01*
G02X375020Y885352I-1298J0D01*
G01X374930Y885335D01*
X374123Y883938D01*
X374154Y883851D01*
G02X374226Y883423I-1225J-426D01*
G02X371632I-1297J0D01*
G02X372687Y884698I1298J0D01*
G01X372777Y884715D01*
X373584Y886112D01*
X373553Y886199D01*
G02X373480Y886627I1225J429D01*
G37*
G36*
G01X380880D02*
G02X383476I1298J0D01*
G02X382420Y885352I-1298J0D01*
G01X382330Y885335D01*
X381523Y883938D01*
X381554Y883851D01*
G02X381626Y883423I-1225J-426D01*
G02X379032I-1297J0D01*
G02X380087Y884698I1298J0D01*
G01X380177Y884715D01*
X380984Y886112D01*
X380953Y886199D01*
G02X380880Y886627I1225J429D01*
G37*
G36*
G01X388280D02*
G02X390876I1298J0D01*
G02X389820Y885352I-1298J0D01*
G01X389730Y885335D01*
X388923Y883938D01*
X388954Y883851D01*
G02X389026Y883423I-1225J-426D01*
G02X386432I-1297J0D01*
G02X387487Y884698I1298J0D01*
G01X387577Y884715D01*
X388384Y886112D01*
X388353Y886199D01*
G02X388280Y886627I1225J429D01*
G37*
G36*
G01X395680D02*
G02X398276I1298J0D01*
G02X397220Y885352I-1298J0D01*
G01X397130Y885335D01*
X396323Y883938D01*
X396354Y883851D01*
G02X396426Y883423I-1225J-426D01*
G02X393832I-1297J0D01*
G02X394887Y884698I1298J0D01*
G01X394977Y884715D01*
X395784Y886112D01*
X395753Y886199D01*
G02X395680Y886627I1225J429D01*
G37*
G36*
G01X403080D02*
G02X405676I1298J0D01*
G02X404620Y885352I-1298J0D01*
G01X404530Y885335D01*
X403723Y883938D01*
X403754Y883851D01*
G02X403826Y883423I-1225J-426D01*
G02X401232I-1297J0D01*
G02X402287Y884698I1298J0D01*
G01X402377Y884715D01*
X403184Y886112D01*
X403153Y886199D01*
G02X403080Y886627I1225J429D01*
G37*
G36*
G01X410480D02*
G02X413076I1298J0D01*
G02X412020Y885352I-1298J0D01*
G01X411930Y885335D01*
X411123Y883938D01*
X411154Y883851D01*
G02X411226Y883423I-1225J-426D01*
G02X408632I-1297J0D01*
G02X409687Y884698I1298J0D01*
G01X409777Y884715D01*
X410584Y886112D01*
X410553Y886199D01*
G02X410480Y886627I1225J429D01*
G37*
G36*
G01X417880D02*
G02X420476I1298J0D01*
G02X419420Y885352I-1298J0D01*
G01X419330Y885335D01*
X418523Y883938D01*
X418554Y883851D01*
G02X418626Y883423I-1225J-426D01*
G02X416032I-1297J0D01*
G02X417087Y884698I1298J0D01*
G01X417177Y884715D01*
X417984Y886112D01*
X417953Y886199D01*
G02X417880Y886627I1225J429D01*
G37*
G36*
G01X425280D02*
G02X427876I1298J0D01*
G02X426820Y885352I-1298J0D01*
G01X426730Y885335D01*
X425923Y883938D01*
X425954Y883851D01*
G02X426026Y883423I-1225J-426D01*
G02X423432I-1297J0D01*
G02X424487Y884698I1298J0D01*
G01X424577Y884715D01*
X425384Y886112D01*
X425353Y886199D01*
G02X425280Y886627I1225J429D01*
G37*
G36*
G01X432680D02*
G02X435276I1298J0D01*
G02X434220Y885352I-1298J0D01*
G01X434130Y885335D01*
X433323Y883938D01*
X433354Y883851D01*
G02X433426Y883423I-1225J-426D01*
G02X430832I-1297J0D01*
G02X431887Y884698I1298J0D01*
G01X431977Y884715D01*
X432784Y886112D01*
X432753Y886199D01*
G02X432680Y886627I1225J429D01*
G37*
G36*
G01X440080D02*
G02X442676I1298J0D01*
G02X441620Y885352I-1298J0D01*
G01X441530Y885335D01*
X440723Y883938D01*
X440754Y883851D01*
G02X440826Y883423I-1225J-426D01*
G02X438232I-1297J0D01*
G02X439287Y884698I1298J0D01*
G01X439377Y884715D01*
X440184Y886112D01*
X440153Y886199D01*
G02X440080Y886627I1225J429D01*
G37*
G36*
G01X447480D02*
G02X450076I1298J0D01*
G02X449020Y885352I-1298J0D01*
G01X448930Y885335D01*
X448123Y883938D01*
X448154Y883851D01*
G02X448226Y883423I-1225J-426D01*
G02X445632I-1297J0D01*
G02X446687Y884698I1298J0D01*
G01X446777Y884715D01*
X447584Y886112D01*
X447553Y886199D01*
G02X447480Y886627I1225J429D01*
G37*
G36*
G01X454880D02*
G02X457476I1298J0D01*
G02X456420Y885352I-1298J0D01*
G01X456330Y885335D01*
X455523Y883938D01*
X455554Y883851D01*
G02X455626Y883423I-1225J-426D01*
G02X453032I-1297J0D01*
G02X454087Y884698I1298J0D01*
G01X454177Y884715D01*
X454984Y886112D01*
X454953Y886199D01*
G02X454880Y886627I1225J429D01*
G37*
G36*
G01X462280D02*
G02X464876I1298J0D01*
G02X463820Y885352I-1298J0D01*
G01X463730Y885335D01*
X462923Y883938D01*
X462954Y883851D01*
G02X463026Y883423I-1225J-426D01*
G02X460432I-1297J0D01*
G02X461487Y884698I1298J0D01*
G01X461577Y884715D01*
X462384Y886112D01*
X462353Y886199D01*
G02X462280Y886627I1225J429D01*
G37*
G36*
G01X469680D02*
G02X472276I1298J0D01*
G02X471220Y885352I-1298J0D01*
G01X471130Y885335D01*
X470323Y883938D01*
X470354Y883851D01*
G02X470426Y883423I-1225J-426D01*
G02X467832I-1297J0D01*
G02X468887Y884698I1298J0D01*
G01X468977Y884715D01*
X469784Y886112D01*
X469753Y886199D01*
G02X469680Y886627I1225J429D01*
G37*
G36*
G01X477080D02*
G02X479676I1298J0D01*
G02X478620Y885352I-1298J0D01*
G01X478530Y885335D01*
X477723Y883938D01*
X477754Y883851D01*
G02X477826Y883423I-1225J-426D01*
G02X475232I-1297J0D01*
G02X476287Y884698I1298J0D01*
G01X476377Y884715D01*
X477184Y886112D01*
X477153Y886199D01*
G02X477080Y886627I1225J429D01*
G37*
G36*
G01X484480D02*
G02X487076I1298J0D01*
G02X486020Y885352I-1298J0D01*
G01X485930Y885335D01*
X485123Y883938D01*
X485154Y883851D01*
G02X485226Y883423I-1225J-426D01*
G02X482632I-1297J0D01*
G02X483687Y884698I1298J0D01*
G01X483777Y884715D01*
X484584Y886112D01*
X484553Y886199D01*
G02X484480Y886627I1225J429D01*
G37*
G36*
G01X491880D02*
G02X494476I1298J0D01*
G02X493420Y885352I-1298J0D01*
G01X493330Y885335D01*
X492523Y883938D01*
X492554Y883851D01*
G02X492626Y883423I-1225J-426D01*
G02X490032I-1297J0D01*
G02X491087Y884698I1298J0D01*
G01X491177Y884715D01*
X491984Y886112D01*
X491953Y886199D01*
G02X491880Y886627I1225J429D01*
G37*
G36*
G01X499280D02*
G02X501876I1298J0D01*
G02X500820Y885352I-1298J0D01*
G01X500730Y885335D01*
X499923Y883938D01*
X499954Y883851D01*
G02X500026Y883423I-1225J-426D01*
G02X497432I-1297J0D01*
G02X498487Y884698I1298J0D01*
G01X498577Y884715D01*
X499384Y886112D01*
X499353Y886199D01*
G02X499280Y886627I1225J429D01*
G37*
G36*
G01X506680D02*
G02X509276I1298J0D01*
G02X508220Y885352I-1298J0D01*
G01X508130Y885335D01*
X507323Y883938D01*
X507354Y883851D01*
G02X507426Y883423I-1225J-426D01*
G02X504832I-1297J0D01*
G02X505887Y884698I1298J0D01*
G01X505977Y884715D01*
X506784Y886112D01*
X506753Y886199D01*
G02X506680Y886627I1225J429D01*
G37*
G36*
G01X514080D02*
G02X516676I1298J0D01*
G02X515620Y885352I-1298J0D01*
G01X515530Y885335D01*
X514723Y883938D01*
X514754Y883851D01*
G02X514826Y883423I-1225J-426D01*
G02X512232I-1297J0D01*
G02X513287Y884698I1298J0D01*
G01X513377Y884715D01*
X514184Y886112D01*
X514153Y886199D01*
G02X514080Y886627I1225J429D01*
G37*
G36*
G01X521480D02*
G02X524076I1298J0D01*
G02X523020Y885352I-1298J0D01*
G01X522930Y885335D01*
X522123Y883938D01*
X522154Y883851D01*
G02X522226Y883423I-1225J-426D01*
G02X519632I-1297J0D01*
G02X520687Y884698I1298J0D01*
G01X520777Y884715D01*
X521584Y886112D01*
X521553Y886199D01*
G02X521480Y886627I1225J429D01*
G37*
G36*
G01X1349622D02*
G02X1352218I1298J0D01*
G02X1351162Y885352I-1298J0D01*
G01X1351072Y885335D01*
X1350265Y883938D01*
X1350296Y883851D01*
G02X1350368Y883423I-1225J-426D01*
G02X1347774I-1297J0D01*
G02X1348829Y884698I1298J0D01*
G01X1348919Y884715D01*
X1349726Y886112D01*
X1349695Y886199D01*
G02X1349622Y886627I1225J429D01*
G37*
G36*
G01X1357022D02*
G02X1359618I1298J0D01*
G02X1358562Y885352I-1298J0D01*
G01X1358472Y885335D01*
X1357665Y883938D01*
X1357696Y883851D01*
G02X1357768Y883423I-1225J-426D01*
G02X1355174I-1297J0D01*
G02X1356229Y884698I1298J0D01*
G01X1356319Y884715D01*
X1357126Y886112D01*
X1357095Y886199D01*
G02X1357022Y886627I1225J429D01*
G37*
G36*
G01X1364422D02*
G02X1367018I1298J0D01*
G02X1365962Y885352I-1298J0D01*
G01X1365872Y885335D01*
X1365065Y883938D01*
X1365096Y883851D01*
G02X1365168Y883423I-1225J-426D01*
G02X1362574I-1297J0D01*
G02X1363629Y884698I1298J0D01*
G01X1363719Y884715D01*
X1364526Y886112D01*
X1364495Y886199D01*
G02X1364422Y886627I1225J429D01*
G37*
G36*
G01X1371822D02*
G02X1374418I1298J0D01*
G02X1373362Y885352I-1298J0D01*
G01X1373272Y885335D01*
X1372465Y883938D01*
X1372496Y883851D01*
G02X1372568Y883423I-1225J-426D01*
G02X1369974I-1297J0D01*
G02X1371029Y884698I1298J0D01*
G01X1371119Y884715D01*
X1371926Y886112D01*
X1371895Y886199D01*
G02X1371822Y886627I1225J429D01*
G37*
G36*
G01X1379222D02*
G02X1381818I1298J0D01*
G02X1380762Y885352I-1298J0D01*
G01X1380672Y885335D01*
X1379865Y883938D01*
X1379896Y883851D01*
G02X1379968Y883423I-1225J-426D01*
G02X1377374I-1297J0D01*
G02X1378429Y884698I1298J0D01*
G01X1378519Y884715D01*
X1379326Y886112D01*
X1379295Y886199D01*
G02X1379222Y886627I1225J429D01*
G37*
G36*
G01X1386622D02*
G02X1389218I1298J0D01*
G02X1388162Y885352I-1298J0D01*
G01X1388072Y885335D01*
X1387265Y883938D01*
X1387296Y883851D01*
G02X1387368Y883423I-1225J-426D01*
G02X1384774I-1297J0D01*
G02X1385829Y884698I1298J0D01*
G01X1385919Y884715D01*
X1386726Y886112D01*
X1386695Y886199D01*
G02X1386622Y886627I1225J429D01*
G37*
G36*
G01X1394022D02*
G02X1396618I1298J0D01*
G02X1395562Y885352I-1298J0D01*
G01X1395472Y885335D01*
X1394665Y883938D01*
X1394696Y883851D01*
G02X1394768Y883423I-1225J-426D01*
G02X1392174I-1297J0D01*
G02X1393229Y884698I1298J0D01*
G01X1393319Y884715D01*
X1394126Y886112D01*
X1394095Y886199D01*
G02X1394022Y886627I1225J429D01*
G37*
G36*
G01X1401422D02*
G02X1404018I1298J0D01*
G02X1402962Y885352I-1298J0D01*
G01X1402872Y885335D01*
X1402065Y883938D01*
X1402096Y883851D01*
G02X1402168Y883423I-1225J-426D01*
G02X1399574I-1297J0D01*
G02X1400629Y884698I1298J0D01*
G01X1400719Y884715D01*
X1401526Y886112D01*
X1401495Y886199D01*
G02X1401422Y886627I1225J429D01*
G37*
G36*
G01X1408822D02*
G02X1411418I1298J0D01*
G02X1410362Y885352I-1298J0D01*
G01X1410272Y885335D01*
X1409465Y883938D01*
X1409496Y883851D01*
G02X1409568Y883423I-1225J-426D01*
G02X1406974I-1297J0D01*
G02X1408029Y884698I1298J0D01*
G01X1408119Y884715D01*
X1408926Y886112D01*
X1408895Y886199D01*
G02X1408822Y886627I1225J429D01*
G37*
G36*
G01X1416222D02*
G02X1418818I1298J0D01*
G02X1417762Y885352I-1298J0D01*
G01X1417672Y885335D01*
X1416865Y883938D01*
X1416896Y883851D01*
G02X1416968Y883423I-1225J-426D01*
G02X1414374I-1297J0D01*
G02X1415429Y884698I1298J0D01*
G01X1415519Y884715D01*
X1416326Y886112D01*
X1416295Y886199D01*
G02X1416222Y886627I1225J429D01*
G37*
G36*
G01X1423622D02*
G02X1426218I1298J0D01*
G02X1425162Y885352I-1298J0D01*
G01X1425072Y885335D01*
X1424265Y883938D01*
X1424296Y883851D01*
G02X1424368Y883423I-1225J-426D01*
G02X1421774I-1297J0D01*
G02X1422829Y884698I1298J0D01*
G01X1422919Y884715D01*
X1423726Y886112D01*
X1423695Y886199D01*
G02X1423622Y886627I1225J429D01*
G37*
G36*
G01X1431022D02*
G02X1433618I1298J0D01*
G02X1432562Y885352I-1298J0D01*
G01X1432472Y885335D01*
X1431665Y883938D01*
X1431696Y883851D01*
G02X1431768Y883423I-1225J-426D01*
G02X1429174I-1297J0D01*
G02X1430229Y884698I1298J0D01*
G01X1430319Y884715D01*
X1431126Y886112D01*
X1431095Y886199D01*
G02X1431022Y886627I1225J429D01*
G37*
G36*
G01X1438422D02*
G02X1441018I1298J0D01*
G02X1439962Y885352I-1298J0D01*
G01X1439872Y885335D01*
X1439065Y883938D01*
X1439096Y883851D01*
G02X1439168Y883423I-1225J-426D01*
G02X1436574I-1297J0D01*
G02X1437629Y884698I1298J0D01*
G01X1437719Y884715D01*
X1438526Y886112D01*
X1438495Y886199D01*
G02X1438422Y886627I1225J429D01*
G37*
G36*
G01X1445822D02*
G02X1448418I1298J0D01*
G02X1447362Y885352I-1298J0D01*
G01X1447272Y885335D01*
X1446465Y883938D01*
X1446496Y883851D01*
G02X1446568Y883423I-1225J-426D01*
G02X1443974I-1297J0D01*
G02X1445029Y884698I1298J0D01*
G01X1445119Y884715D01*
X1445926Y886112D01*
X1445895Y886199D01*
G02X1445822Y886627I1225J429D01*
G37*
G36*
G01X1453222D02*
G02X1455818I1298J0D01*
G02X1454762Y885352I-1298J0D01*
G01X1454672Y885335D01*
X1453865Y883938D01*
X1453896Y883851D01*
G02X1453968Y883423I-1225J-426D01*
G02X1451374I-1297J0D01*
G02X1452429Y884698I1298J0D01*
G01X1452519Y884715D01*
X1453326Y886112D01*
X1453295Y886199D01*
G02X1453222Y886627I1225J429D01*
G37*
G36*
G01X1460622D02*
G02X1463218I1298J0D01*
G02X1462162Y885352I-1298J0D01*
G01X1462072Y885335D01*
X1461265Y883938D01*
X1461296Y883851D01*
G02X1461368Y883423I-1225J-426D01*
G02X1458774I-1297J0D01*
G02X1459829Y884698I1298J0D01*
G01X1459919Y884715D01*
X1460726Y886112D01*
X1460695Y886199D01*
G02X1460622Y886627I1225J429D01*
G37*
G36*
G01X1468022D02*
G02X1470618I1298J0D01*
G02X1469562Y885352I-1298J0D01*
G01X1469472Y885335D01*
X1468665Y883938D01*
X1468696Y883851D01*
G02X1468768Y883423I-1225J-426D01*
G02X1466174I-1297J0D01*
G02X1467229Y884698I1298J0D01*
G01X1467319Y884715D01*
X1468126Y886112D01*
X1468095Y886199D01*
G02X1468022Y886627I1225J429D01*
G37*
G36*
G01X1475422D02*
G02X1478018I1298J0D01*
G02X1476962Y885352I-1298J0D01*
G01X1476872Y885335D01*
X1476065Y883938D01*
X1476096Y883851D01*
G02X1476168Y883423I-1225J-426D01*
G02X1473574I-1297J0D01*
G02X1474629Y884698I1298J0D01*
G01X1474719Y884715D01*
X1475526Y886112D01*
X1475495Y886199D01*
G02X1475422Y886627I1225J429D01*
G37*
G36*
G01X1482822D02*
G02X1485418I1298J0D01*
G02X1484362Y885352I-1298J0D01*
G01X1484272Y885335D01*
X1483465Y883938D01*
X1483496Y883851D01*
G02X1483568Y883423I-1225J-426D01*
G02X1480974I-1297J0D01*
G02X1482029Y884698I1298J0D01*
G01X1482119Y884715D01*
X1482926Y886112D01*
X1482895Y886199D01*
G02X1482822Y886627I1225J429D01*
G37*
G36*
G01X1490222D02*
G02X1492818I1298J0D01*
G02X1491762Y885352I-1298J0D01*
G01X1491672Y885335D01*
X1490865Y883938D01*
X1490896Y883851D01*
G02X1490968Y883423I-1225J-426D01*
G02X1488374I-1297J0D01*
G02X1489429Y884698I1298J0D01*
G01X1489519Y884715D01*
X1490326Y886112D01*
X1490295Y886199D01*
G02X1490222Y886627I1225J429D01*
G37*
G36*
G01X1497622D02*
G02X1500218I1298J0D01*
G02X1499162Y885352I-1298J0D01*
G01X1499072Y885335D01*
X1498265Y883938D01*
X1498296Y883851D01*
G02X1498368Y883423I-1225J-426D01*
G02X1495774I-1297J0D01*
G02X1496829Y884698I1298J0D01*
G01X1496919Y884715D01*
X1497726Y886112D01*
X1497695Y886199D01*
G02X1497622Y886627I1225J429D01*
G37*
G36*
G01X429414Y1079791D02*
G02X432008I1297J0D01*
G02X430953Y1078516I-1298J0D01*
G01X430863Y1078499D01*
X430056Y1077101D01*
X430086Y1077015D01*
G02X430158Y1076587I-1225J-426D01*
G02X427564I-1297J0D01*
G02X428620Y1077862I1298J0D01*
G01X428710Y1077879D01*
X429517Y1079276D01*
X429486Y1079363D01*
G02X429414Y1079791I1225J426D01*
G37*
G36*
G01X1405556D02*
G02X1408150I1297J0D01*
G02X1407095Y1078516I-1298J0D01*
G01X1407005Y1078499D01*
X1406198Y1077101D01*
X1406228Y1077015D01*
G02X1406300Y1076587I-1225J-426D01*
G02X1403706I-1297J0D01*
G02X1404762Y1077862I1298J0D01*
G01X1404852Y1077879D01*
X1405659Y1079276D01*
X1405628Y1079363D01*
G02X1405556Y1079791I1225J426D01*
G37*
G36*
G01X402962Y1084292D02*
G02X404001Y1083772I0J-1298D01*
G01X405623D01*
G02X406662Y1084292I1039J-778D01*
G02Y1081698I0J-1297D01*
G02X405623Y1082218I0J1298D01*
G01X404001D01*
G02X402962Y1081698I-1039J778D01*
G02Y1084292I0J1297D01*
G37*
G36*
G01X409064Y1082995D02*
G02X411660I1298J0D01*
G02X410604Y1081720I-1298J0D01*
G01X410514Y1081703D01*
X409706Y1080304D01*
X409736Y1080218D01*
G02X409808Y1079793I-1225J-426D01*
G01Y1079791D01*
G02X407214I-1297J0D01*
G02X408271Y1081066I1297J0D01*
G01X408361Y1081083D01*
X409168Y1082480D01*
X409137Y1082567D01*
G02X409064Y1082995I1225J429D01*
G37*
G36*
G01X1379104Y1084292D02*
G02X1380143Y1083772I0J-1298D01*
G01X1381765D01*
G02X1382804Y1084292I1039J-778D01*
G02Y1081698I0J-1297D01*
G02X1381765Y1082218I0J1298D01*
G01X1380143D01*
G02X1379104Y1081698I-1039J778D01*
G02Y1084292I0J1297D01*
G37*
G36*
G01X1385206Y1082995D02*
G02X1387802I1298J0D01*
G02X1386746Y1081720I-1298J0D01*
G01X1386656Y1081703D01*
X1385848Y1080304D01*
X1385878Y1080218D01*
G02X1385950Y1079793I-1225J-426D01*
G01Y1079791D01*
G02X1383356I-1297J0D01*
G02X1384413Y1081066I1297J0D01*
G01X1384503Y1081083D01*
X1385310Y1082480D01*
X1385279Y1082567D01*
G02X1385206Y1082995I1225J429D01*
G37*
G36*
G01X410914Y1086200D02*
G02X413508I1297J0D01*
G02X413436Y1085772I-1297J-2D01*
G01X413405Y1085685D01*
X414212Y1084287D01*
X414303Y1084270D01*
G02X415360Y1082995I-240J-1275D01*
G02X412764I-1298J0D01*
G02X412837Y1083422I1298J-2D01*
G01X412867Y1083509D01*
X412059Y1084908D01*
X411969Y1084925D01*
G02X410914Y1086200I243J1275D01*
G37*
G36*
G01X419611Y1087498D02*
G02X420650Y1086978I0J-1298D01*
G01X422272D01*
G02X423311Y1087498I1039J-778D01*
G02Y1084902I0J-1298D01*
G02X422272Y1085422I0J1298D01*
G01X420650D01*
G02X419611Y1084902I-1039J778D01*
G02Y1087498I0J1298D01*
G37*
G36*
G01X425714Y1086200D02*
G02X428310I1298J0D01*
G02X427254Y1084925I-1298J0D01*
G01X427164Y1084908D01*
X426356Y1083510D01*
X426387Y1083423D01*
G02X426460Y1082995I-1225J-429D01*
G02X423864I-1298J0D01*
G02X424920Y1084270I1298J0D01*
G01X425010Y1084287D01*
X425818Y1085685D01*
X425787Y1085772D01*
G02X425714Y1086200I1225J429D01*
G37*
G36*
G01X1387056D02*
G02X1389650I1297J0D01*
G02X1389578Y1085772I-1297J-2D01*
G01X1389547Y1085685D01*
X1390354Y1084287D01*
X1390445Y1084270D01*
G02X1391502Y1082995I-240J-1275D01*
G02X1388906I-1298J0D01*
G02X1388979Y1083422I1298J-2D01*
G01X1389009Y1083509D01*
X1388201Y1084908D01*
X1388111Y1084925D01*
G02X1387056Y1086200I243J1275D01*
G37*
G36*
G01X1395753Y1087498D02*
G02X1396792Y1086978I0J-1298D01*
G01X1398414D01*
G02X1399453Y1087498I1039J-778D01*
G02Y1084902I0J-1298D01*
G02X1398414Y1085422I0J1298D01*
G01X1396792D01*
G02X1395753Y1084902I-1039J778D01*
G02Y1087498I0J1298D01*
G37*
G36*
G01X1401856Y1086200D02*
G02X1404452I1298J0D01*
G02X1403396Y1084925I-1298J0D01*
G01X1403306Y1084908D01*
X1402498Y1083510D01*
X1402529Y1083423D01*
G02X1402602Y1082995I-1225J-429D01*
G02X1400006I-1298J0D01*
G02X1401062Y1084270I1298J0D01*
G01X1401152Y1084287D01*
X1401960Y1085685D01*
X1401929Y1085772D01*
G02X1401856Y1086200I1225J429D01*
G37*
G36*
G01X401664Y1089404D02*
G02X404258I1297J0D01*
G02X404186Y1088976I-1297J-2D01*
G01X404155Y1088889D01*
X404962Y1087492D01*
X405052Y1087475D01*
G02X406108Y1086200I-242J-1275D01*
G02X403514I-1297J0D01*
G02X403586Y1086628I1297J2D01*
G01X403616Y1086714D01*
X402809Y1088112D01*
X402719Y1088129D01*
G02X401664Y1089404I243J1275D01*
G37*
G36*
G01X410362Y1090702D02*
G02X411401Y1090182I0J-1298D01*
G01X413023D01*
G02X414062Y1090702I1039J-778D01*
G02Y1088106I0J-1298D01*
G02X413023Y1088626I0J1298D01*
G01X411401D01*
G02X410362Y1088106I-1039J778D01*
G02Y1090702I0J1298D01*
G37*
G36*
G01X427564Y1089404D02*
G02X430158I1297J0D01*
G02X430086Y1088976I-1297J-2D01*
G01X430055Y1088889D01*
X430862Y1087492D01*
X430952Y1087475D01*
G02X432008Y1086200I-242J-1275D01*
G02X429412I-1298J0D01*
G02X429485Y1086629I1297J0D01*
G01X429516Y1086715D01*
X428709Y1088112D01*
X428619Y1088129D01*
G02X427564Y1089404I243J1275D01*
G37*
G36*
G01X1377806D02*
G02X1380400I1297J0D01*
G02X1380328Y1088976I-1297J-2D01*
G01X1380297Y1088889D01*
X1381104Y1087492D01*
X1381194Y1087475D01*
G02X1382250Y1086200I-242J-1275D01*
G02X1379656I-1297J0D01*
G02X1379728Y1086628I1297J2D01*
G01X1379758Y1086714D01*
X1378951Y1088112D01*
X1378861Y1088129D01*
G02X1377806Y1089404I243J1275D01*
G37*
G36*
G01X1386504Y1090702D02*
G02X1387543Y1090182I0J-1298D01*
G01X1389165D01*
G02X1390204Y1090702I1039J-778D01*
G02Y1088106I0J-1298D01*
G02X1389165Y1088626I0J1298D01*
G01X1387543D01*
G02X1386504Y1088106I-1039J778D01*
G02Y1090702I0J1298D01*
G37*
G36*
G01X1403706Y1089404D02*
G02X1406300I1297J0D01*
G02X1406228Y1088976I-1297J-2D01*
G01X1406197Y1088889D01*
X1407004Y1087492D01*
X1407094Y1087475D01*
G02X1408150Y1086200I-242J-1275D01*
G02X1405554I-1298J0D01*
G02X1405627Y1086629I1297J0D01*
G01X1405658Y1086715D01*
X1404851Y1088112D01*
X1404761Y1088129D01*
G02X1403706Y1089404I243J1275D01*
G37*
G36*
G01X407214Y1092608D02*
G02X409808I1297J0D01*
G02X408753Y1091333I-1298J0D01*
G01X408663Y1091316D01*
X407856Y1089919D01*
X407887Y1089833D01*
G02X407960Y1089404I-1224J-429D01*
G02X405364I-1298J0D01*
G02X406420Y1090679I1298J0D01*
G01X406510Y1090696D01*
X407317Y1092093D01*
X407286Y1092180D01*
G02X407214Y1092608I1225J426D01*
G37*
G36*
G01X418314D02*
G02X420908I1297J0D01*
G02X420836Y1092180I-1297J-2D01*
G01X420805Y1092093D01*
X421612Y1090696D01*
X421702Y1090679D01*
G02X422760Y1089404I-239J-1275D01*
G02X420164I-1298J0D01*
G02X420237Y1089831I1298J-2D01*
G01X420267Y1089917D01*
X419459Y1091316D01*
X419369Y1091333D01*
G02X418314Y1092608I243J1275D01*
G37*
G36*
G01X427011Y1093906D02*
G02X428050Y1093386I0J-1298D01*
G01X429672D01*
G02X430711Y1093906I1039J-778D01*
G02Y1091310I0J-1298D01*
G02X429672Y1091830I0J1298D01*
G01X428050D01*
G02X427011Y1091310I-1039J778D01*
G02Y1093906I0J1298D01*
G37*
G36*
G01X1383356Y1092608D02*
G02X1385950I1297J0D01*
G02X1384895Y1091333I-1298J0D01*
G01X1384805Y1091316D01*
X1383998Y1089919D01*
X1384029Y1089833D01*
G02X1384102Y1089404I-1224J-429D01*
G02X1381506I-1298J0D01*
G02X1382562Y1090679I1298J0D01*
G01X1382652Y1090696D01*
X1383459Y1092093D01*
X1383428Y1092180D01*
G02X1383356Y1092608I1225J426D01*
G37*
G36*
G01X1394456D02*
G02X1397050I1297J0D01*
G02X1396978Y1092180I-1297J-2D01*
G01X1396947Y1092093D01*
X1397754Y1090696D01*
X1397844Y1090679D01*
G02X1398902Y1089404I-239J-1275D01*
G02X1396306I-1298J0D01*
G02X1396379Y1089831I1298J-2D01*
G01X1396409Y1089917D01*
X1395601Y1091316D01*
X1395511Y1091333D01*
G02X1394456Y1092608I243J1275D01*
G37*
G36*
G01X1403153Y1093906D02*
G02X1404192Y1093386I0J-1298D01*
G01X1405814D01*
G02X1406853Y1093906I1039J-778D01*
G02Y1091310I0J-1298D01*
G02X1405814Y1091830I0J1298D01*
G01X1404192D01*
G02X1403153Y1091310I-1039J778D01*
G02Y1093906I0J1298D01*
G37*
G36*
G01X423864Y1095813D02*
G02X426460I1298J0D01*
G02X425404Y1094538I-1298J0D01*
G01X425314Y1094521D01*
X424506Y1093122D01*
X424536Y1093035D01*
G02X424608Y1092610I-1225J-426D01*
G01Y1092608D01*
G02X422014I-1297J0D01*
G02X423070Y1093883I1298J0D01*
G01X423161Y1093900D01*
X423968Y1095298D01*
X423937Y1095385D01*
G02X423864Y1095813I1225J429D01*
G37*
G36*
G01X1400006D02*
G02X1402602I1298J0D01*
G02X1401546Y1094538I-1298J0D01*
G01X1401456Y1094521D01*
X1400648Y1093122D01*
X1400678Y1093035D01*
G02X1400750Y1092610I-1225J-426D01*
G01Y1092608D01*
G02X1398156I-1297J0D01*
G02X1399212Y1093883I1298J0D01*
G01X1399303Y1093900D01*
X1400110Y1095298D01*
X1400079Y1095385D01*
G02X1400006Y1095813I1225J429D01*
G37*
G36*
G01X404811Y1100314D02*
G02X405850Y1099794I0J-1298D01*
G01X407472D01*
G02X408511Y1100314I1039J-778D01*
G02Y1097720I0J-1297D01*
G02X407472Y1098240I0J1298D01*
G01X405850D01*
G02X404811Y1097720I-1039J778D01*
G02Y1100314I0J1297D01*
G37*
G36*
G01X1380953D02*
G02X1381992Y1099794I0J-1298D01*
G01X1383614D01*
G02X1384653Y1100314I1039J-778D01*
G02Y1097720I0J-1297D01*
G02X1383614Y1098240I0J1298D01*
G01X1381992D01*
G02X1380953Y1097720I-1039J778D01*
G02Y1100314I0J1297D01*
G37*
G36*
G01X351161Y1103518D02*
G02X352200Y1102998I0J-1298D01*
G01X353822D01*
G02X354861Y1103518I1039J-778D01*
G02Y1100924I0J-1297D01*
G02X353822Y1101444I0J1298D01*
G01X352200D01*
G02X351161Y1100924I-1039J778D01*
G02Y1103518I0J1297D01*
G37*
G36*
G01X401664Y1102221D02*
G02X404260I1298J0D01*
G02X403204Y1100946I-1298J0D01*
G01X403114Y1100929D01*
X402306Y1099530D01*
X402336Y1099444D01*
G02X402408Y1099019I-1225J-426D01*
G01Y1099017D01*
G02X399814I-1297J0D01*
G02X400871Y1100292I1297J0D01*
G01X400961Y1100309D01*
X401768Y1101706D01*
X401737Y1101793D01*
G02X401664Y1102221I1225J429D01*
G37*
G36*
G01X1327303Y1103518D02*
G02X1328342Y1102998I0J-1298D01*
G01X1329964D01*
G02X1331003Y1103518I1039J-778D01*
G02Y1100924I0J-1297D01*
G02X1329964Y1101444I0J1298D01*
G01X1328342D01*
G02X1327303Y1100924I-1039J778D01*
G02Y1103518I0J1297D01*
G37*
G36*
G01X1377806Y1102221D02*
G02X1380402I1298J0D01*
G02X1379346Y1100946I-1298J0D01*
G01X1379256Y1100929D01*
X1378448Y1099530D01*
X1378478Y1099444D01*
G02X1378550Y1099019I-1225J-426D01*
G01Y1099017D01*
G02X1375956I-1297J0D01*
G02X1377013Y1100292I1297J0D01*
G01X1377103Y1100309D01*
X1377910Y1101706D01*
X1377879Y1101793D01*
G02X1377806Y1102221I1225J429D01*
G37*
G36*
G01X375211Y1106724D02*
G02X376250Y1106204I0J-1298D01*
G01X377873D01*
G02X378912Y1106724I1039J-778D01*
G02Y1104128I0J-1298D01*
G02X377873Y1104648I0J1298D01*
G01X376250D01*
G02X375211Y1104128I-1039J778D01*
G02Y1106724I0J1298D01*
G37*
G36*
G01X381314Y1105426D02*
G02X383908I1297J0D01*
G02X382853Y1104151I-1298J0D01*
G01X382763Y1104134D01*
X381956Y1102737D01*
X381986Y1102650D01*
G02X382060Y1102221I-1223J-432D01*
G02X379464I-1298J0D01*
G02X380519Y1103496I1298J0D01*
G01X380609Y1103513D01*
X381417Y1104911D01*
X381386Y1104998D01*
G02X381314Y1105426I1225J426D01*
G37*
G36*
G01X410914D02*
G02X413508I1297J0D01*
G02X413436Y1104998I-1297J-2D01*
G01X413405Y1104911D01*
X414212Y1103513D01*
X414303Y1103496D01*
G02X415360Y1102221I-240J-1275D01*
G02X412764I-1298J0D01*
G02X412837Y1102648I1298J-2D01*
G01X412867Y1102735D01*
X412059Y1104134D01*
X411969Y1104151D01*
G02X410914Y1105426I243J1275D01*
G37*
G36*
G01X415911Y1106724D02*
G02X416950Y1106204I0J-1298D01*
G01X418572D01*
G02X419611Y1106724I1039J-778D01*
G02Y1104128I0J-1298D01*
G02X418572Y1104648I0J1298D01*
G01X416950D01*
G02X415911Y1104128I-1039J778D01*
G02Y1106724I0J1298D01*
G37*
G36*
G01X1351353D02*
G02X1352392Y1106204I0J-1298D01*
G01X1354015D01*
G02X1355054Y1106724I1039J-778D01*
G02Y1104128I0J-1298D01*
G02X1354015Y1104648I0J1298D01*
G01X1352392D01*
G02X1351353Y1104128I-1039J778D01*
G02Y1106724I0J1298D01*
G37*
G36*
G01X1357456Y1105426D02*
G02X1360050I1297J0D01*
G02X1358995Y1104151I-1298J0D01*
G01X1358905Y1104134D01*
X1358098Y1102737D01*
X1358128Y1102650D01*
G02X1358202Y1102221I-1223J-432D01*
G02X1355606I-1298J0D01*
G02X1356661Y1103496I1298J0D01*
G01X1356751Y1103513D01*
X1357559Y1104911D01*
X1357528Y1104998D01*
G02X1357456Y1105426I1225J426D01*
G37*
G36*
G01X1387056D02*
G02X1389650I1297J0D01*
G02X1389578Y1104998I-1297J-2D01*
G01X1389547Y1104911D01*
X1390354Y1103513D01*
X1390445Y1103496D01*
G02X1391502Y1102221I-240J-1275D01*
G02X1388906I-1298J0D01*
G02X1388979Y1102648I1298J-2D01*
G01X1389009Y1102735D01*
X1388201Y1104134D01*
X1388111Y1104151D01*
G02X1387056Y1105426I243J1275D01*
G37*
G36*
G01X1392053Y1106724D02*
G02X1393092Y1106204I0J-1298D01*
G01X1394714D01*
G02X1395753Y1106724I1039J-778D01*
G02Y1104128I0J-1298D01*
G02X1394714Y1104648I0J1298D01*
G01X1393092D01*
G02X1392053Y1104128I-1039J778D01*
G02Y1106724I0J1298D01*
G37*
G36*
G01X358561Y1109928D02*
G02X359600Y1109408I0J-1298D01*
G01X361222D01*
G02X362261Y1109928I1039J-778D01*
G02Y1107332I0J-1298D01*
G02X361222Y1107852I0J1298D01*
G01X359600D01*
G02X358561Y1107332I-1039J778D01*
G02Y1109928I0J1298D01*
G37*
G36*
G01X383164Y1108630D02*
G02X385760I1298J0D01*
G02X385687Y1108202I-1298J1D01*
G01X385656Y1108115D01*
X386463Y1106718D01*
X386553Y1106701D01*
G02X387608Y1105426I-243J-1275D01*
G02X385014I-1297J0D01*
G02X385086Y1105855I1297J3D01*
G01X385117Y1105941D01*
X384310Y1107338D01*
X384220Y1107355D01*
G02X383164Y1108630I242J1275D01*
G37*
G36*
G01X391862Y1109928D02*
G02X392901Y1109408I0J-1298D01*
G01X394523D01*
G02X395562Y1109928I1039J-778D01*
G02Y1107332I0J-1298D01*
G02X394523Y1107852I0J1298D01*
G01X392901D01*
G02X391862Y1107332I-1039J778D01*
G02Y1109928I0J1298D01*
G37*
G36*
G01X397964Y1108630D02*
G02X400560I1298J0D01*
G02X399504Y1107355I-1298J0D01*
G01X399414Y1107338D01*
X398606Y1105939D01*
X398636Y1105853D01*
G02X398708Y1105428I-1225J-426D01*
G01Y1105426D01*
G02X396114I-1297J0D01*
G02X397171Y1106701I1297J0D01*
G01X397261Y1106718D01*
X398068Y1108115D01*
X398037Y1108202D01*
G02X397964Y1108630I1225J429D01*
G37*
G36*
G01X409064D02*
G02X411660I1298J0D01*
G02X410604Y1107355I-1298J0D01*
G01X410514Y1107338D01*
X409706Y1105939D01*
X409736Y1105853D01*
G02X409808Y1105428I-1225J-426D01*
G01Y1105426D01*
G02X407214I-1297J0D01*
G02X408271Y1106701I1297J0D01*
G01X408361Y1106718D01*
X409168Y1108115D01*
X409137Y1108202D01*
G02X409064Y1108630I1225J429D01*
G37*
G36*
G01X1334703Y1109928D02*
G02X1335742Y1109408I0J-1298D01*
G01X1337364D01*
G02X1338403Y1109928I1039J-778D01*
G02Y1107332I0J-1298D01*
G02X1337364Y1107852I0J1298D01*
G01X1335742D01*
G02X1334703Y1107332I-1039J778D01*
G02Y1109928I0J1298D01*
G37*
G36*
G01X1359306Y1108630D02*
G02X1361902I1298J0D01*
G02X1361829Y1108202I-1298J1D01*
G01X1361798Y1108115D01*
X1362605Y1106718D01*
X1362695Y1106701D01*
G02X1363750Y1105426I-243J-1275D01*
G02X1361156I-1297J0D01*
G02X1361228Y1105855I1297J3D01*
G01X1361259Y1105941D01*
X1360452Y1107338D01*
X1360362Y1107355D01*
G02X1359306Y1108630I242J1275D01*
G37*
G36*
G01X1368004Y1109928D02*
G02X1369043Y1109408I0J-1298D01*
G01X1370665D01*
G02X1371704Y1109928I1039J-778D01*
G02Y1107332I0J-1298D01*
G02X1370665Y1107852I0J1298D01*
G01X1369043D01*
G02X1368004Y1107332I-1039J778D01*
G02Y1109928I0J1298D01*
G37*
G36*
G01X1374106Y1108630D02*
G02X1376702I1298J0D01*
G02X1375646Y1107355I-1298J0D01*
G01X1375556Y1107338D01*
X1374748Y1105939D01*
X1374778Y1105853D01*
G02X1374850Y1105428I-1225J-426D01*
G01Y1105426D01*
G02X1372256I-1297J0D01*
G02X1373313Y1106701I1297J0D01*
G01X1373403Y1106718D01*
X1374210Y1108115D01*
X1374179Y1108202D01*
G02X1374106Y1108630I1225J429D01*
G37*
G36*
G01X1385206D02*
G02X1387802I1298J0D01*
G02X1386746Y1107355I-1298J0D01*
G01X1386656Y1107338D01*
X1385848Y1105939D01*
X1385878Y1105853D01*
G02X1385950Y1105428I-1225J-426D01*
G01Y1105426D01*
G02X1383356I-1297J0D01*
G02X1384413Y1106701I1297J0D01*
G01X1384503Y1106718D01*
X1385310Y1108115D01*
X1385279Y1108202D01*
G02X1385206Y1108630I1225J429D01*
G37*
G36*
G01X366514Y1111834D02*
G02X369110I1298J0D01*
G02X369037Y1111406I-1298J1D01*
G01X369006Y1111319D01*
X369813Y1109922D01*
X369903Y1109905D01*
G02X370958Y1108630I-243J-1275D01*
G02X368364I-1297J0D01*
G02X368436Y1109059I1297J3D01*
G01X368467Y1109145D01*
X367660Y1110542D01*
X367570Y1110559D01*
G02X366514Y1111834I242J1275D01*
G37*
G36*
G01X373914D02*
G02X376508I1297J0D01*
G02X376436Y1111406I-1297J-2D01*
G01X376405Y1111319D01*
X377212Y1109922D01*
X377302Y1109905D01*
G02X378360Y1108630I-239J-1275D01*
G02X375764I-1298J0D01*
G02X375837Y1109057I1298J-2D01*
G01X375867Y1109143D01*
X375059Y1110542D01*
X374969Y1110559D01*
G02X373914Y1111834I243J1275D01*
G37*
G36*
G01X382611Y1113132D02*
G02X383650Y1112612I0J-1298D01*
G01X385272D01*
G02X386311Y1113132I1039J-778D01*
G02Y1110536I0J-1298D01*
G02X385272Y1111056I0J1298D01*
G01X383650D01*
G02X382611Y1110536I-1039J778D01*
G02Y1113132I0J1298D01*
G37*
G36*
G01X399814Y1111834D02*
G02X402408I1297J0D01*
G02X402336Y1111406I-1297J-2D01*
G01X402305Y1111319D01*
X403112Y1109922D01*
X403202Y1109905D01*
G02X404260Y1108630I-239J-1275D01*
G02X401664I-1298J0D01*
G02X401737Y1109057I1298J-2D01*
G01X401767Y1109143D01*
X400959Y1110542D01*
X400869Y1110559D01*
G02X399814Y1111834I243J1275D01*
G37*
G36*
G01X408511Y1113132D02*
G02X409550Y1112612I0J-1298D01*
G01X411172D01*
G02X412211Y1113132I1039J-778D01*
G02Y1110536I0J-1298D01*
G02X411172Y1111056I0J1298D01*
G01X409550D01*
G02X408511Y1110536I-1039J778D01*
G02Y1113132I0J1298D01*
G37*
G36*
G01X418314Y1111834D02*
G02X420908I1297J0D01*
G02X419853Y1110559I-1298J0D01*
G01X419763Y1110542D01*
X418956Y1109145D01*
X418987Y1109059D01*
G02X419060Y1108630I-1224J-429D01*
G02X416464I-1298J0D01*
G02X417520Y1109905I1298J0D01*
G01X417610Y1109922D01*
X418417Y1111319D01*
X418386Y1111406D01*
G02X418314Y1111834I1225J426D01*
G37*
G36*
G01X1342656D02*
G02X1345252I1298J0D01*
G02X1345179Y1111406I-1298J1D01*
G01X1345148Y1111319D01*
X1345955Y1109922D01*
X1346045Y1109905D01*
G02X1347100Y1108630I-243J-1275D01*
G02X1344506I-1297J0D01*
G02X1344578Y1109059I1297J3D01*
G01X1344609Y1109145D01*
X1343802Y1110542D01*
X1343712Y1110559D01*
G02X1342656Y1111834I242J1275D01*
G37*
G36*
G01X1350056D02*
G02X1352650I1297J0D01*
G02X1352578Y1111406I-1297J-2D01*
G01X1352547Y1111319D01*
X1353354Y1109922D01*
X1353444Y1109905D01*
G02X1354502Y1108630I-239J-1275D01*
G02X1351906I-1298J0D01*
G02X1351979Y1109057I1298J-2D01*
G01X1352009Y1109143D01*
X1351201Y1110542D01*
X1351111Y1110559D01*
G02X1350056Y1111834I243J1275D01*
G37*
G36*
G01X1358753Y1113132D02*
G02X1359792Y1112612I0J-1298D01*
G01X1361414D01*
G02X1362453Y1113132I1039J-778D01*
G02Y1110536I0J-1298D01*
G02X1361414Y1111056I0J1298D01*
G01X1359792D01*
G02X1358753Y1110536I-1039J778D01*
G02Y1113132I0J1298D01*
G37*
G36*
G01X1375956Y1111834D02*
G02X1378550I1297J0D01*
G02X1378478Y1111406I-1297J-2D01*
G01X1378447Y1111319D01*
X1379254Y1109922D01*
X1379344Y1109905D01*
G02X1380402Y1108630I-239J-1275D01*
G02X1377806I-1298J0D01*
G02X1377879Y1109057I1298J-2D01*
G01X1377909Y1109143D01*
X1377101Y1110542D01*
X1377011Y1110559D01*
G02X1375956Y1111834I243J1275D01*
G37*
G36*
G01X1384653Y1113132D02*
G02X1385692Y1112612I0J-1298D01*
G01X1387314D01*
G02X1388353Y1113132I1039J-778D01*
G02Y1110536I0J-1298D01*
G02X1387314Y1111056I0J1298D01*
G01X1385692D01*
G02X1384653Y1110536I-1039J778D01*
G02Y1113132I0J1298D01*
G37*
G36*
G01X1394456Y1111834D02*
G02X1397050I1297J0D01*
G02X1395995Y1110559I-1298J0D01*
G01X1395905Y1110542D01*
X1395098Y1109145D01*
X1395129Y1109059D01*
G02X1395202Y1108630I-1224J-429D01*
G02X1392606I-1298J0D01*
G02X1393662Y1109905I1298J0D01*
G01X1393752Y1109922D01*
X1394559Y1111319D01*
X1394528Y1111406D01*
G02X1394456Y1111834I1225J426D01*
G37*
G36*
G01X346164Y1115039D02*
G02X348758I1297J0D01*
G02X347703Y1113764I-1298J0D01*
G01X347613Y1113747D01*
X346805Y1112349D01*
X346836Y1112262D01*
G02X346908Y1111834I-1225J-426D01*
G02X344314I-1297J0D01*
G02X345369Y1113109I1298J0D01*
G01X345459Y1113126D01*
X346267Y1114524D01*
X346236Y1114611D01*
G02X346164Y1115039I1225J426D01*
G37*
G36*
G01X365961Y1116336D02*
G02X367000Y1115816I0J-1298D01*
G01X368622D01*
G02X369661Y1116336I1039J-778D01*
G02Y1113742I0J-1297D01*
G02X368622Y1114262I0J1298D01*
G01X367000D01*
G02X365961Y1113742I-1039J778D01*
G02Y1116336I0J1297D01*
G37*
G36*
G01X379464Y1115039D02*
G02X382060I1298J0D01*
G02X381004Y1113764I-1298J0D01*
G01X380914Y1113747D01*
X380106Y1112348D01*
X380136Y1112261D01*
G02X380208Y1111836I-1225J-426D01*
G01Y1111834D01*
G02X377614I-1297J0D01*
G02X378670Y1113109I1298J0D01*
G01X378761Y1113126D01*
X379568Y1114524D01*
X379537Y1114611D01*
G02X379464Y1115039I1225J429D01*
G37*
G36*
G01X390564D02*
G02X393160I1298J0D01*
G02X393087Y1114611I-1298J1D01*
G01X393056Y1114524D01*
X393864Y1113126D01*
X393954Y1113109D01*
G02X395008Y1111834I-244J-1275D01*
G02X392414I-1297J0D01*
G02X392487Y1112263I1297J0D01*
G01X392517Y1112350D01*
X391710Y1113747D01*
X391620Y1113764D01*
G02X390564Y1115039I242J1275D01*
G37*
G36*
G01X399262Y1116336D02*
G02X400301Y1115816I0J-1298D01*
G01X401923D01*
G02X402962Y1116336I1039J-778D01*
G02Y1113742I0J-1297D01*
G02X401923Y1114262I0J1298D01*
G01X400301D01*
G02X399262Y1113742I-1039J778D01*
G02Y1116336I0J1297D01*
G37*
G36*
G01X412764Y1115039D02*
G02X415360I1298J0D01*
G02X415287Y1114611I-1298J1D01*
G01X415256Y1114524D01*
X416064Y1113126D01*
X416154Y1113109D01*
G02X417208Y1111834I-244J-1275D01*
G02X414614I-1297J0D01*
G02X414687Y1112263I1297J0D01*
G01X414717Y1112350D01*
X413910Y1113747D01*
X413820Y1113764D01*
G02X412764Y1115039I242J1275D01*
G37*
G36*
G01X1322306D02*
G02X1324900I1297J0D01*
G02X1323845Y1113764I-1298J0D01*
G01X1323755Y1113747D01*
X1322947Y1112349D01*
X1322978Y1112262D01*
G02X1323050Y1111834I-1225J-426D01*
G02X1320456I-1297J0D01*
G02X1321511Y1113109I1298J0D01*
G01X1321601Y1113126D01*
X1322409Y1114524D01*
X1322378Y1114611D01*
G02X1322306Y1115039I1225J426D01*
G37*
G36*
G01X1342103Y1116336D02*
G02X1343142Y1115816I0J-1298D01*
G01X1344764D01*
G02X1345803Y1116336I1039J-778D01*
G02Y1113742I0J-1297D01*
G02X1344764Y1114262I0J1298D01*
G01X1343142D01*
G02X1342103Y1113742I-1039J778D01*
G02Y1116336I0J1297D01*
G37*
G36*
G01X1355606Y1115039D02*
G02X1358202I1298J0D01*
G02X1357146Y1113764I-1298J0D01*
G01X1357056Y1113747D01*
X1356248Y1112348D01*
X1356278Y1112261D01*
G02X1356350Y1111836I-1225J-426D01*
G01Y1111834D01*
G02X1353756I-1297J0D01*
G02X1354812Y1113109I1298J0D01*
G01X1354903Y1113126D01*
X1355710Y1114524D01*
X1355679Y1114611D01*
G02X1355606Y1115039I1225J429D01*
G37*
G36*
G01X1366706D02*
G02X1369302I1298J0D01*
G02X1369229Y1114611I-1298J1D01*
G01X1369198Y1114524D01*
X1370006Y1113126D01*
X1370096Y1113109D01*
G02X1371150Y1111834I-244J-1275D01*
G02X1368556I-1297J0D01*
G02X1368629Y1112263I1297J0D01*
G01X1368659Y1112350D01*
X1367852Y1113747D01*
X1367762Y1113764D01*
G02X1366706Y1115039I242J1275D01*
G37*
G36*
G01X1375404Y1116336D02*
G02X1376443Y1115816I0J-1298D01*
G01X1378065D01*
G02X1379104Y1116336I1039J-778D01*
G02Y1113742I0J-1297D01*
G02X1378065Y1114262I0J1298D01*
G01X1376443D01*
G02X1375404Y1113742I-1039J778D01*
G02Y1116336I0J1297D01*
G37*
G36*
G01X1388906Y1115039D02*
G02X1391502I1298J0D01*
G02X1391429Y1114611I-1298J1D01*
G01X1391398Y1114524D01*
X1392206Y1113126D01*
X1392296Y1113109D01*
G02X1393350Y1111834I-244J-1275D01*
G02X1390756I-1297J0D01*
G02X1390829Y1112263I1297J0D01*
G01X1390859Y1112350D01*
X1390052Y1113747D01*
X1389962Y1113764D01*
G02X1388906Y1115039I242J1275D01*
G37*
G36*
G01X342464Y1121447D02*
G02X345058I1297J0D01*
G02X344003Y1120172I-1298J0D01*
G01X343913Y1120155D01*
X343106Y1118758D01*
X343137Y1118671D01*
G02X343210Y1118243I-1225J-429D01*
G02X340614I-1298J0D01*
G02X341670Y1119518I1298J0D01*
G01X341760Y1119535D01*
X342567Y1120932D01*
X342536Y1121019D01*
G02X342464Y1121447I1225J426D01*
G37*
G36*
G01X1318606D02*
G02X1321200I1297J0D01*
G02X1320145Y1120172I-1298J0D01*
G01X1320055Y1120155D01*
X1319248Y1118758D01*
X1319279Y1118671D01*
G02X1319352Y1118243I-1225J-429D01*
G02X1316756I-1298J0D01*
G02X1317812Y1119518I1298J0D01*
G01X1317902Y1119535D01*
X1318709Y1120932D01*
X1318678Y1121019D01*
G02X1318606Y1121447I1225J426D01*
G37*
G36*
G01X355414Y1124651D02*
G02X358010I1298J0D01*
G02X357937Y1124223I-1298J1D01*
G01X357906Y1124136D01*
X358713Y1122739D01*
X358803Y1122722D01*
G02X359858Y1121447I-243J-1275D01*
G02X357264I-1297J0D01*
G02X357336Y1121876I1297J3D01*
G01X357367Y1121962D01*
X356560Y1123359D01*
X356470Y1123376D01*
G02X355414Y1124651I242J1275D01*
G37*
G36*
G01X362814D02*
G02X365408I1297J0D01*
G02X365336Y1124223I-1297J-2D01*
G01X365305Y1124136D01*
X366112Y1122739D01*
X366202Y1122722D01*
G02X367260Y1121447I-239J-1275D01*
G02X364664I-1298J0D01*
G02X364737Y1121874I1298J-2D01*
G01X364767Y1121960D01*
X363959Y1123359D01*
X363869Y1123376D01*
G02X362814Y1124651I243J1275D01*
G37*
G36*
G01X370214D02*
G02X372808I1297J0D01*
G02X372736Y1124223I-1297J-2D01*
G01X372705Y1124136D01*
X373512Y1122739D01*
X373602Y1122722D01*
G02X374660Y1121447I-239J-1275D01*
G02X372064I-1298J0D01*
G02X372137Y1121874I1298J-2D01*
G01X372167Y1121960D01*
X371359Y1123359D01*
X371269Y1123376D01*
G02X370214Y1124651I243J1275D01*
G37*
G36*
G01X377614D02*
G02X380208I1297J0D01*
G02X380136Y1124223I-1297J-2D01*
G01X380105Y1124136D01*
X380912Y1122739D01*
X381002Y1122722D01*
G02X382060Y1121447I-239J-1275D01*
G02X379464I-1298J0D01*
G02X379537Y1121874I1298J-2D01*
G01X379567Y1121960D01*
X378759Y1123359D01*
X378669Y1123376D01*
G02X377614Y1124651I243J1275D01*
G37*
G36*
G01X385014D02*
G02X387608I1297J0D01*
G02X387536Y1124223I-1297J-2D01*
G01X387505Y1124136D01*
X388312Y1122739D01*
X388402Y1122722D01*
G02X389460Y1121447I-239J-1275D01*
G02X386864I-1298J0D01*
G02X386937Y1121874I1298J-2D01*
G01X386967Y1121960D01*
X386159Y1123359D01*
X386069Y1123376D01*
G02X385014Y1124651I243J1275D01*
G37*
G36*
G01X392414D02*
G02X395008I1297J0D01*
G02X394936Y1124223I-1297J-2D01*
G01X394905Y1124136D01*
X395712Y1122739D01*
X395802Y1122722D01*
G02X396860Y1121447I-239J-1275D01*
G02X394264I-1298J0D01*
G02X394337Y1121874I1298J-2D01*
G01X394367Y1121960D01*
X393559Y1123359D01*
X393469Y1123376D01*
G02X392414Y1124651I243J1275D01*
G37*
G36*
G01X399814D02*
G02X402408I1297J0D01*
G02X402336Y1124223I-1297J-2D01*
G01X402305Y1124136D01*
X403112Y1122739D01*
X403202Y1122722D01*
G02X404260Y1121447I-239J-1275D01*
G02X401664I-1298J0D01*
G02X401737Y1121874I1298J-2D01*
G01X401767Y1121960D01*
X400959Y1123359D01*
X400869Y1123376D01*
G02X399814Y1124651I243J1275D01*
G37*
G36*
G01X407214D02*
G02X409808I1297J0D01*
G02X409736Y1124223I-1297J-2D01*
G01X409705Y1124136D01*
X410512Y1122739D01*
X410602Y1122722D01*
G02X411660Y1121447I-239J-1275D01*
G02X409064I-1298J0D01*
G02X409137Y1121874I1298J-2D01*
G01X409167Y1121960D01*
X408359Y1123359D01*
X408269Y1123376D01*
G02X407214Y1124651I243J1275D01*
G37*
G36*
G01X470114D02*
G02X472708I1297J0D01*
G02X471653Y1123376I-1298J0D01*
G01X471563Y1123359D01*
X470756Y1121962D01*
X470787Y1121875D01*
G02X470860Y1121447I-1225J-429D01*
G02X468264I-1298J0D01*
G02X469320Y1122722I1298J0D01*
G01X469410Y1122739D01*
X470217Y1124136D01*
X470186Y1124223D01*
G02X470114Y1124651I1225J426D01*
G37*
G36*
G01X477514D02*
G02X480108I1297J0D01*
G02X479053Y1123376I-1298J0D01*
G01X478963Y1123359D01*
X478156Y1121962D01*
X478187Y1121875D01*
G02X478260Y1121447I-1225J-429D01*
G02X475664I-1298J0D01*
G02X476720Y1122722I1298J0D01*
G01X476810Y1122739D01*
X477617Y1124136D01*
X477586Y1124223D01*
G02X477514Y1124651I1225J426D01*
G37*
G36*
G01X484914D02*
G02X487508I1297J0D01*
G02X486453Y1123376I-1298J0D01*
G01X486363Y1123359D01*
X485556Y1121962D01*
X485587Y1121875D01*
G02X485660Y1121447I-1225J-429D01*
G02X483064I-1298J0D01*
G02X484120Y1122722I1298J0D01*
G01X484210Y1122739D01*
X485017Y1124136D01*
X484986Y1124223D01*
G02X484914Y1124651I1225J426D01*
G37*
G36*
G01X492314D02*
G02X494908I1297J0D01*
G02X493853Y1123376I-1298J0D01*
G01X493763Y1123359D01*
X492956Y1121962D01*
X492987Y1121875D01*
G02X493060Y1121447I-1225J-429D01*
G02X490464I-1298J0D01*
G02X491520Y1122722I1298J0D01*
G01X491610Y1122739D01*
X492417Y1124136D01*
X492386Y1124223D01*
G02X492314Y1124651I1225J426D01*
G37*
G36*
G01X499714D02*
G02X502308I1297J0D01*
G02X501253Y1123376I-1298J0D01*
G01X501163Y1123359D01*
X500356Y1121962D01*
X500387Y1121875D01*
G02X500460Y1121447I-1225J-429D01*
G02X497864I-1298J0D01*
G02X498920Y1122722I1298J0D01*
G01X499010Y1122739D01*
X499817Y1124136D01*
X499786Y1124223D01*
G02X499714Y1124651I1225J426D01*
G37*
G36*
G01X507114D02*
G02X509708I1297J0D01*
G02X508653Y1123376I-1298J0D01*
G01X508563Y1123359D01*
X507756Y1121962D01*
X507787Y1121875D01*
G02X507860Y1121447I-1225J-429D01*
G02X505264I-1298J0D01*
G02X506320Y1122722I1298J0D01*
G01X506410Y1122739D01*
X507217Y1124136D01*
X507186Y1124223D01*
G02X507114Y1124651I1225J426D01*
G37*
G36*
G01X514514D02*
G02X517108I1297J0D01*
G02X516053Y1123376I-1298J0D01*
G01X515963Y1123359D01*
X515156Y1121962D01*
X515187Y1121875D01*
G02X515260Y1121447I-1225J-429D01*
G02X512664I-1298J0D01*
G02X513720Y1122722I1298J0D01*
G01X513810Y1122739D01*
X514617Y1124136D01*
X514586Y1124223D01*
G02X514514Y1124651I1225J426D01*
G37*
G36*
G01X521914D02*
G02X524508I1297J0D01*
G02X523453Y1123376I-1298J0D01*
G01X523363Y1123359D01*
X522556Y1121962D01*
X522587Y1121875D01*
G02X522660Y1121447I-1225J-429D01*
G02X520064I-1298J0D01*
G02X521120Y1122722I1298J0D01*
G01X521210Y1122739D01*
X522017Y1124136D01*
X521986Y1124223D01*
G02X521914Y1124651I1225J426D01*
G37*
G36*
G01X1331556D02*
G02X1334152I1298J0D01*
G02X1334079Y1124223I-1298J1D01*
G01X1334048Y1124136D01*
X1334855Y1122739D01*
X1334945Y1122722D01*
G02X1336000Y1121447I-243J-1275D01*
G02X1333406I-1297J0D01*
G02X1333478Y1121876I1297J3D01*
G01X1333509Y1121962D01*
X1332702Y1123359D01*
X1332612Y1123376D01*
G02X1331556Y1124651I242J1275D01*
G37*
G36*
G01X1338956D02*
G02X1341550I1297J0D01*
G02X1341478Y1124223I-1297J-2D01*
G01X1341447Y1124136D01*
X1342254Y1122739D01*
X1342344Y1122722D01*
G02X1343402Y1121447I-239J-1275D01*
G02X1340806I-1298J0D01*
G02X1340879Y1121874I1298J-2D01*
G01X1340909Y1121960D01*
X1340101Y1123359D01*
X1340011Y1123376D01*
G02X1338956Y1124651I243J1275D01*
G37*
G36*
G01X1346356D02*
G02X1348950I1297J0D01*
G02X1348878Y1124223I-1297J-2D01*
G01X1348847Y1124136D01*
X1349654Y1122739D01*
X1349744Y1122722D01*
G02X1350802Y1121447I-239J-1275D01*
G02X1348206I-1298J0D01*
G02X1348279Y1121874I1298J-2D01*
G01X1348309Y1121960D01*
X1347501Y1123359D01*
X1347411Y1123376D01*
G02X1346356Y1124651I243J1275D01*
G37*
G36*
G01X1353756D02*
G02X1356350I1297J0D01*
G02X1356278Y1124223I-1297J-2D01*
G01X1356247Y1124136D01*
X1357054Y1122739D01*
X1357144Y1122722D01*
G02X1358202Y1121447I-239J-1275D01*
G02X1355606I-1298J0D01*
G02X1355679Y1121874I1298J-2D01*
G01X1355709Y1121960D01*
X1354901Y1123359D01*
X1354811Y1123376D01*
G02X1353756Y1124651I243J1275D01*
G37*
G36*
G01X1361156D02*
G02X1363750I1297J0D01*
G02X1363678Y1124223I-1297J-2D01*
G01X1363647Y1124136D01*
X1364454Y1122739D01*
X1364544Y1122722D01*
G02X1365602Y1121447I-239J-1275D01*
G02X1363006I-1298J0D01*
G02X1363079Y1121874I1298J-2D01*
G01X1363109Y1121960D01*
X1362301Y1123359D01*
X1362211Y1123376D01*
G02X1361156Y1124651I243J1275D01*
G37*
G36*
G01X1368556D02*
G02X1371150I1297J0D01*
G02X1371078Y1124223I-1297J-2D01*
G01X1371047Y1124136D01*
X1371854Y1122739D01*
X1371944Y1122722D01*
G02X1373002Y1121447I-239J-1275D01*
G02X1370406I-1298J0D01*
G02X1370479Y1121874I1298J-2D01*
G01X1370509Y1121960D01*
X1369701Y1123359D01*
X1369611Y1123376D01*
G02X1368556Y1124651I243J1275D01*
G37*
G36*
G01X1375956D02*
G02X1378550I1297J0D01*
G02X1378478Y1124223I-1297J-2D01*
G01X1378447Y1124136D01*
X1379254Y1122739D01*
X1379344Y1122722D01*
G02X1380402Y1121447I-239J-1275D01*
G02X1377806I-1298J0D01*
G02X1377879Y1121874I1298J-2D01*
G01X1377909Y1121960D01*
X1377101Y1123359D01*
X1377011Y1123376D01*
G02X1375956Y1124651I243J1275D01*
G37*
G36*
G01X1383356D02*
G02X1385950I1297J0D01*
G02X1385878Y1124223I-1297J-2D01*
G01X1385847Y1124136D01*
X1386654Y1122739D01*
X1386744Y1122722D01*
G02X1387802Y1121447I-239J-1275D01*
G02X1385206I-1298J0D01*
G02X1385279Y1121874I1298J-2D01*
G01X1385309Y1121960D01*
X1384501Y1123359D01*
X1384411Y1123376D01*
G02X1383356Y1124651I243J1275D01*
G37*
G36*
G01X1446256D02*
G02X1448850I1297J0D01*
G02X1447795Y1123376I-1298J0D01*
G01X1447705Y1123359D01*
X1446898Y1121962D01*
X1446929Y1121875D01*
G02X1447002Y1121447I-1225J-429D01*
G02X1444406I-1298J0D01*
G02X1445462Y1122722I1298J0D01*
G01X1445552Y1122739D01*
X1446359Y1124136D01*
X1446328Y1124223D01*
G02X1446256Y1124651I1225J426D01*
G37*
G36*
G01X1453656D02*
G02X1456250I1297J0D01*
G02X1455195Y1123376I-1298J0D01*
G01X1455105Y1123359D01*
X1454298Y1121962D01*
X1454329Y1121875D01*
G02X1454402Y1121447I-1225J-429D01*
G02X1451806I-1298J0D01*
G02X1452862Y1122722I1298J0D01*
G01X1452952Y1122739D01*
X1453759Y1124136D01*
X1453728Y1124223D01*
G02X1453656Y1124651I1225J426D01*
G37*
G36*
G01X1461056D02*
G02X1463650I1297J0D01*
G02X1462595Y1123376I-1298J0D01*
G01X1462505Y1123359D01*
X1461698Y1121962D01*
X1461729Y1121875D01*
G02X1461802Y1121447I-1225J-429D01*
G02X1459206I-1298J0D01*
G02X1460262Y1122722I1298J0D01*
G01X1460352Y1122739D01*
X1461159Y1124136D01*
X1461128Y1124223D01*
G02X1461056Y1124651I1225J426D01*
G37*
G36*
G01X1468456D02*
G02X1471050I1297J0D01*
G02X1469995Y1123376I-1298J0D01*
G01X1469905Y1123359D01*
X1469098Y1121962D01*
X1469129Y1121875D01*
G02X1469202Y1121447I-1225J-429D01*
G02X1466606I-1298J0D01*
G02X1467662Y1122722I1298J0D01*
G01X1467752Y1122739D01*
X1468559Y1124136D01*
X1468528Y1124223D01*
G02X1468456Y1124651I1225J426D01*
G37*
G36*
G01X1475856D02*
G02X1478450I1297J0D01*
G02X1477395Y1123376I-1298J0D01*
G01X1477305Y1123359D01*
X1476498Y1121962D01*
X1476529Y1121875D01*
G02X1476602Y1121447I-1225J-429D01*
G02X1474006I-1298J0D01*
G02X1475062Y1122722I1298J0D01*
G01X1475152Y1122739D01*
X1475959Y1124136D01*
X1475928Y1124223D01*
G02X1475856Y1124651I1225J426D01*
G37*
G36*
G01X1483256D02*
G02X1485850I1297J0D01*
G02X1484795Y1123376I-1298J0D01*
G01X1484705Y1123359D01*
X1483898Y1121962D01*
X1483929Y1121875D01*
G02X1484002Y1121447I-1225J-429D01*
G02X1481406I-1298J0D01*
G02X1482462Y1122722I1298J0D01*
G01X1482552Y1122739D01*
X1483359Y1124136D01*
X1483328Y1124223D01*
G02X1483256Y1124651I1225J426D01*
G37*
G36*
G01X1490656D02*
G02X1493250I1297J0D01*
G02X1492195Y1123376I-1298J0D01*
G01X1492105Y1123359D01*
X1491298Y1121962D01*
X1491329Y1121875D01*
G02X1491402Y1121447I-1225J-429D01*
G02X1488806I-1298J0D01*
G02X1489862Y1122722I1298J0D01*
G01X1489952Y1122739D01*
X1490759Y1124136D01*
X1490728Y1124223D01*
G02X1490656Y1124651I1225J426D01*
G37*
G36*
G01X1498056D02*
G02X1500650I1297J0D01*
G02X1499595Y1123376I-1298J0D01*
G01X1499505Y1123359D01*
X1498698Y1121962D01*
X1498729Y1121875D01*
G02X1498802Y1121447I-1225J-429D01*
G02X1496206I-1298J0D01*
G02X1497262Y1122722I1298J0D01*
G01X1497352Y1122739D01*
X1498159Y1124136D01*
X1498128Y1124223D01*
G02X1498056Y1124651I1225J426D01*
G37*
G36*
G01X353564Y1127856D02*
G02X356158I1297J0D01*
G02X355103Y1126581I-1298J0D01*
G01X355013Y1126564D01*
X354205Y1125166D01*
X354236Y1125079D01*
G02X354308Y1124651I-1225J-426D01*
G02X351714I-1297J0D01*
G02X352769Y1125926I1298J0D01*
G01X352859Y1125943D01*
X353667Y1127341D01*
X353636Y1127428D01*
G02X353564Y1127856I1225J426D01*
G37*
G36*
G01X360964D02*
G02X363560I1298J0D01*
G02X362504Y1126581I-1298J0D01*
G01X362414Y1126564D01*
X361606Y1125166D01*
X361637Y1125079D01*
G02X361710Y1124651I-1225J-429D01*
G02X359114I-1298J0D01*
G02X360170Y1125926I1298J0D01*
G01X360260Y1125943D01*
X361068Y1127341D01*
X361037Y1127428D01*
G02X360964Y1127856I1225J429D01*
G37*
G36*
G01X368364D02*
G02X370960I1298J0D01*
G02X369904Y1126581I-1298J0D01*
G01X369814Y1126564D01*
X369006Y1125165D01*
X369036Y1125078D01*
G02X369108Y1124653I-1225J-426D01*
G01Y1124651D01*
G02X366514I-1297J0D01*
G02X367570Y1125926I1298J0D01*
G01X367661Y1125943D01*
X368468Y1127341D01*
X368437Y1127428D01*
G02X368364Y1127856I1225J429D01*
G37*
G36*
G01X375764D02*
G02X378360I1298J0D01*
G02X377304Y1126581I-1298J0D01*
G01X377214Y1126564D01*
X376406Y1125165D01*
X376436Y1125078D01*
G02X376508Y1124653I-1225J-426D01*
G01Y1124651D01*
G02X373914I-1297J0D01*
G02X374970Y1125926I1298J0D01*
G01X375061Y1125943D01*
X375868Y1127341D01*
X375837Y1127428D01*
G02X375764Y1127856I1225J429D01*
G37*
G36*
G01X383164D02*
G02X385760I1298J0D01*
G02X384704Y1126581I-1298J0D01*
G01X384614Y1126564D01*
X383806Y1125165D01*
X383836Y1125078D01*
G02X383908Y1124653I-1225J-426D01*
G01Y1124651D01*
G02X381314I-1297J0D01*
G02X382370Y1125926I1298J0D01*
G01X382461Y1125943D01*
X383268Y1127341D01*
X383237Y1127428D01*
G02X383164Y1127856I1225J429D01*
G37*
G36*
G01X390564D02*
G02X393160I1298J0D01*
G02X392104Y1126581I-1298J0D01*
G01X392014Y1126564D01*
X391206Y1125165D01*
X391236Y1125078D01*
G02X391308Y1124653I-1225J-426D01*
G01Y1124651D01*
G02X388714I-1297J0D01*
G02X389770Y1125926I1298J0D01*
G01X389861Y1125943D01*
X390668Y1127341D01*
X390637Y1127428D01*
G02X390564Y1127856I1225J429D01*
G37*
G36*
G01X397964D02*
G02X400560I1298J0D01*
G02X399504Y1126581I-1298J0D01*
G01X399414Y1126564D01*
X398606Y1125165D01*
X398636Y1125078D01*
G02X398708Y1124653I-1225J-426D01*
G01Y1124651D01*
G02X396114I-1297J0D01*
G02X397170Y1125926I1298J0D01*
G01X397261Y1125943D01*
X398068Y1127341D01*
X398037Y1127428D01*
G02X397964Y1127856I1225J429D01*
G37*
G36*
G01X405364D02*
G02X407960I1298J0D01*
G02X406904Y1126581I-1298J0D01*
G01X406814Y1126564D01*
X406006Y1125165D01*
X406036Y1125078D01*
G02X406108Y1124653I-1225J-426D01*
G01Y1124651D01*
G02X403514I-1297J0D01*
G02X404570Y1125926I1298J0D01*
G01X404661Y1125943D01*
X405468Y1127341D01*
X405437Y1127428D01*
G02X405364Y1127856I1225J429D01*
G37*
G36*
G01X471964D02*
G02X474560I1298J0D01*
G02X474487Y1127427I-1297J0D01*
G01X474456Y1127341D01*
X475263Y1125943D01*
X475353Y1125926D01*
G02X476408Y1124651I-243J-1275D01*
G02X473814I-1297J0D01*
G02X473886Y1125080I1297J3D01*
G01X473917Y1125166D01*
X473110Y1126564D01*
X473020Y1126581D01*
G02X471964Y1127856I242J1275D01*
G37*
G36*
G01X479364D02*
G02X481960I1298J0D01*
G02X481887Y1127427I-1297J0D01*
G01X481856Y1127341D01*
X482663Y1125943D01*
X482753Y1125926D01*
G02X483808Y1124651I-243J-1275D01*
G02X481214I-1297J0D01*
G02X481286Y1125080I1297J3D01*
G01X481317Y1125166D01*
X480510Y1126564D01*
X480420Y1126581D01*
G02X479364Y1127856I242J1275D01*
G37*
G36*
G01X486764D02*
G02X489360I1298J0D01*
G02X489287Y1127427I-1297J0D01*
G01X489256Y1127341D01*
X490063Y1125943D01*
X490153Y1125926D01*
G02X491208Y1124651I-243J-1275D01*
G02X488614I-1297J0D01*
G02X488686Y1125080I1297J3D01*
G01X488717Y1125166D01*
X487910Y1126564D01*
X487820Y1126581D01*
G02X486764Y1127856I242J1275D01*
G37*
G36*
G01X494164D02*
G02X496760I1298J0D01*
G02X496687Y1127427I-1297J0D01*
G01X496656Y1127341D01*
X497463Y1125943D01*
X497553Y1125926D01*
G02X498608Y1124651I-243J-1275D01*
G02X496014I-1297J0D01*
G02X496086Y1125080I1297J3D01*
G01X496117Y1125166D01*
X495310Y1126564D01*
X495220Y1126581D01*
G02X494164Y1127856I242J1275D01*
G37*
G36*
G01X501564D02*
G02X504160I1298J0D01*
G02X504087Y1127427I-1297J0D01*
G01X504056Y1127341D01*
X504863Y1125943D01*
X504953Y1125926D01*
G02X506008Y1124651I-243J-1275D01*
G02X503414I-1297J0D01*
G02X503486Y1125080I1297J3D01*
G01X503517Y1125166D01*
X502710Y1126564D01*
X502620Y1126581D01*
G02X501564Y1127856I242J1275D01*
G37*
G36*
G01X508964D02*
G02X511560I1298J0D01*
G02X511487Y1127427I-1297J0D01*
G01X511456Y1127341D01*
X512263Y1125943D01*
X512353Y1125926D01*
G02X513408Y1124651I-243J-1275D01*
G02X510814I-1297J0D01*
G02X510886Y1125080I1297J3D01*
G01X510917Y1125166D01*
X510110Y1126564D01*
X510020Y1126581D01*
G02X508964Y1127856I242J1275D01*
G37*
G36*
G01X516364D02*
G02X518960I1298J0D01*
G02X518887Y1127427I-1297J0D01*
G01X518856Y1127341D01*
X519663Y1125943D01*
X519753Y1125926D01*
G02X520808Y1124651I-243J-1275D01*
G02X518214I-1297J0D01*
G02X518286Y1125080I1297J3D01*
G01X518317Y1125166D01*
X517510Y1126564D01*
X517420Y1126581D01*
G02X516364Y1127856I242J1275D01*
G37*
G36*
G01X523764D02*
G02X526360I1298J0D01*
G02X526287Y1127427I-1297J0D01*
G01X526256Y1127341D01*
X527063Y1125943D01*
X527153Y1125926D01*
G02X528208Y1124651I-243J-1275D01*
G02X525614I-1297J0D01*
G02X525686Y1125080I1297J3D01*
G01X525717Y1125166D01*
X524910Y1126564D01*
X524820Y1126581D01*
G02X523764Y1127856I242J1275D01*
G37*
G36*
G01X1329706D02*
G02X1332300I1297J0D01*
G02X1331245Y1126581I-1298J0D01*
G01X1331155Y1126564D01*
X1330347Y1125166D01*
X1330378Y1125079D01*
G02X1330450Y1124651I-1225J-426D01*
G02X1327856I-1297J0D01*
G02X1328911Y1125926I1298J0D01*
G01X1329001Y1125943D01*
X1329809Y1127341D01*
X1329778Y1127428D01*
G02X1329706Y1127856I1225J426D01*
G37*
G36*
G01X1337106D02*
G02X1339702I1298J0D01*
G02X1338646Y1126581I-1298J0D01*
G01X1338556Y1126564D01*
X1337748Y1125166D01*
X1337779Y1125079D01*
G02X1337852Y1124651I-1225J-429D01*
G02X1335256I-1298J0D01*
G02X1336312Y1125926I1298J0D01*
G01X1336402Y1125943D01*
X1337210Y1127341D01*
X1337179Y1127428D01*
G02X1337106Y1127856I1225J429D01*
G37*
G36*
G01X1344506D02*
G02X1347102I1298J0D01*
G02X1346046Y1126581I-1298J0D01*
G01X1345956Y1126564D01*
X1345148Y1125165D01*
X1345178Y1125078D01*
G02X1345250Y1124653I-1225J-426D01*
G01Y1124651D01*
G02X1342656I-1297J0D01*
G02X1343712Y1125926I1298J0D01*
G01X1343803Y1125943D01*
X1344610Y1127341D01*
X1344579Y1127428D01*
G02X1344506Y1127856I1225J429D01*
G37*
G36*
G01X1351906D02*
G02X1354502I1298J0D01*
G02X1353446Y1126581I-1298J0D01*
G01X1353356Y1126564D01*
X1352548Y1125165D01*
X1352578Y1125078D01*
G02X1352650Y1124653I-1225J-426D01*
G01Y1124651D01*
G02X1350056I-1297J0D01*
G02X1351112Y1125926I1298J0D01*
G01X1351203Y1125943D01*
X1352010Y1127341D01*
X1351979Y1127428D01*
G02X1351906Y1127856I1225J429D01*
G37*
G36*
G01X1359306D02*
G02X1361902I1298J0D01*
G02X1360846Y1126581I-1298J0D01*
G01X1360756Y1126564D01*
X1359948Y1125165D01*
X1359978Y1125078D01*
G02X1360050Y1124653I-1225J-426D01*
G01Y1124651D01*
G02X1357456I-1297J0D01*
G02X1358512Y1125926I1298J0D01*
G01X1358603Y1125943D01*
X1359410Y1127341D01*
X1359379Y1127428D01*
G02X1359306Y1127856I1225J429D01*
G37*
G36*
G01X1366706D02*
G02X1369302I1298J0D01*
G02X1368246Y1126581I-1298J0D01*
G01X1368156Y1126564D01*
X1367348Y1125165D01*
X1367378Y1125078D01*
G02X1367450Y1124653I-1225J-426D01*
G01Y1124651D01*
G02X1364856I-1297J0D01*
G02X1365912Y1125926I1298J0D01*
G01X1366003Y1125943D01*
X1366810Y1127341D01*
X1366779Y1127428D01*
G02X1366706Y1127856I1225J429D01*
G37*
G36*
G01X1374106D02*
G02X1376702I1298J0D01*
G02X1375646Y1126581I-1298J0D01*
G01X1375556Y1126564D01*
X1374748Y1125165D01*
X1374778Y1125078D01*
G02X1374850Y1124653I-1225J-426D01*
G01Y1124651D01*
G02X1372256I-1297J0D01*
G02X1373312Y1125926I1298J0D01*
G01X1373403Y1125943D01*
X1374210Y1127341D01*
X1374179Y1127428D01*
G02X1374106Y1127856I1225J429D01*
G37*
G36*
G01X1381506D02*
G02X1384102I1298J0D01*
G02X1383046Y1126581I-1298J0D01*
G01X1382956Y1126564D01*
X1382148Y1125165D01*
X1382178Y1125078D01*
G02X1382250Y1124653I-1225J-426D01*
G01Y1124651D01*
G02X1379656I-1297J0D01*
G02X1380712Y1125926I1298J0D01*
G01X1380803Y1125943D01*
X1381610Y1127341D01*
X1381579Y1127428D01*
G02X1381506Y1127856I1225J429D01*
G37*
G36*
G01X1448106D02*
G02X1450702I1298J0D01*
G02X1450629Y1127427I-1297J0D01*
G01X1450598Y1127341D01*
X1451405Y1125943D01*
X1451495Y1125926D01*
G02X1452550Y1124651I-243J-1275D01*
G02X1449956I-1297J0D01*
G02X1450028Y1125080I1297J3D01*
G01X1450059Y1125166D01*
X1449252Y1126564D01*
X1449162Y1126581D01*
G02X1448106Y1127856I242J1275D01*
G37*
G36*
G01X1455506D02*
G02X1458102I1298J0D01*
G02X1458029Y1127427I-1297J0D01*
G01X1457998Y1127341D01*
X1458805Y1125943D01*
X1458895Y1125926D01*
G02X1459950Y1124651I-243J-1275D01*
G02X1457356I-1297J0D01*
G02X1457428Y1125080I1297J3D01*
G01X1457459Y1125166D01*
X1456652Y1126564D01*
X1456562Y1126581D01*
G02X1455506Y1127856I242J1275D01*
G37*
G36*
G01X1462906D02*
G02X1465502I1298J0D01*
G02X1465429Y1127427I-1297J0D01*
G01X1465398Y1127341D01*
X1466205Y1125943D01*
X1466295Y1125926D01*
G02X1467350Y1124651I-243J-1275D01*
G02X1464756I-1297J0D01*
G02X1464828Y1125080I1297J3D01*
G01X1464859Y1125166D01*
X1464052Y1126564D01*
X1463962Y1126581D01*
G02X1462906Y1127856I242J1275D01*
G37*
G36*
G01X1470306D02*
G02X1472902I1298J0D01*
G02X1472829Y1127427I-1297J0D01*
G01X1472798Y1127341D01*
X1473605Y1125943D01*
X1473695Y1125926D01*
G02X1474750Y1124651I-243J-1275D01*
G02X1472156I-1297J0D01*
G02X1472228Y1125080I1297J3D01*
G01X1472259Y1125166D01*
X1471452Y1126564D01*
X1471362Y1126581D01*
G02X1470306Y1127856I242J1275D01*
G37*
G36*
G01X1477706D02*
G02X1480302I1298J0D01*
G02X1480229Y1127427I-1297J0D01*
G01X1480198Y1127341D01*
X1481005Y1125943D01*
X1481095Y1125926D01*
G02X1482150Y1124651I-243J-1275D01*
G02X1479556I-1297J0D01*
G02X1479628Y1125080I1297J3D01*
G01X1479659Y1125166D01*
X1478852Y1126564D01*
X1478762Y1126581D01*
G02X1477706Y1127856I242J1275D01*
G37*
G36*
G01X1485106D02*
G02X1487702I1298J0D01*
G02X1487629Y1127427I-1297J0D01*
G01X1487598Y1127341D01*
X1488405Y1125943D01*
X1488495Y1125926D01*
G02X1489550Y1124651I-243J-1275D01*
G02X1486956I-1297J0D01*
G02X1487028Y1125080I1297J3D01*
G01X1487059Y1125166D01*
X1486252Y1126564D01*
X1486162Y1126581D01*
G02X1485106Y1127856I242J1275D01*
G37*
G36*
G01X1492506D02*
G02X1495102I1298J0D01*
G02X1495029Y1127427I-1297J0D01*
G01X1494998Y1127341D01*
X1495805Y1125943D01*
X1495895Y1125926D01*
G02X1496950Y1124651I-243J-1275D01*
G02X1494356I-1297J0D01*
G02X1494428Y1125080I1297J3D01*
G01X1494459Y1125166D01*
X1493652Y1126564D01*
X1493562Y1126581D01*
G02X1492506Y1127856I242J1275D01*
G37*
G36*
G01X1499906D02*
G02X1502502I1298J0D01*
G02X1502429Y1127427I-1297J0D01*
G01X1502398Y1127341D01*
X1503205Y1125943D01*
X1503295Y1125926D01*
G02X1504350Y1124651I-243J-1275D01*
G02X1501756I-1297J0D01*
G02X1501828Y1125080I1297J3D01*
G01X1501859Y1125166D01*
X1501052Y1126564D01*
X1500962Y1126581D01*
G02X1499906Y1127856I242J1275D01*
G37*
G36*
G01X340614Y1131060D02*
G02X343208I1297J0D01*
G02X342153Y1129785I-1298J0D01*
G01X342063Y1129768D01*
X341256Y1128370D01*
X341286Y1128284D01*
G02X341358Y1127856I-1225J-426D01*
G02X338764I-1297J0D01*
G02X339819Y1129131I1298J0D01*
G01X339909Y1129148D01*
X340716Y1130546D01*
X340686Y1130632D01*
G02X340614Y1131060I1225J426D01*
G37*
G36*
G01X1316756D02*
G02X1319350I1297J0D01*
G02X1318295Y1129785I-1298J0D01*
G01X1318205Y1129768D01*
X1317398Y1128370D01*
X1317428Y1128284D01*
G02X1317500Y1127856I-1225J-426D01*
G02X1314906I-1297J0D01*
G02X1315961Y1129131I1298J0D01*
G01X1316051Y1129148D01*
X1316858Y1130546D01*
X1316828Y1130632D01*
G02X1316756Y1131060I1225J426D01*
G37*
G36*
G01X348014Y1137469D02*
G02X350610I1298J0D01*
G02X350537Y1137040I-1297J0D01*
G01X350506Y1136954D01*
X351313Y1135556D01*
X351403Y1135539D01*
G02X352458Y1134264I-243J-1275D01*
G02X349864I-1297J0D01*
G02X349936Y1134693I1297J3D01*
G01X349967Y1134779D01*
X349160Y1136177D01*
X349070Y1136194D01*
G02X348014Y1137469I242J1275D01*
G37*
G36*
G01X355414D02*
G02X358010I1298J0D01*
G02X357937Y1137040I-1297J0D01*
G01X357906Y1136954D01*
X358713Y1135556D01*
X358803Y1135539D01*
G02X359858Y1134264I-243J-1275D01*
G02X357264I-1297J0D01*
G02X357336Y1134693I1297J3D01*
G01X357367Y1134779D01*
X356560Y1136177D01*
X356470Y1136194D01*
G02X355414Y1137469I242J1275D01*
G37*
G36*
G01X362814D02*
G02X365410I1298J0D01*
G02X365337Y1137041I-1298J1D01*
G01X365306Y1136954D01*
X366114Y1135556D01*
X366204Y1135539D01*
G02X367260Y1134264I-242J-1275D01*
G02X364664I-1298J0D01*
G02X364737Y1134692I1298J-1D01*
G01X364768Y1134779D01*
X363960Y1136177D01*
X363870Y1136194D01*
G02X362814Y1137469I242J1275D01*
G37*
G36*
G01X370214D02*
G02X372810I1298J0D01*
G02X372737Y1137041I-1298J1D01*
G01X372706Y1136954D01*
X373514Y1135556D01*
X373604Y1135539D01*
G02X374660Y1134264I-242J-1275D01*
G02X372064I-1298J0D01*
G02X372137Y1134692I1298J-1D01*
G01X372168Y1134779D01*
X371360Y1136177D01*
X371270Y1136194D01*
G02X370214Y1137469I242J1275D01*
G37*
G36*
G01X377614D02*
G02X380210I1298J0D01*
G02X380137Y1137041I-1298J1D01*
G01X380106Y1136954D01*
X380914Y1135556D01*
X381004Y1135539D01*
G02X382060Y1134264I-242J-1275D01*
G02X379464I-1298J0D01*
G02X379537Y1134692I1298J-1D01*
G01X379568Y1134779D01*
X378760Y1136177D01*
X378670Y1136194D01*
G02X377614Y1137469I242J1275D01*
G37*
G36*
G01X385014D02*
G02X387610I1298J0D01*
G02X387537Y1137041I-1298J1D01*
G01X387506Y1136954D01*
X388314Y1135556D01*
X388404Y1135539D01*
G02X389460Y1134264I-242J-1275D01*
G02X386864I-1298J0D01*
G02X386937Y1134692I1298J-1D01*
G01X386968Y1134779D01*
X386160Y1136177D01*
X386070Y1136194D01*
G02X385014Y1137469I242J1275D01*
G37*
G36*
G01X392414D02*
G02X395010I1298J0D01*
G02X394937Y1137041I-1298J1D01*
G01X394906Y1136954D01*
X395714Y1135556D01*
X395804Y1135539D01*
G02X396860Y1134264I-242J-1275D01*
G02X394264I-1298J0D01*
G02X394337Y1134692I1298J-1D01*
G01X394368Y1134779D01*
X393560Y1136177D01*
X393470Y1136194D01*
G02X392414Y1137469I242J1275D01*
G37*
G36*
G01X399814D02*
G02X402410I1298J0D01*
G02X402337Y1137041I-1298J1D01*
G01X402306Y1136954D01*
X403114Y1135556D01*
X403204Y1135539D01*
G02X404260Y1134264I-242J-1275D01*
G02X401664I-1298J0D01*
G02X401737Y1134692I1298J-1D01*
G01X401768Y1134779D01*
X400960Y1136177D01*
X400870Y1136194D01*
G02X399814Y1137469I242J1275D01*
G37*
G36*
G01X407214D02*
G02X409810I1298J0D01*
G02X409737Y1137041I-1298J1D01*
G01X409706Y1136954D01*
X410514Y1135556D01*
X410604Y1135539D01*
G02X411660Y1134264I-242J-1275D01*
G02X409064I-1298J0D01*
G02X409137Y1134692I1298J-1D01*
G01X409168Y1134779D01*
X408360Y1136177D01*
X408270Y1136194D01*
G02X407214Y1137469I242J1275D01*
G37*
G36*
G01X477514D02*
G02X480110I1298J0D01*
G02X479054Y1136194I-1298J0D01*
G01X478964Y1136177D01*
X478156Y1134779D01*
X478187Y1134692D01*
G02X478260Y1134264I-1225J-429D01*
G02X475664I-1298J0D01*
G02X476720Y1135539I1298J0D01*
G01X476810Y1135556D01*
X477618Y1136954D01*
X477587Y1137041D01*
G02X477514Y1137469I1225J429D01*
G37*
G36*
G01X484914D02*
G02X487510I1298J0D01*
G02X486454Y1136194I-1298J0D01*
G01X486364Y1136177D01*
X485557Y1134779D01*
X485587Y1134692D01*
G02X485660Y1134264I-1225J-429D01*
G02X483064I-1298J0D01*
G02X484121Y1135539I1297J0D01*
G01X484211Y1135556D01*
X485018Y1136954D01*
X484987Y1137041D01*
G02X484914Y1137469I1225J429D01*
G37*
G36*
G01X492314D02*
G02X494910I1298J0D01*
G02X493854Y1136194I-1298J0D01*
G01X493764Y1136177D01*
X492957Y1134779D01*
X492987Y1134692D01*
G02X493060Y1134264I-1225J-429D01*
G02X490464I-1298J0D01*
G02X491521Y1135539I1297J0D01*
G01X491611Y1135556D01*
X492418Y1136954D01*
X492387Y1137041D01*
G02X492314Y1137469I1225J429D01*
G37*
G36*
G01X499714D02*
G02X502310I1298J0D01*
G02X501254Y1136194I-1298J0D01*
G01X501164Y1136177D01*
X500357Y1134779D01*
X500387Y1134692D01*
G02X500460Y1134264I-1225J-429D01*
G02X497864I-1298J0D01*
G02X498921Y1135539I1297J0D01*
G01X499011Y1135556D01*
X499818Y1136954D01*
X499787Y1137041D01*
G02X499714Y1137469I1225J429D01*
G37*
G36*
G01X507114D02*
G02X509710I1298J0D01*
G02X508654Y1136194I-1298J0D01*
G01X508564Y1136177D01*
X507757Y1134779D01*
X507787Y1134692D01*
G02X507860Y1134264I-1225J-429D01*
G02X505264I-1298J0D01*
G02X506321Y1135539I1297J0D01*
G01X506411Y1135556D01*
X507218Y1136954D01*
X507187Y1137041D01*
G02X507114Y1137469I1225J429D01*
G37*
G36*
G01X514514D02*
G02X517110I1298J0D01*
G02X516054Y1136194I-1298J0D01*
G01X515964Y1136177D01*
X515157Y1134779D01*
X515187Y1134692D01*
G02X515260Y1134264I-1225J-429D01*
G02X512664I-1298J0D01*
G02X513721Y1135539I1297J0D01*
G01X513811Y1135556D01*
X514618Y1136954D01*
X514587Y1137041D01*
G02X514514Y1137469I1225J429D01*
G37*
G36*
G01X521914D02*
G02X524510I1298J0D01*
G02X523454Y1136194I-1298J0D01*
G01X523364Y1136177D01*
X522557Y1134779D01*
X522587Y1134692D01*
G02X522660Y1134264I-1225J-429D01*
G02X520064I-1298J0D01*
G02X521121Y1135539I1297J0D01*
G01X521211Y1135556D01*
X522018Y1136954D01*
X521987Y1137041D01*
G02X521914Y1137469I1225J429D01*
G37*
G36*
G01X533014D02*
G02X535610I1298J0D01*
G02X534554Y1136194I-1298J0D01*
G01X534464Y1136177D01*
X533656Y1134779D01*
X533687Y1134692D01*
G02X533760Y1134264I-1225J-429D01*
G02X531164I-1298J0D01*
G02X532220Y1135539I1298J0D01*
G01X532310Y1135556D01*
X533118Y1136954D01*
X533087Y1137041D01*
G02X533014Y1137469I1225J429D01*
G37*
G36*
G01X1324156D02*
G02X1326752I1298J0D01*
G02X1326679Y1137040I-1297J0D01*
G01X1326648Y1136954D01*
X1327455Y1135556D01*
X1327545Y1135539D01*
G02X1328600Y1134264I-243J-1275D01*
G02X1326006I-1297J0D01*
G02X1326078Y1134693I1297J3D01*
G01X1326109Y1134779D01*
X1325302Y1136177D01*
X1325212Y1136194D01*
G02X1324156Y1137469I242J1275D01*
G37*
G36*
G01X1331556D02*
G02X1334152I1298J0D01*
G02X1334079Y1137040I-1297J0D01*
G01X1334048Y1136954D01*
X1334855Y1135556D01*
X1334945Y1135539D01*
G02X1336000Y1134264I-243J-1275D01*
G02X1333406I-1297J0D01*
G02X1333478Y1134693I1297J3D01*
G01X1333509Y1134779D01*
X1332702Y1136177D01*
X1332612Y1136194D01*
G02X1331556Y1137469I242J1275D01*
G37*
G36*
G01X1338956D02*
G02X1341552I1298J0D01*
G02X1341479Y1137041I-1298J1D01*
G01X1341448Y1136954D01*
X1342256Y1135556D01*
X1342346Y1135539D01*
G02X1343402Y1134264I-242J-1275D01*
G02X1340806I-1298J0D01*
G02X1340879Y1134692I1298J-1D01*
G01X1340910Y1134779D01*
X1340102Y1136177D01*
X1340012Y1136194D01*
G02X1338956Y1137469I242J1275D01*
G37*
G36*
G01X1346356D02*
G02X1348952I1298J0D01*
G02X1348879Y1137041I-1298J1D01*
G01X1348848Y1136954D01*
X1349656Y1135556D01*
X1349746Y1135539D01*
G02X1350802Y1134264I-242J-1275D01*
G02X1348206I-1298J0D01*
G02X1348279Y1134692I1298J-1D01*
G01X1348310Y1134779D01*
X1347502Y1136177D01*
X1347412Y1136194D01*
G02X1346356Y1137469I242J1275D01*
G37*
G36*
G01X1353756D02*
G02X1356352I1298J0D01*
G02X1356279Y1137041I-1298J1D01*
G01X1356248Y1136954D01*
X1357056Y1135556D01*
X1357146Y1135539D01*
G02X1358202Y1134264I-242J-1275D01*
G02X1355606I-1298J0D01*
G02X1355679Y1134692I1298J-1D01*
G01X1355710Y1134779D01*
X1354902Y1136177D01*
X1354812Y1136194D01*
G02X1353756Y1137469I242J1275D01*
G37*
G36*
G01X1361156D02*
G02X1363752I1298J0D01*
G02X1363679Y1137041I-1298J1D01*
G01X1363648Y1136954D01*
X1364456Y1135556D01*
X1364546Y1135539D01*
G02X1365602Y1134264I-242J-1275D01*
G02X1363006I-1298J0D01*
G02X1363079Y1134692I1298J-1D01*
G01X1363110Y1134779D01*
X1362302Y1136177D01*
X1362212Y1136194D01*
G02X1361156Y1137469I242J1275D01*
G37*
G36*
G01X1368556D02*
G02X1371152I1298J0D01*
G02X1371079Y1137041I-1298J1D01*
G01X1371048Y1136954D01*
X1371856Y1135556D01*
X1371946Y1135539D01*
G02X1373002Y1134264I-242J-1275D01*
G02X1370406I-1298J0D01*
G02X1370479Y1134692I1298J-1D01*
G01X1370510Y1134779D01*
X1369702Y1136177D01*
X1369612Y1136194D01*
G02X1368556Y1137469I242J1275D01*
G37*
G36*
G01X1375956D02*
G02X1378552I1298J0D01*
G02X1378479Y1137041I-1298J1D01*
G01X1378448Y1136954D01*
X1379256Y1135556D01*
X1379346Y1135539D01*
G02X1380402Y1134264I-242J-1275D01*
G02X1377806I-1298J0D01*
G02X1377879Y1134692I1298J-1D01*
G01X1377910Y1134779D01*
X1377102Y1136177D01*
X1377012Y1136194D01*
G02X1375956Y1137469I242J1275D01*
G37*
G36*
G01X1383356D02*
G02X1385952I1298J0D01*
G02X1385879Y1137041I-1298J1D01*
G01X1385848Y1136954D01*
X1386656Y1135556D01*
X1386746Y1135539D01*
G02X1387802Y1134264I-242J-1275D01*
G02X1385206I-1298J0D01*
G02X1385279Y1134692I1298J-1D01*
G01X1385310Y1134779D01*
X1384502Y1136177D01*
X1384412Y1136194D01*
G02X1383356Y1137469I242J1275D01*
G37*
G36*
G01X1453656D02*
G02X1456252I1298J0D01*
G02X1455196Y1136194I-1298J0D01*
G01X1455106Y1136177D01*
X1454298Y1134779D01*
X1454329Y1134692D01*
G02X1454402Y1134264I-1225J-429D01*
G02X1451806I-1298J0D01*
G02X1452862Y1135539I1298J0D01*
G01X1452952Y1135556D01*
X1453760Y1136954D01*
X1453729Y1137041D01*
G02X1453656Y1137469I1225J429D01*
G37*
G36*
G01X1461056D02*
G02X1463652I1298J0D01*
G02X1462596Y1136194I-1298J0D01*
G01X1462506Y1136177D01*
X1461699Y1134779D01*
X1461729Y1134692D01*
G02X1461802Y1134264I-1225J-429D01*
G02X1459206I-1298J0D01*
G02X1460263Y1135539I1297J0D01*
G01X1460353Y1135556D01*
X1461160Y1136954D01*
X1461129Y1137041D01*
G02X1461056Y1137469I1225J429D01*
G37*
G36*
G01X1468456D02*
G02X1471052I1298J0D01*
G02X1469996Y1136194I-1298J0D01*
G01X1469906Y1136177D01*
X1469099Y1134779D01*
X1469129Y1134692D01*
G02X1469202Y1134264I-1225J-429D01*
G02X1466606I-1298J0D01*
G02X1467663Y1135539I1297J0D01*
G01X1467753Y1135556D01*
X1468560Y1136954D01*
X1468529Y1137041D01*
G02X1468456Y1137469I1225J429D01*
G37*
G36*
G01X1475856D02*
G02X1478452I1298J0D01*
G02X1477396Y1136194I-1298J0D01*
G01X1477306Y1136177D01*
X1476499Y1134779D01*
X1476529Y1134692D01*
G02X1476602Y1134264I-1225J-429D01*
G02X1474006I-1298J0D01*
G02X1475063Y1135539I1297J0D01*
G01X1475153Y1135556D01*
X1475960Y1136954D01*
X1475929Y1137041D01*
G02X1475856Y1137469I1225J429D01*
G37*
G36*
G01X1483256D02*
G02X1485852I1298J0D01*
G02X1484796Y1136194I-1298J0D01*
G01X1484706Y1136177D01*
X1483899Y1134779D01*
X1483929Y1134692D01*
G02X1484002Y1134264I-1225J-429D01*
G02X1481406I-1298J0D01*
G02X1482463Y1135539I1297J0D01*
G01X1482553Y1135556D01*
X1483360Y1136954D01*
X1483329Y1137041D01*
G02X1483256Y1137469I1225J429D01*
G37*
G36*
G01X1490656D02*
G02X1493252I1298J0D01*
G02X1492196Y1136194I-1298J0D01*
G01X1492106Y1136177D01*
X1491299Y1134779D01*
X1491329Y1134692D01*
G02X1491402Y1134264I-1225J-429D01*
G02X1488806I-1298J0D01*
G02X1489863Y1135539I1297J0D01*
G01X1489953Y1135556D01*
X1490760Y1136954D01*
X1490729Y1137041D01*
G02X1490656Y1137469I1225J429D01*
G37*
G36*
G01X1498056D02*
G02X1500652I1298J0D01*
G02X1499596Y1136194I-1298J0D01*
G01X1499506Y1136177D01*
X1498699Y1134779D01*
X1498729Y1134692D01*
G02X1498802Y1134264I-1225J-429D01*
G02X1496206I-1298J0D01*
G02X1497263Y1135539I1297J0D01*
G01X1497353Y1135556D01*
X1498160Y1136954D01*
X1498129Y1137041D01*
G02X1498056Y1137469I1225J429D01*
G37*
G36*
G01X1509156D02*
G02X1511752I1298J0D01*
G02X1510696Y1136194I-1298J0D01*
G01X1510606Y1136177D01*
X1509798Y1134779D01*
X1509829Y1134692D01*
G02X1509902Y1134264I-1225J-429D01*
G02X1507306I-1298J0D01*
G02X1508362Y1135539I1298J0D01*
G01X1508452Y1135556D01*
X1509260Y1136954D01*
X1509229Y1137041D01*
G02X1509156Y1137469I1225J429D01*
G37*
G36*
G01X360964Y1140973D02*
G02X363558I1297J0D01*
G02X362496Y1139697I-1298J0D01*
G01X362401Y1139679D01*
X361559Y1138084D01*
X361598Y1137995D01*
G02X361710Y1137469I-1186J-527D01*
G02X359114I-1298J0D01*
G02X360177Y1138745I1297J0D01*
G01X360272Y1138763D01*
X361114Y1140358D01*
X361075Y1140447D01*
G02X360964Y1140971I1186J525D01*
G01Y1140973D01*
G37*
G36*
G01X368364D02*
G02X370958I1297J0D01*
G02X369896Y1139697I-1298J0D01*
G01X369801Y1139679D01*
X368959Y1138084D01*
X368998Y1137995D01*
G02X369110Y1137469I-1186J-527D01*
G02X366514I-1298J0D01*
G02X367577Y1138745I1297J0D01*
G01X367672Y1138763D01*
X368514Y1140358D01*
X368475Y1140447D01*
G02X368364Y1140971I1186J525D01*
G01Y1140973D01*
G37*
G36*
G01X375764D02*
G02X378358I1297J0D01*
G02X377296Y1139697I-1298J0D01*
G01X377201Y1139679D01*
X376359Y1138084D01*
X376398Y1137995D01*
G02X376510Y1137469I-1186J-527D01*
G02X373914I-1298J0D01*
G02X374977Y1138745I1297J0D01*
G01X375072Y1138763D01*
X375914Y1140358D01*
X375875Y1140447D01*
G02X375764Y1140971I1186J525D01*
G01Y1140973D01*
G37*
G36*
G01X383164D02*
G02X385758I1297J0D01*
G02X384696Y1139697I-1298J0D01*
G01X384601Y1139679D01*
X383759Y1138084D01*
X383798Y1137995D01*
G02X383910Y1137469I-1186J-527D01*
G02X381314I-1298J0D01*
G02X382377Y1138745I1297J0D01*
G01X382472Y1138763D01*
X383314Y1140358D01*
X383275Y1140447D01*
G02X383164Y1140971I1186J525D01*
G01Y1140973D01*
G37*
G36*
G01X390564D02*
G02X393158I1297J0D01*
G02X392096Y1139697I-1298J0D01*
G01X392001Y1139679D01*
X391159Y1138084D01*
X391198Y1137995D01*
G02X391310Y1137469I-1186J-527D01*
G02X388714I-1298J0D01*
G02X389777Y1138745I1297J0D01*
G01X389872Y1138763D01*
X390714Y1140358D01*
X390675Y1140447D01*
G02X390564Y1140971I1186J525D01*
G01Y1140973D01*
G37*
G36*
G01X397964D02*
G02X400558I1297J0D01*
G02X399496Y1139697I-1298J0D01*
G01X399401Y1139679D01*
X398559Y1138084D01*
X398598Y1137995D01*
G02X398710Y1137469I-1186J-527D01*
G02X396114I-1298J0D01*
G02X397177Y1138745I1297J0D01*
G01X397272Y1138763D01*
X398114Y1140358D01*
X398075Y1140447D01*
G02X397964Y1140971I1186J525D01*
G01Y1140973D01*
G37*
G36*
G01X405364D02*
G02X407958I1297J0D01*
G02X406896Y1139697I-1298J0D01*
G01X406801Y1139679D01*
X405959Y1138084D01*
X405998Y1137995D01*
G02X406110Y1137469I-1186J-527D01*
G02X403514I-1298J0D01*
G02X404577Y1138745I1297J0D01*
G01X404672Y1138763D01*
X405514Y1140358D01*
X405475Y1140447D01*
G02X405364Y1140971I1186J525D01*
G01Y1140973D01*
G37*
G36*
G01X471964D02*
G02X474558I1297J0D01*
G02X474447Y1140448I-1297J0D01*
G01X474408Y1140359D01*
X475252Y1138763D01*
X475347Y1138745D01*
G02X476410Y1137469I-234J-1276D01*
G02X473814I-1298J0D01*
G02X473926Y1137994I1297J-2D01*
G01X473965Y1138083D01*
X473121Y1139679D01*
X473026Y1139697D01*
G02X471964Y1140973I236J1276D01*
G37*
G36*
G01X479364D02*
G02X481958I1297J0D01*
G02X481847Y1140448I-1297J0D01*
G01X481808Y1140359D01*
X482652Y1138763D01*
X482747Y1138745D01*
G02X483810Y1137469I-234J-1276D01*
G02X481214I-1298J0D01*
G02X481326Y1137994I1297J-2D01*
G01X481365Y1138083D01*
X480521Y1139679D01*
X480426Y1139697D01*
G02X479364Y1140973I236J1276D01*
G37*
G36*
G01X486764D02*
G02X489358I1297J0D01*
G02X489247Y1140448I-1297J0D01*
G01X489208Y1140359D01*
X490052Y1138763D01*
X490147Y1138745D01*
G02X491210Y1137469I-234J-1276D01*
G02X488614I-1298J0D01*
G02X488726Y1137994I1297J-2D01*
G01X488765Y1138083D01*
X487921Y1139679D01*
X487826Y1139697D01*
G02X486764Y1140973I236J1276D01*
G37*
G36*
G01X494164D02*
G02X496758I1297J0D01*
G02X496647Y1140448I-1297J0D01*
G01X496608Y1140359D01*
X497452Y1138763D01*
X497547Y1138745D01*
G02X498610Y1137469I-234J-1276D01*
G02X496014I-1298J0D01*
G02X496126Y1137994I1297J-2D01*
G01X496165Y1138083D01*
X495321Y1139679D01*
X495226Y1139697D01*
G02X494164Y1140973I236J1276D01*
G37*
G36*
G01X501564D02*
G02X504158I1297J0D01*
G02X504047Y1140448I-1297J0D01*
G01X504008Y1140359D01*
X504852Y1138763D01*
X504947Y1138745D01*
G02X506010Y1137469I-234J-1276D01*
G02X503414I-1298J0D01*
G02X503526Y1137994I1297J-2D01*
G01X503565Y1138083D01*
X502721Y1139679D01*
X502626Y1139697D01*
G02X501564Y1140973I236J1276D01*
G37*
G36*
G01X508964D02*
G02X511558I1297J0D01*
G02X511447Y1140448I-1297J0D01*
G01X511408Y1140359D01*
X512252Y1138763D01*
X512347Y1138745D01*
G02X513410Y1137469I-234J-1276D01*
G02X510814I-1298J0D01*
G02X510926Y1137994I1297J-2D01*
G01X510965Y1138083D01*
X510121Y1139679D01*
X510026Y1139697D01*
G02X508964Y1140973I236J1276D01*
G37*
G36*
G01X516364D02*
G02X518958I1297J0D01*
G02X518847Y1140448I-1297J0D01*
G01X518808Y1140359D01*
X519652Y1138763D01*
X519747Y1138745D01*
G02X520810Y1137469I-234J-1276D01*
G02X518214I-1298J0D01*
G02X518326Y1137994I1297J-2D01*
G01X518365Y1138083D01*
X517521Y1139679D01*
X517426Y1139697D01*
G02X516364Y1140973I236J1276D01*
G37*
G36*
G01X523764D02*
G02X526358I1297J0D01*
G02X526247Y1140448I-1297J0D01*
G01X526208Y1140359D01*
X527052Y1138763D01*
X527147Y1138745D01*
G02X528210Y1137469I-234J-1276D01*
G02X525614I-1298J0D01*
G02X525726Y1137994I1297J-2D01*
G01X525765Y1138083D01*
X524921Y1139679D01*
X524826Y1139697D01*
G02X523764Y1140973I236J1276D01*
G37*
G36*
G01X1337106D02*
G02X1339700I1297J0D01*
G02X1338638Y1139697I-1298J0D01*
G01X1338543Y1139679D01*
X1337701Y1138084D01*
X1337740Y1137995D01*
G02X1337852Y1137469I-1186J-527D01*
G02X1335256I-1298J0D01*
G02X1336319Y1138745I1297J0D01*
G01X1336414Y1138763D01*
X1337256Y1140358D01*
X1337217Y1140447D01*
G02X1337106Y1140971I1186J525D01*
G01Y1140973D01*
G37*
G36*
G01X1344506D02*
G02X1347100I1297J0D01*
G02X1346038Y1139697I-1298J0D01*
G01X1345943Y1139679D01*
X1345101Y1138084D01*
X1345140Y1137995D01*
G02X1345252Y1137469I-1186J-527D01*
G02X1342656I-1298J0D01*
G02X1343719Y1138745I1297J0D01*
G01X1343814Y1138763D01*
X1344656Y1140358D01*
X1344617Y1140447D01*
G02X1344506Y1140971I1186J525D01*
G01Y1140973D01*
G37*
G36*
G01X1351906D02*
G02X1354500I1297J0D01*
G02X1353438Y1139697I-1298J0D01*
G01X1353343Y1139679D01*
X1352501Y1138084D01*
X1352540Y1137995D01*
G02X1352652Y1137469I-1186J-527D01*
G02X1350056I-1298J0D01*
G02X1351119Y1138745I1297J0D01*
G01X1351214Y1138763D01*
X1352056Y1140358D01*
X1352017Y1140447D01*
G02X1351906Y1140971I1186J525D01*
G01Y1140973D01*
G37*
G36*
G01X1359306D02*
G02X1361900I1297J0D01*
G02X1360838Y1139697I-1298J0D01*
G01X1360743Y1139679D01*
X1359901Y1138084D01*
X1359940Y1137995D01*
G02X1360052Y1137469I-1186J-527D01*
G02X1357456I-1298J0D01*
G02X1358519Y1138745I1297J0D01*
G01X1358614Y1138763D01*
X1359456Y1140358D01*
X1359417Y1140447D01*
G02X1359306Y1140971I1186J525D01*
G01Y1140973D01*
G37*
G36*
G01X1366706D02*
G02X1369300I1297J0D01*
G02X1368238Y1139697I-1298J0D01*
G01X1368143Y1139679D01*
X1367301Y1138084D01*
X1367340Y1137995D01*
G02X1367452Y1137469I-1186J-527D01*
G02X1364856I-1298J0D01*
G02X1365919Y1138745I1297J0D01*
G01X1366014Y1138763D01*
X1366856Y1140358D01*
X1366817Y1140447D01*
G02X1366706Y1140971I1186J525D01*
G01Y1140973D01*
G37*
G36*
G01X1374106D02*
G02X1376700I1297J0D01*
G02X1375638Y1139697I-1298J0D01*
G01X1375543Y1139679D01*
X1374701Y1138084D01*
X1374740Y1137995D01*
G02X1374852Y1137469I-1186J-527D01*
G02X1372256I-1298J0D01*
G02X1373319Y1138745I1297J0D01*
G01X1373414Y1138763D01*
X1374256Y1140358D01*
X1374217Y1140447D01*
G02X1374106Y1140971I1186J525D01*
G01Y1140973D01*
G37*
G36*
G01X1381506D02*
G02X1384100I1297J0D01*
G02X1383038Y1139697I-1298J0D01*
G01X1382943Y1139679D01*
X1382101Y1138084D01*
X1382140Y1137995D01*
G02X1382252Y1137469I-1186J-527D01*
G02X1379656I-1298J0D01*
G02X1380719Y1138745I1297J0D01*
G01X1380814Y1138763D01*
X1381656Y1140358D01*
X1381617Y1140447D01*
G02X1381506Y1140971I1186J525D01*
G01Y1140973D01*
G37*
G36*
G01X1448106D02*
G02X1450700I1297J0D01*
G02X1450589Y1140448I-1297J0D01*
G01X1450550Y1140359D01*
X1451394Y1138763D01*
X1451489Y1138745D01*
G02X1452552Y1137469I-234J-1276D01*
G02X1449956I-1298J0D01*
G02X1450068Y1137994I1297J-2D01*
G01X1450107Y1138083D01*
X1449263Y1139679D01*
X1449168Y1139697D01*
G02X1448106Y1140973I236J1276D01*
G37*
G36*
G01X1455506D02*
G02X1458100I1297J0D01*
G02X1457989Y1140448I-1297J0D01*
G01X1457950Y1140359D01*
X1458794Y1138763D01*
X1458889Y1138745D01*
G02X1459952Y1137469I-234J-1276D01*
G02X1457356I-1298J0D01*
G02X1457468Y1137994I1297J-2D01*
G01X1457507Y1138083D01*
X1456663Y1139679D01*
X1456568Y1139697D01*
G02X1455506Y1140973I236J1276D01*
G37*
G36*
G01X1462906D02*
G02X1465500I1297J0D01*
G02X1465389Y1140448I-1297J0D01*
G01X1465350Y1140359D01*
X1466194Y1138763D01*
X1466289Y1138745D01*
G02X1467352Y1137469I-234J-1276D01*
G02X1464756I-1298J0D01*
G02X1464868Y1137994I1297J-2D01*
G01X1464907Y1138083D01*
X1464063Y1139679D01*
X1463968Y1139697D01*
G02X1462906Y1140973I236J1276D01*
G37*
G36*
G01X1470306D02*
G02X1472900I1297J0D01*
G02X1472789Y1140448I-1297J0D01*
G01X1472750Y1140359D01*
X1473594Y1138763D01*
X1473689Y1138745D01*
G02X1474752Y1137469I-234J-1276D01*
G02X1472156I-1298J0D01*
G02X1472268Y1137994I1297J-2D01*
G01X1472307Y1138083D01*
X1471463Y1139679D01*
X1471368Y1139697D01*
G02X1470306Y1140973I236J1276D01*
G37*
G36*
G01X1477706D02*
G02X1480300I1297J0D01*
G02X1480189Y1140448I-1297J0D01*
G01X1480150Y1140359D01*
X1480994Y1138763D01*
X1481089Y1138745D01*
G02X1482152Y1137469I-234J-1276D01*
G02X1479556I-1298J0D01*
G02X1479668Y1137994I1297J-2D01*
G01X1479707Y1138083D01*
X1478863Y1139679D01*
X1478768Y1139697D01*
G02X1477706Y1140973I236J1276D01*
G37*
G36*
G01X1485106D02*
G02X1487700I1297J0D01*
G02X1487589Y1140448I-1297J0D01*
G01X1487550Y1140359D01*
X1488394Y1138763D01*
X1488489Y1138745D01*
G02X1489552Y1137469I-234J-1276D01*
G02X1486956I-1298J0D01*
G02X1487068Y1137994I1297J-2D01*
G01X1487107Y1138083D01*
X1486263Y1139679D01*
X1486168Y1139697D01*
G02X1485106Y1140973I236J1276D01*
G37*
G36*
G01X1492506D02*
G02X1495100I1297J0D01*
G02X1494989Y1140448I-1297J0D01*
G01X1494950Y1140359D01*
X1495794Y1138763D01*
X1495889Y1138745D01*
G02X1496952Y1137469I-234J-1276D01*
G02X1494356I-1298J0D01*
G02X1494468Y1137994I1297J-2D01*
G01X1494507Y1138083D01*
X1493663Y1139679D01*
X1493568Y1139697D01*
G02X1492506Y1140973I236J1276D01*
G37*
G36*
G01X1499906D02*
G02X1502500I1297J0D01*
G02X1502389Y1140448I-1297J0D01*
G01X1502350Y1140359D01*
X1503194Y1138763D01*
X1503289Y1138745D01*
G02X1504352Y1137469I-234J-1276D01*
G02X1501756I-1298J0D01*
G02X1501868Y1137994I1297J-2D01*
G01X1501907Y1138083D01*
X1501063Y1139679D01*
X1500968Y1139697D01*
G02X1499906Y1140973I236J1276D01*
G37*
G36*
G01X1143020Y1540382D02*
G03X1143411Y1540758I-8J400D01*
G02X1145410Y1542642I1999J-119D01*
G02X1147412Y1540640I0J-2002D01*
G02X1145450Y1538638I-2002J0D01*
G03X1145059Y1538262I8J-400D01*
G02X1143060Y1536378I-1999J119D01*
G02X1141058Y1538380I0J2002D01*
G02X1143020Y1540382I2002J0D01*
G37*
G36*
G01X1162980Y1551449D02*
G03X1163635I328J229D01*
G02X1166917I1641J-1147D01*
G03X1167572I327J229D01*
G02X1169213Y1552304I1641J-1147D01*
G02Y1548298I0J-2003D01*
G02X1167572Y1549153I0J2002D01*
G03X1166917I-328J-229D01*
G02X1163635I-1641J1147D01*
G03X1162980I-327J-229D01*
G02X1159698I-1641J1147D01*
G03X1159043I-328J-229D01*
G02X1155761I-1641J1147D01*
G03X1155106I-328J-229D01*
G02X1151824I-1641J1147D01*
G03X1151169I-328J-229D01*
G02X1149528Y1548298I-1641J1147D01*
G02Y1552304I0J2003D01*
G02X1151169Y1551449I0J-2002D01*
G03X1151824I327J229D01*
G02X1155106I1641J-1147D01*
G03X1155761I328J229D01*
G02X1159043I1641J-1147D01*
G03X1159698I327J229D01*
G02X1162980I1641J-1147D01*
G37*
G36*
G01X1139652Y1550301D02*
Y1550302D01*
G02X1140157Y1551631I2002J0D01*
G02X1139688Y1552918I1533J1288D01*
G01Y1552920D01*
G02X1143692I2002J0D01*
G01Y1552919D01*
G02X1143187Y1551590I-2002J0D01*
G02X1143656Y1550303I-1533J-1288D01*
G01Y1550301D01*
G02X1139652I-2002J0D01*
G37*
G36*
G01X1101405Y1550386D02*
G03X1101083Y1550900I-382J119D01*
G02X1098098Y1554364I517J3464D01*
G02X1105102I3502J0D01*
G02X1104945Y1553324I-3502J-3D01*
G03X1105267Y1552810I382J-119D01*
G02X1108252Y1549346I-517J-3464D01*
G02X1101248I-3502J0D01*
G02X1101405Y1550386I3502J3D01*
G37*
G36*
G01X1143823Y1573272D02*
G03X1143551I-136J-147D01*
G02X1142188Y1572736I-1363J1466D01*
G01X1142187D01*
G02Y1576740I0J2002D01*
G01X1142188D01*
G02X1143551Y1576204I0J-2002D01*
G03X1143823I136J147D01*
G02X1145186Y1576740I1363J-1466D01*
G01X1145187D01*
G02Y1572736I0J-2002D01*
G01X1145186D01*
G02X1143823Y1573272I0J2002D01*
G37*
G36*
G01X1153823D02*
G03X1153551I-136J-147D01*
G02X1152188Y1572736I-1363J1466D01*
G01X1152187D01*
G02Y1576740I0J2002D01*
G01X1152188D01*
G02X1153551Y1576204I0J-2002D01*
G03X1153823I136J147D01*
G02X1155186Y1576740I1363J-1466D01*
G01X1155187D01*
G02Y1572736I0J-2002D01*
G01X1155186D01*
G02X1153823Y1573272I0J2002D01*
G37*
G36*
G01X1163231D02*
G03X1162959I-136J-147D01*
G02X1161596Y1572736I-1363J1466D01*
G01X1161595D01*
G02Y1576740I0J2002D01*
G01X1161596D01*
G02X1162959Y1576204I0J-2002D01*
G03X1163231I136J147D01*
G02X1164594Y1576740I1363J-1466D01*
G01X1164595D01*
G02Y1572736I0J-2002D01*
G01X1164594D01*
G02X1163231Y1573272I0J2002D01*
G37*
G36*
G01X1173231D02*
G03X1172959I-136J-147D01*
G02X1171596Y1572736I-1363J1466D01*
G01X1171595D01*
G02Y1576740I0J2002D01*
G01X1171596D01*
G02X1172959Y1576204I0J-2002D01*
G03X1173231I136J147D01*
G02X1174594Y1576740I1363J-1466D01*
G01X1174595D01*
G02Y1572736I0J-2002D01*
G01X1174594D01*
G02X1173231Y1573272I0J2002D01*
G37*
G36*
G01X1133823Y1581272D02*
G03X1133551I-136J-147D01*
G02X1132188Y1580736I-1363J1466D01*
G01X1132187D01*
G02Y1584740I0J2002D01*
G01X1132188D01*
G02X1133551Y1584204I0J-2002D01*
G03X1133823I136J147D01*
G02X1135186Y1584740I1363J-1466D01*
G01X1135187D01*
G02Y1580736I0J-2002D01*
G01X1135186D01*
G02X1133823Y1581272I0J2002D01*
G37*
G36*
G01X1143823D02*
G03X1143551I-136J-147D01*
G02X1142188Y1580736I-1363J1466D01*
G01X1142187D01*
G02Y1584740I0J2002D01*
G01X1142188D01*
G02X1143551Y1584204I0J-2002D01*
G03X1143823I136J147D01*
G02X1145186Y1584740I1363J-1466D01*
G01X1145187D01*
G02Y1580736I0J-2002D01*
G01X1145186D01*
G02X1143823Y1581272I0J2002D01*
G37*
G36*
G01X1153823D02*
G03X1153551I-136J-147D01*
G02X1152188Y1580736I-1363J1466D01*
G01X1152187D01*
G02Y1584740I0J2002D01*
G01X1152188D01*
G02X1153551Y1584204I0J-2002D01*
G03X1153823I136J147D01*
G02X1155186Y1584740I1363J-1466D01*
G01X1155187D01*
G02Y1580736I0J-2002D01*
G01X1155186D01*
G02X1153823Y1581272I0J2002D01*
G37*
G36*
G01X1163231D02*
G03X1162959I-136J-147D01*
G02X1161596Y1580736I-1363J1466D01*
G01X1161595D01*
G02Y1584740I0J2002D01*
G01X1161596D01*
G02X1162959Y1584204I0J-2002D01*
G03X1163231I136J147D01*
G02X1164594Y1584740I1363J-1466D01*
G01X1164595D01*
G02Y1580736I0J-2002D01*
G01X1164594D01*
G02X1163231Y1581272I0J2002D01*
G37*
G36*
G01X1173231D02*
G03X1172959I-136J-147D01*
G02X1171596Y1580736I-1363J1466D01*
G01X1171595D01*
G02Y1584740I0J2002D01*
G01X1171596D01*
G02X1172959Y1584204I0J-2002D01*
G03X1173231I136J147D01*
G02X1174594Y1584740I1363J-1466D01*
G01X1174595D01*
G02Y1580736I0J-2002D01*
G01X1174594D01*
G02X1173231Y1581272I0J2002D01*
G37*
G36*
G01X1133823Y1589272D02*
G03X1133551I-136J-147D01*
G02X1132188Y1588736I-1363J1466D01*
G01X1132187D01*
G02Y1592740I0J2002D01*
G01X1132188D01*
G02X1133551Y1592204I0J-2002D01*
G03X1133823I136J147D01*
G02X1135186Y1592740I1363J-1466D01*
G01X1135187D01*
G02Y1588736I0J-2002D01*
G01X1135186D01*
G02X1133823Y1589272I0J2002D01*
G37*
G36*
G01X1143823D02*
G03X1143551I-136J-147D01*
G02X1142188Y1588736I-1363J1466D01*
G01X1142187D01*
G02Y1592740I0J2002D01*
G01X1142188D01*
G02X1143551Y1592204I0J-2002D01*
G03X1143823I136J147D01*
G02X1145186Y1592740I1363J-1466D01*
G01X1145187D01*
G02Y1588736I0J-2002D01*
G01X1145186D01*
G02X1143823Y1589272I0J2002D01*
G37*
G36*
G01X1153823D02*
G03X1153551I-136J-147D01*
G02X1152188Y1588736I-1363J1466D01*
G01X1152187D01*
G02Y1592740I0J2002D01*
G01X1152188D01*
G02X1153551Y1592204I0J-2002D01*
G03X1153823I136J147D01*
G02X1155186Y1592740I1363J-1466D01*
G01X1155187D01*
G02Y1588736I0J-2002D01*
G01X1155186D01*
G02X1153823Y1589272I0J2002D01*
G37*
G36*
G01X1163231D02*
G03X1162959I-136J-147D01*
G02X1161596Y1588736I-1363J1466D01*
G01X1161595D01*
G02Y1592740I0J2002D01*
G01X1161596D01*
G02X1162959Y1592204I0J-2002D01*
G03X1163231I136J147D01*
G02X1164594Y1592740I1363J-1466D01*
G01X1164595D01*
G02Y1588736I0J-2002D01*
G01X1164594D01*
G02X1163231Y1589272I0J2002D01*
G37*
G36*
G01X1173231D02*
G03X1172959I-136J-147D01*
G02X1171596Y1588736I-1363J1466D01*
G01X1171595D01*
G02Y1592740I0J2002D01*
G01X1171596D01*
G02X1172959Y1592204I0J-2002D01*
G03X1173231I136J147D01*
G02X1174594Y1592740I1363J-1466D01*
G01X1174595D01*
G02Y1588736I0J-2002D01*
G01X1174594D01*
G02X1173231Y1589272I0J2002D01*
G37*
G36*
G01X1411037Y1711457D02*
G03X1411142Y1712134I-151J370D01*
G02X1421732I5295J6330D01*
G03X1421837Y1711457I256J-307D01*
G02X1430690Y1698267I-5399J-13190D01*
G02X1402184I-14253J0D01*
G02X1411037Y1711457I14252J0D01*
G37*
G36*
G01X435643Y1711458D02*
G03X435748Y1712135I-151J370D01*
G02X446338I5295J6330D01*
G03X446443Y1711458I256J-307D01*
G02X455296Y1698268I-5399J-13190D01*
G02X426790I-14253J0D01*
G02X435643Y1711458I14252J0D01*
G37*
G54D104*
X1137717Y1558020D03*
G54D101*
X1290005Y293768D03*
G54D97*
X1455787Y1421784D03*
X1710550Y691327D03*
X93547Y692260D03*
X479646Y1421784D03*
G54D102*
X1175215Y1532913D03*
X1131715D03*
G54D82*
X1307572Y-26511D03*
X1040152Y-16511D03*
X1015152D03*
X1307572Y13489D03*
X1282572Y23489D03*
X1307572D03*
X1282572Y13489D03*
X1040152Y23489D03*
Y13489D03*
X973180Y-6500D03*
X998180D03*
X1015152Y13489D03*
X1282572Y-16511D03*
X973180Y-26500D03*
X998180D03*
Y-16500D03*
X1015152Y23489D03*
X1307572Y-16511D03*
X973180Y-16500D03*
X1474931Y23489D03*
X1499931D03*
X705760Y-26500D03*
X730760D03*
X705760Y-6500D03*
Y-16500D03*
X730760D03*
Y-6500D03*
X1474931Y13489D03*
X998180Y3500D03*
X973180D03*
X1499931Y13489D03*
X998180Y13500D03*
Y23500D03*
X973180D03*
Y13500D03*
X1499931Y-16511D03*
X1474931D03*
X1324471Y23489D03*
X1349471D03*
X822720Y3500D03*
X847720D03*
X822720Y23500D03*
Y13500D03*
X847720D03*
Y23500D03*
X1324471Y-16511D03*
X1349471D03*
X1324471Y13489D03*
X1349471D03*
X1307572Y-36511D03*
X1282572D03*
Y-26511D03*
X1307572Y-6511D03*
Y3489D03*
X1282572D03*
Y-6511D03*
X1015152Y-36511D03*
Y-26511D03*
X1040152D03*
Y-36511D03*
X1015152Y3489D03*
Y-6511D03*
X1040152D03*
Y3489D03*
X1499931Y-26511D03*
Y-36511D03*
X1474931D03*
Y-26511D03*
X1499931Y-6511D03*
Y3489D03*
X1474931D03*
Y-6511D03*
X1324471Y-36511D03*
Y-26511D03*
X1349471D03*
Y-36511D03*
X1324471Y3489D03*
Y-6511D03*
X1349471D03*
Y3489D03*
G54D89*
X70472Y173228D03*
Y236220D03*
G54D93*
X1565236Y184783D03*
Y264035D03*
G54D94*
X929331Y160413D03*
X922441Y237697D03*
X1534712Y20354D03*
X1787330Y24291D03*
X505185Y41142D03*
X757803Y45079D03*
X312921Y24291D03*
G54D92*
X676508Y224606D03*
G54D91*
Y145866D03*
G54D88*
X1829725Y130315D03*
G54D84*
X791280Y1704890D03*
X1066280D03*
G54D99*
X1405118Y112008D03*
G54D81*
X1341752Y-31511D03*
Y-21511D03*
Y-11511D03*
Y-1511D03*
X1482650Y-31511D03*
Y-21511D03*
Y-11511D03*
Y-1511D03*
X90998Y1517237D03*
X78120Y1517136D03*
X99750Y1563678D03*
X75922Y1560674D03*
X404030Y1593690D03*
X957156Y228863D03*
X899830Y973184D03*
X1380522Y261936D03*
X1388754Y255503D03*
X1380638Y247394D03*
X1386630Y240351D03*
X397406Y1634842D03*
X1031950Y385471D03*
X736710Y605542D03*
X527310Y96447D03*
X414406Y1626692D03*
X460910Y1627472D03*
X64410Y1600802D03*
X1340420Y540122D03*
X704770Y204921D03*
X896060Y482922D03*
X716698Y210721D03*
X704770Y216732D03*
X895340Y499582D03*
X907470Y213680D03*
X902350Y220768D03*
X953970Y206575D03*
X716698Y198887D03*
X704770Y193110D03*
Y181299D03*
X947496Y227835D03*
X705800Y169488D03*
X947496Y213697D03*
X907470Y227854D03*
X941050Y530552D03*
X968286Y482241D03*
X716698Y175387D03*
X902350Y206594D03*
X944032Y435931D03*
X716698Y187387D03*
X944250Y196189D03*
X954420Y512952D03*
Y498852D03*
G54D100*
X1247638Y269488D03*
G54D96*
X1550708Y991220D03*
X525275Y1171319D03*
X1332204D03*
X1326240Y811122D03*
X1501417Y1171319D03*
X1507381Y811122D03*
X1282913Y991220D03*
X306771D03*
X574566D03*
X350098Y811122D03*
X531240D03*
X356062Y1171319D03*
G54D80*
X723041Y-11500D03*
Y-21500D03*
X840001Y8500D03*
Y18500D03*
X980899Y-21500D03*
Y-11500D03*
Y8500D03*
Y18500D03*
X1032433Y-31511D03*
Y-21511D03*
Y-11511D03*
Y-1511D03*
X1290291Y-31511D03*
Y-21511D03*
Y-11511D03*
Y-1511D03*
X62813Y414300D03*
X47619Y417205D03*
X1386273Y270370D03*
X615573Y178034D03*
X628195Y174214D03*
X1282645Y253971D03*
X941059Y426211D03*
X901829Y514430D03*
X889439Y491299D03*
X1407029Y154432D03*
X922879Y530276D03*
X946727Y506252D03*
G54D95*
X1819208Y1420330D03*
X38346D03*
G54D83*
X19685Y-29134D03*
X1837795D03*
X1808192Y1569255D03*
X41870Y1511291D03*
X1812980Y502472D03*
X49280Y337402D03*
X441043Y1672205D03*
X1416437Y1672204D03*
X2081889Y1803261D03*
Y-29134D03*
G54D90*
X1057658Y204724D03*
X805690D03*
G54D98*
X763602Y605413D03*
X1739744D03*
X1094075Y605378D03*
X117933D03*
G54D103*
X841240Y1420330D03*
X1016240D03*
G54D87*
X1680327Y277236D03*
X1153555Y277208D03*
X704185Y277236D03*
X177413Y277208D03*
G54D85*
X177311Y1657953D03*
G54D86*
X1680232D03*
%LPC*%
G75*
G36*
G01X917246Y1656376D02*
G03X918130Y1656010I884J885D01*
G01X1064430D01*
X1084474Y1635966D01*
G03X1085358Y1635600I884J885D01*
G01X1101560D01*
X1103140Y1634020D01*
Y1607480D01*
X1102240Y1606580D01*
X944270D01*
X917966Y1632884D01*
G03X917082Y1633250I-884J-885D01*
G01X816320D01*
X812960Y1636610D01*
Y1714140D01*
X817460Y1718640D01*
X900700D01*
X907010Y1712330D01*
Y1667130D01*
G03X907376Y1666246I1251J0D01*
G01X917246Y1656376D01*
G37*
%LPD*%
G75*
G54D15*
X16925Y203366D03*
X17061Y196368D03*
X24720Y216362D03*
Y232362D03*
Y224362D03*
Y240362D03*
X16420Y420662D03*
X26500Y672862D03*
Y675862D03*
X27300Y764200D03*
X27520Y1245162D03*
X33500Y200862D03*
X33670Y192862D03*
Y208362D03*
X30795Y213358D03*
X33670Y232362D03*
X42500Y224409D03*
X30795Y227366D03*
X33670Y240362D03*
X40000Y298707D03*
X36000Y295952D03*
X40000Y293392D03*
X33105Y304972D03*
X35740Y363337D03*
X39320Y392269D03*
X40940Y387302D03*
X43020Y382942D03*
X41933Y395652D03*
X45960Y428806D03*
X38220Y589862D03*
Y592862D03*
X33020Y595232D03*
X32720Y598402D03*
X34790Y666595D03*
X31390D03*
X38470Y688122D03*
Y683122D03*
Y680622D03*
Y685622D03*
Y693122D03*
Y690622D03*
Y695622D03*
X34899Y711400D03*
X45700Y724100D03*
X45800Y726874D03*
X43841Y1248688D03*
X44833Y1656759D03*
X48269Y1672771D03*
X61470Y84622D03*
X62020Y295952D03*
X62731Y305426D03*
X59322Y360702D03*
X51114Y360862D03*
X62812Y412708D03*
X53406Y402862D03*
X62813Y415750D03*
X49360Y428806D03*
X61171D03*
X47619Y418655D03*
X47618Y415613D03*
X48400Y586000D03*
X57595Y603476D03*
X59500Y738700D03*
X56777Y1314165D03*
X56799Y1520094D03*
Y1536094D03*
Y1540094D03*
Y1560094D03*
X59833Y1604359D03*
X54333Y1613359D03*
X50333D03*
X54478Y1663669D03*
X54535Y1658447D03*
X57833Y1671809D03*
X53333Y1671862D03*
X65000Y1681900D03*
X58325Y1679275D03*
X78269Y26474D03*
X74869D03*
X65937Y28403D03*
Y48720D03*
X64870Y84622D03*
X77165Y278798D03*
Y295798D03*
Y286262D03*
Y303262D03*
X63429Y360702D03*
X67681D03*
X77220Y379022D03*
Y381522D03*
X68020Y395222D03*
X75516Y420319D03*
Y424319D03*
X64571Y428806D03*
X63540Y438802D03*
X72610Y441262D03*
Y444762D03*
X72981Y466385D03*
X77000Y485362D03*
X74550Y487812D03*
X80300Y641862D03*
X80241Y659011D03*
X80123Y664031D03*
X80135Y667933D03*
X74559Y667814D03*
X78080Y701832D03*
X63930Y739300D03*
X73759Y754726D03*
X68315Y765664D03*
X73759Y759246D03*
X72485Y1304152D03*
X75485D03*
X78485D03*
X72485Y1307152D03*
X75485D03*
X69485Y1304152D03*
Y1307152D03*
X65600Y1318588D03*
X65240Y1326068D03*
X75485Y1316152D03*
X72485Y1313152D03*
Y1310152D03*
X75485Y1313152D03*
Y1310152D03*
X69485D03*
X69809Y1333918D03*
Y1331418D03*
Y1336418D03*
X72809Y1333918D03*
Y1331418D03*
Y1336418D03*
X75809Y1333918D03*
Y1331418D03*
Y1336418D03*
X72909Y1339938D03*
X79009Y1340238D03*
X75909Y1339938D03*
X73027Y1347925D03*
X73059Y1345138D03*
X72987Y1342535D03*
X75909Y1342438D03*
X79009Y1342738D03*
Y1345238D03*
X78977Y1348025D03*
X75859Y1348138D03*
Y1345138D03*
X78120Y1515436D03*
Y1518836D03*
X76369Y1507456D03*
X76680Y1530482D03*
X72774Y1546519D03*
X75922Y1558974D03*
Y1562374D03*
X77618Y1572504D03*
X74218D03*
X77040Y1601102D03*
X65120Y1609909D03*
X65520Y1615972D03*
X74100Y1613300D03*
X77833Y1678902D03*
X73833Y1674252D03*
X69833Y1678582D03*
X85374Y19538D03*
X81974D03*
X92442Y26474D03*
X89042D03*
X87620Y285321D03*
X87845Y278798D03*
Y295798D03*
X87820Y302821D03*
X87520Y395865D03*
Y391391D03*
Y382219D03*
X85826Y428319D03*
X84410Y438519D03*
X83320Y445212D03*
X94439Y450081D03*
X81505Y447377D03*
X79400Y482862D03*
X91027Y643276D03*
X89859Y628246D03*
X86459D03*
X82961Y657111D03*
X95725Y654540D03*
X95860Y659622D03*
X83165Y652564D03*
X91078Y649584D03*
X83208Y646436D03*
X83250Y665428D03*
X84470Y668702D03*
X86433Y688160D03*
X81285Y689804D03*
X84035Y697604D03*
X93547Y692260D03*
X83004Y705141D03*
X97295Y699786D03*
X85095Y722164D03*
X95849Y716358D03*
X91610Y721414D03*
X82357Y737803D03*
X84623Y741249D03*
X81966Y759246D03*
X85877Y759275D03*
X93485Y1304152D03*
X87485D03*
X90485D03*
X93485Y1307152D03*
X84485Y1304152D03*
X81485D03*
X93485Y1318152D03*
Y1315652D03*
Y1310152D03*
Y1313152D03*
X94209Y1337738D03*
X81809Y1340238D03*
X84809D03*
X87809D03*
X90809D03*
X94209D03*
X84809Y1345238D03*
X81809Y1342738D03*
X84809D03*
X81809Y1348238D03*
Y1345238D03*
X84809Y1348238D03*
X87809D03*
Y1345238D03*
Y1342738D03*
X94209D03*
Y1348238D03*
Y1345238D03*
X90809Y1348238D03*
Y1345238D03*
Y1342738D03*
X88520Y1484482D03*
Y1491482D03*
Y1487982D03*
Y1494982D03*
X90998Y1518937D03*
Y1515537D03*
X89264Y1507611D03*
X92664D03*
X79769Y1507456D03*
X87500Y1567069D03*
X91500D03*
X90713Y1581852D03*
Y1597867D03*
X81008Y1589872D03*
X90788Y1615821D03*
Y1601867D03*
X81900Y1613300D03*
X85800D03*
X90698Y1630362D03*
X90788Y1619821D03*
X90698Y1642362D03*
X90407Y1656672D03*
X88333Y1661334D03*
X81833Y1674526D03*
X86245Y1694362D03*
X96420Y1693803D03*
X86030Y1683092D03*
X99547Y19538D03*
X110320D03*
X96147D03*
X106615Y26474D03*
X103215D03*
X113490Y216596D03*
X113400Y232128D03*
X110937Y285495D03*
Y302854D03*
X107200Y393562D03*
X107301Y388071D03*
X107419Y487807D03*
X104875Y490980D03*
X102384Y505374D03*
X112480Y507792D03*
X110689Y498271D03*
X110464Y505374D03*
X101983Y518100D03*
X99880Y526300D03*
X110060Y515279D03*
X99773Y515606D03*
X105587Y520727D03*
X106110Y633732D03*
X107489Y630917D03*
X110374Y630879D03*
X102269Y634466D03*
X107045Y661917D03*
X99021Y663732D03*
X103397Y667272D03*
X102120Y688650D03*
X102060Y692100D03*
X102420Y697262D03*
X96626Y736187D03*
X110527Y758869D03*
X108465Y1304292D03*
Y1307292D03*
X105475Y1304222D03*
Y1307222D03*
X102485Y1304152D03*
X99485D03*
X96485D03*
X102485Y1307152D03*
X99485D03*
X96485D03*
X108465Y1318292D03*
Y1310292D03*
Y1313292D03*
Y1315792D03*
X105475Y1318222D03*
Y1310222D03*
Y1313222D03*
Y1315722D03*
X99485Y1318152D03*
X96485D03*
Y1315652D03*
Y1310152D03*
Y1313152D03*
X99485Y1310152D03*
Y1313152D03*
Y1315652D03*
X102485Y1318152D03*
Y1310152D03*
Y1313152D03*
Y1315652D03*
X96809Y1340238D03*
Y1345238D03*
Y1348238D03*
Y1342738D03*
X112270Y1518907D03*
X99274Y1529169D03*
X96570Y1546187D03*
X99750Y1565378D03*
Y1561978D03*
X103902Y1584337D03*
X102251Y1576504D03*
X105651D03*
X104318Y1589352D03*
X100620Y1596367D03*
X101500Y1604400D03*
X100020Y1615821D03*
X98738Y1605867D03*
X104400Y1632385D03*
X104430Y1628012D03*
X104318Y1637862D03*
X99600Y1668332D03*
X99645Y1663217D03*
X99980Y1687921D03*
Y1698921D03*
X113720Y19538D03*
X127894D03*
X124494D03*
X120789Y26474D03*
X117389D03*
X115850Y186362D03*
X122000Y207362D03*
X116920Y207462D03*
X118920Y278875D03*
X119220Y306236D03*
X119920Y379362D03*
X119457Y392071D03*
Y388071D03*
X125070Y486736D03*
X125013Y491829D03*
X124124Y495883D03*
X116171Y485041D03*
X112483Y510637D03*
X116411Y497707D03*
X118652Y528860D03*
X129762Y531942D03*
X115793Y528188D03*
X112393D03*
X111920Y632922D03*
X114540Y633032D03*
X117750Y633232D03*
X120440Y633347D03*
X121400Y638062D03*
X125890Y644163D03*
X122329Y654660D03*
X122280Y651934D03*
X124431Y649570D03*
X122575Y671930D03*
X118019Y661371D03*
X124737Y735726D03*
X118737D03*
X121737D03*
Y738726D03*
X118737D03*
X124737D03*
X123220Y1324662D03*
X120220D03*
X112749Y1532594D03*
Y1528594D03*
Y1552594D03*
Y1556594D03*
X117707Y1553759D03*
X125033Y1589352D03*
X116798D03*
X123230Y1597350D03*
X119500Y1622380D03*
X124795Y1681846D03*
X128195Y1674362D03*
X114645Y1698862D03*
X117220Y1683437D03*
X127195Y1696362D03*
Y1700362D03*
Y1704362D03*
X125082Y1727092D03*
X123394Y1723472D03*
X117426Y1726622D03*
X125720Y1719262D03*
X141520Y181462D03*
X139720Y179162D03*
X143470Y184012D03*
X133590Y212382D03*
X129394Y278875D03*
X129375Y274800D03*
X129394Y306236D03*
X135220Y397071D03*
X132490Y420062D03*
X138042Y480238D03*
X132833D03*
X136982Y497090D03*
X131737Y496295D03*
X135006Y487753D03*
X131295Y487822D03*
X141325Y503806D03*
X141462Y507600D03*
X141329Y510487D03*
X141220Y498810D03*
X138878Y512550D03*
X138408Y507366D03*
X139153Y516453D03*
X133160Y532002D03*
X132600Y537072D03*
Y540472D03*
X133467Y634531D03*
X131740Y640103D03*
X131600Y646861D03*
X131330Y665740D03*
X142960Y690807D03*
X140460D03*
X142754Y698811D03*
X140254D03*
X142778Y706835D03*
X140278D03*
X140326Y721660D03*
X142826D03*
X140142Y1392545D03*
Y1396275D03*
X129627Y1556360D03*
X129586Y1553759D03*
X129813Y1604367D03*
X130533Y1622321D03*
X129533Y1637862D03*
X137420Y1708362D03*
X144520Y1717562D03*
X141642Y1717592D03*
X134557Y1722778D03*
X137852Y1726572D03*
X160360Y19538D03*
X156655Y26474D03*
X153255D03*
X147924Y28258D03*
X148784Y48720D03*
X145720Y186462D03*
Y202862D03*
Y206362D03*
X156670Y344542D03*
X159170D03*
X154220Y375682D03*
X158110Y376172D03*
X160090Y391170D03*
Y397470D03*
X152826Y439397D03*
Y434362D03*
X156306Y449045D03*
X153360Y449112D03*
X149557Y494353D03*
X150113Y488487D03*
X161267Y503143D03*
X149472Y506810D03*
X160000Y510052D03*
X152470Y495383D03*
X151378Y526924D03*
X149512Y514810D03*
X150800Y512021D03*
X153737Y514893D03*
X149504Y519881D03*
X154647Y521783D03*
X150877Y757969D03*
X151277Y1339183D03*
X153877D03*
X156477D03*
X156417Y1336343D03*
X151217Y1336393D03*
X153817D03*
X156417Y1333843D03*
X151217Y1333893D03*
X153817D03*
X151277Y1346883D03*
X153877D03*
X151277Y1349383D03*
X153877D03*
X156477Y1346883D03*
Y1349383D03*
Y1344383D03*
X151277D03*
X153877D03*
X156477Y1341883D03*
X151277D03*
X153877D03*
X147307Y1404745D03*
X149568Y1395145D03*
Y1397695D03*
X152684Y1403451D03*
X157490Y1421454D03*
X154990D03*
X159858Y1409361D03*
X155858Y1406669D03*
Y1409390D03*
X157530Y1432124D03*
X155030D03*
X157530Y1424124D03*
X155030D03*
X157530Y1429124D03*
X155030Y1426624D03*
Y1429124D03*
X157530Y1426624D03*
Y1435124D03*
X155030D03*
X157530Y1437754D03*
X155030D03*
X146390Y1504240D03*
X145538Y1517374D03*
X148938D03*
X153600Y1505600D03*
X147067Y1545985D03*
X157441Y1581932D03*
X146312Y1569525D03*
X149712D03*
X152026Y1614138D03*
X158335Y1614452D03*
X155180Y1619872D03*
X156070Y1695702D03*
X145745Y1712362D03*
X161310Y1708022D03*
X148145Y1701862D03*
X155145Y1713517D03*
X163760Y19538D03*
X174533D03*
X170828Y26474D03*
X167428D03*
X164830Y344542D03*
X161670D03*
X173275Y393497D03*
X164000Y415362D03*
X163926Y425383D03*
X164000Y420362D03*
X172507Y417205D03*
X163926Y430883D03*
Y443319D03*
Y439397D03*
Y435383D03*
X178546Y453806D03*
X172632Y454095D03*
X165176Y500782D03*
X176393Y575189D03*
X173793D03*
X176393Y572689D03*
X173793D03*
X171293D03*
Y575189D03*
X173793Y577790D03*
X171293D03*
X176393D03*
X176651Y596883D03*
Y594163D03*
X173878Y597027D03*
Y594307D03*
X176651Y599603D03*
X173878Y599747D03*
X161126Y721660D03*
X161078Y706835D03*
X163626Y721660D03*
X163578Y706835D03*
X170877Y1333783D03*
Y1336383D03*
X176077Y1333783D03*
X173477D03*
X176077Y1336383D03*
X173477D03*
X170907Y1339233D03*
X176107D03*
X173507D03*
X170877Y1341883D03*
X176077D03*
X173477D03*
Y1349383D03*
Y1346883D03*
Y1344383D03*
X176077D03*
Y1346883D03*
Y1349383D03*
X170877D03*
Y1346883D03*
Y1344383D03*
X176358Y1403669D03*
X176258Y1400669D03*
X173892Y1402749D03*
Y1405649D03*
X170922Y1399255D03*
X166262D03*
X173252Y1400005D03*
X168592D03*
X160490Y1421454D03*
X164000Y1408862D03*
X162257Y1406594D03*
X160530Y1432124D03*
Y1424124D03*
Y1429124D03*
Y1426624D03*
Y1435124D03*
Y1437754D03*
X165500Y1440362D03*
X173727Y1452134D03*
Y1448734D03*
X170570Y1509250D03*
X164710Y1518014D03*
X168110D03*
X173331Y1579399D03*
X167266Y1569968D03*
X170666D03*
X172099Y1588141D03*
X164920Y1712017D03*
X163060Y1717017D03*
X178226Y1726517D03*
X172962Y1721234D03*
X169777Y1726517D03*
X178142Y1720652D03*
X177933Y19538D03*
X186120Y24162D03*
X188620D03*
X190880Y383012D03*
Y387162D03*
Y391082D03*
X178375Y396571D03*
X181845Y401071D03*
X187371Y425383D03*
X187532Y421387D03*
X187371Y430883D03*
Y443383D03*
X180740Y437562D03*
X184550Y435712D03*
X187371Y440742D03*
X194440Y433895D03*
Y439565D03*
X187371Y447172D03*
X177871D03*
X181994Y453932D03*
X180640Y447172D03*
X185211Y453942D03*
X185191Y502439D03*
X186793Y575189D03*
X184193D03*
X186793Y572689D03*
X184193D03*
X181593Y575189D03*
X178993D03*
X181593Y572689D03*
X178993D03*
X189293Y575189D03*
X186793Y577790D03*
X184193D03*
X189293D03*
X181593D03*
X178993D03*
X181651Y596883D03*
X179151D03*
X186796Y594195D03*
Y596915D03*
X184151Y596883D03*
X179151Y594163D03*
X181651D03*
X184151D03*
X181651Y599603D03*
X179151D03*
X186796Y599635D03*
X184151Y599603D03*
X186720Y737862D03*
X180720D03*
X183720D03*
Y734862D03*
X180720D03*
X186720D03*
X185835Y757057D03*
X188978Y756855D03*
X191602Y756839D03*
X189377Y1333783D03*
X191977D03*
X189377Y1336383D03*
X191977D03*
X191947Y1339263D03*
X189347D03*
X189377Y1349383D03*
X191977D03*
X189377Y1346883D03*
X191977D03*
Y1344383D03*
X189377D03*
X191977Y1341883D03*
X189377D03*
X187711Y1395170D03*
Y1397670D03*
X190827Y1403451D03*
X180977Y1396173D03*
X178458Y1399269D03*
Y1402169D03*
Y1405069D03*
X188211Y1406691D03*
X186165Y1422589D03*
X183135Y1419784D03*
X180510Y1420258D03*
X177510D03*
X186135Y1419784D03*
X183165Y1422589D03*
X177510Y1423278D03*
X180510D03*
X183075Y1430424D03*
Y1425424D03*
Y1427924D03*
X186075Y1430424D03*
Y1425424D03*
Y1427924D03*
X183075Y1432924D03*
X186075D03*
X192600Y1557360D03*
X185895Y1557875D03*
X189600Y1566300D03*
X187400Y1568132D03*
X187542Y1729092D03*
X193293Y1722197D03*
X188794Y1725092D03*
X207894Y19538D03*
X204494D03*
X200789Y26474D03*
X197389D03*
X195050Y412055D03*
X199149Y425755D03*
Y420255D03*
Y414755D03*
X204699Y423242D03*
Y428742D03*
X195050Y417465D03*
X199149Y436755D03*
Y442255D03*
Y431255D03*
Y453255D03*
Y447755D03*
X197650Y455712D03*
X199149Y468255D03*
X208200Y493510D03*
X202338Y568746D03*
X201392Y574271D03*
X198336D03*
X204610Y571097D03*
X199164Y582481D03*
X200654Y578271D03*
X201622Y581009D03*
X208056Y591665D03*
X208806Y589335D03*
X208056Y587005D03*
X208806Y584675D03*
X202262Y592305D03*
X205162D03*
X202338Y602746D03*
X201392Y608271D03*
X198336D03*
X203892Y594471D03*
X202492Y596571D03*
X208292D03*
X206892Y594371D03*
X205392Y596571D03*
X204610Y605097D03*
X199164Y616481D03*
X200654Y612271D03*
X201622Y615009D03*
X208806Y618675D03*
X208056Y621005D03*
X208806Y623335D03*
X202338Y636746D03*
X208056Y625665D03*
X203892Y628471D03*
X202492Y630571D03*
X202262Y626305D03*
X208292Y630571D03*
X206892Y628371D03*
X205162Y626305D03*
X205392Y630571D03*
X204610Y639097D03*
X201392Y642271D03*
X199164Y650481D03*
X200654Y646271D03*
X201622Y649009D03*
X198336Y642271D03*
X208056Y655005D03*
X208806Y657335D03*
Y652675D03*
X207620Y671262D03*
X198420Y672662D03*
X198495Y669487D03*
X208056Y659665D03*
X205392Y664571D03*
X205162Y660305D03*
X206892Y662371D03*
X202262Y660305D03*
X202492Y664571D03*
X203892Y662471D03*
X208292Y664571D03*
X196049Y678195D03*
X194196Y687061D03*
X200018Y677492D03*
X193332Y678195D03*
X207129Y690027D03*
X203199Y690006D03*
X197086Y686326D03*
X203179Y693626D03*
X207140Y693636D03*
X195735Y696469D03*
X198235Y698969D03*
Y696469D03*
X200735Y698969D03*
Y696469D03*
X207140Y738462D03*
X205220Y736562D03*
X201220Y736662D03*
X203660Y731802D03*
X195602Y756839D03*
X203602Y756855D03*
X208977Y1336383D03*
Y1333783D03*
X194577D03*
Y1336383D03*
X209007Y1339263D03*
X194547D03*
X208977Y1341883D03*
X194577Y1349383D03*
Y1346883D03*
Y1344383D03*
X208977D03*
Y1346883D03*
Y1349383D03*
X194577Y1341883D03*
X206735Y1400005D03*
X209065Y1399255D03*
X204405D03*
X198001Y1409361D03*
X193941Y1407029D03*
X200797Y1409605D03*
X200492Y1406686D03*
X193941Y1409750D03*
X195966Y1542863D03*
X203120Y1624782D03*
X208115Y1624217D03*
X195590Y1714517D03*
X196010Y1709017D03*
X208295Y1703362D03*
X199050Y1726431D03*
X204600Y1733022D03*
X222067Y19538D03*
X218667D03*
X214962Y26474D03*
X211562D03*
X225407Y321831D03*
X209530Y426192D03*
X217770Y428262D03*
X224210Y431501D03*
X224305Y422977D03*
X219995Y426267D03*
X224210Y436619D03*
X218140Y440735D03*
X218010Y432735D03*
X223664Y443125D03*
X220000Y448735D03*
X212891Y566632D03*
X210391Y567981D03*
X212891Y601981D03*
X210391D03*
Y635981D03*
X212891D03*
X210320Y671262D03*
X224900Y713293D03*
X209720Y731862D03*
X220033Y756844D03*
X211602Y756855D03*
X216842Y756865D03*
X214177Y1336383D03*
X211577D03*
X214177Y1333783D03*
X211577D03*
X214207Y1339263D03*
X211607D03*
X214177Y1341883D03*
X211577D03*
X214177Y1349383D03*
Y1346883D03*
Y1344383D03*
X211577D03*
Y1346883D03*
Y1349383D03*
X211395Y1400005D03*
X214201Y1404169D03*
X212035Y1402899D03*
X214101Y1401169D03*
X216554Y1399264D03*
Y1402164D03*
Y1405064D03*
X212035Y1405799D03*
X219587Y1435402D03*
X217469Y1454725D03*
X219587Y1443402D03*
Y1439402D03*
X220869Y1454725D03*
X209820Y1631142D03*
X210593Y1714017D03*
X212120Y1703062D03*
X214120Y1713462D03*
X233339Y17662D03*
X235701Y21582D03*
X241310Y20322D03*
X229135Y26474D03*
X225735D03*
X238063Y26232D03*
X235701Y39570D03*
X229131Y50646D03*
X225731D03*
X239820Y54362D03*
X239720Y71862D03*
X239010Y78542D03*
X238297Y129703D03*
X234902Y174047D03*
X226800Y359464D03*
X230359Y461683D03*
X227430Y719772D03*
X238940Y716652D03*
X230864Y1254295D03*
X246510Y20362D03*
X242220Y39362D03*
X246220D03*
X250220D03*
X254050Y39422D03*
X246360Y26852D03*
X248820Y48962D03*
X252320D03*
X255820D03*
X257520Y51562D03*
X254020D03*
X250520D03*
X249885Y69623D03*
X245220Y67862D03*
X248097Y92143D03*
X247897Y100543D03*
X244822Y115543D03*
Y111543D03*
X253910Y115722D03*
X253878Y111771D03*
X243892Y140912D03*
X259933Y141122D03*
X257256Y156727D03*
X245490Y159702D03*
X252000Y395400D03*
X255810Y405582D03*
X252500Y415862D03*
X258066Y426735D03*
X256695Y461117D03*
X257750Y450842D03*
X254713Y518465D03*
X245700Y513262D03*
X250100Y521783D03*
X256885Y574805D03*
X254385D03*
X256855Y571995D03*
X251885Y574805D03*
X249800Y563262D03*
X254355Y589235D03*
X256855D03*
X251855D03*
X256855Y605995D03*
X251885Y608805D03*
X257643Y594220D03*
X255043D03*
Y596820D03*
X257643D03*
X256885Y608805D03*
X254385D03*
X256855Y603495D03*
X251855Y623265D03*
X254355D03*
X256855D03*
Y639995D03*
Y637495D03*
X257643Y628220D03*
X255043D03*
Y630820D03*
X257643D03*
X256885Y642805D03*
X254385D03*
X251855Y657265D03*
X251885Y642805D03*
X254355Y657265D03*
X256855D03*
X257643Y662220D03*
X255043D03*
Y664820D03*
X257643D03*
X253819Y675567D03*
X253849Y678077D03*
X256419Y675567D03*
X256449Y678077D03*
X251219Y675567D03*
X251249Y678077D03*
X248649D03*
X248989Y698827D03*
X249019Y693767D03*
X251589Y698827D03*
X251649Y696277D03*
X254189Y698827D03*
X251619Y693767D03*
X256849Y696277D03*
X256789Y698827D03*
X256819Y693767D03*
X254249Y696277D03*
X254219Y693767D03*
X248300Y703862D03*
X242460Y716652D03*
X253057Y755345D03*
X245487Y755435D03*
X259510Y757822D03*
X251187Y1255025D03*
X263240Y38122D03*
X266990Y41832D03*
X275120Y28562D03*
X275900Y48872D03*
X259320Y48962D03*
X261020Y51562D03*
X263520D03*
X261820Y48962D03*
X264740Y49182D03*
X266497Y69536D03*
Y72036D03*
X264720Y56362D03*
Y60362D03*
Y64362D03*
X266597Y77526D03*
Y80026D03*
X263320Y87662D03*
X261420Y100662D03*
X264920D03*
X268420D03*
X262920Y97962D03*
X266420D03*
X269920D03*
X273620Y96662D03*
X263550Y120922D03*
X269191Y121092D03*
X275797Y120245D03*
X265910Y125492D03*
X266975Y140107D03*
X260600Y151062D03*
X272800Y140162D03*
X264578Y151203D03*
X260100Y159562D03*
X265500Y227862D03*
X263000D03*
X260500Y227362D03*
Y224862D03*
X270240Y245332D03*
X271821Y251962D03*
X267759D03*
X259224Y419532D03*
X263430Y422235D03*
X259869Y431039D03*
X262963Y443735D03*
X272500Y447735D03*
X263040Y448752D03*
X272500Y452862D03*
X264055Y574505D03*
X264025Y571995D03*
X261555Y574505D03*
X261525Y571995D03*
X264055Y566935D03*
X263995Y569485D03*
X261495D03*
X261555Y566935D03*
X266555Y574505D03*
X266525Y571995D03*
X266495Y569485D03*
X266555Y566935D03*
X269055Y574505D03*
X269025Y571995D03*
X268995Y569485D03*
X269055Y566935D03*
X261465Y592115D03*
X261525Y589565D03*
X264025D03*
X263965Y592115D03*
X266525Y589565D03*
X266465Y592115D03*
X269025Y589565D03*
X268965Y592115D03*
X264025Y605995D03*
X261525D03*
X264055Y608505D03*
X261555D03*
X261435Y597175D03*
X261495Y594625D03*
X263995D03*
X263935Y597175D03*
X266525Y605995D03*
X266555Y608505D03*
X266435Y597175D03*
X266495Y594625D03*
X261525Y603495D03*
X264025D03*
X266525D03*
X269025Y605995D03*
X269055Y608505D03*
X268935Y597175D03*
X268995Y594625D03*
X269025Y603495D03*
X261495Y621055D03*
X263995D03*
X261525Y623565D03*
X264025D03*
X263995Y611055D03*
X261495D03*
X266495Y621055D03*
X266525Y623565D03*
X266495Y611055D03*
X268995Y621055D03*
X269025Y623565D03*
X268995Y611055D03*
X261525Y639995D03*
X264025D03*
X261525Y637495D03*
X266525Y639995D03*
X269025D03*
X264025Y637495D03*
X266525D03*
X269025D03*
X263965Y626115D03*
X261465D03*
X266465D03*
X268965D03*
X261495Y655055D03*
X263995D03*
X261525Y657565D03*
X264025D03*
X263995Y645055D03*
X264055Y642505D03*
X261495Y645055D03*
X261555Y642505D03*
X266495Y655055D03*
X266525Y657565D03*
X266495Y645055D03*
X266555Y642505D03*
X268995Y655055D03*
X269025Y657565D03*
X268995Y645055D03*
X269055Y642505D03*
X261465Y660115D03*
X263965D03*
X266465D03*
X268965D03*
X259049Y678077D03*
X259019Y675567D03*
X259419Y693767D03*
X259389Y698827D03*
X259449Y696277D03*
X269600Y715792D03*
X274247Y727165D03*
X268331Y738029D03*
X273046Y735662D03*
X270100Y727262D03*
X264000Y726262D03*
X266700Y730962D03*
X271570Y746422D03*
X265997Y747535D03*
X272208Y768516D03*
X271057Y765525D03*
Y762425D03*
X287000Y20862D03*
X284233Y26474D03*
X280833D03*
X290799Y28362D03*
X284230Y50646D03*
X280830D03*
X289400Y54222D03*
X285357Y105003D03*
X288557D03*
X280857Y107303D03*
X285857Y115603D03*
X282857D03*
X280857Y109903D03*
X275797Y129592D03*
X287000Y139862D03*
X283053Y139728D03*
X276825Y140462D03*
X290685Y165447D03*
X286481Y251962D03*
X281077D03*
X276491D03*
X289274Y290662D03*
X284515D03*
X276500Y444862D03*
X274850Y442562D03*
X279500Y455362D03*
X277578Y509039D03*
X284482Y566022D03*
X286582Y637809D03*
Y634283D03*
X284287Y716015D03*
X277046Y725709D03*
Y735442D03*
X284358Y732562D03*
X283350Y728483D03*
X289137Y735275D03*
X279507Y727025D03*
X285046Y737964D03*
X281046Y737938D03*
X275210Y738102D03*
X287607Y754962D03*
X277046Y746702D03*
X281046D03*
X285046D03*
X299500Y22862D03*
X295520Y12762D03*
X302610Y26362D03*
X292060Y24472D03*
X295520Y26362D03*
X300248Y28362D03*
X304927Y24654D03*
X304972Y28362D03*
X302720Y38182D03*
X292590Y53982D03*
X293161Y50522D03*
X306570Y50222D03*
X290720Y40017D03*
X294720D03*
X295524Y52092D03*
X301310Y52482D03*
X298550Y51602D03*
X303715Y50857D03*
X292942Y71499D03*
X305747Y64013D03*
Y61113D03*
X305247Y71567D03*
X301600Y82457D03*
X302310Y75673D03*
X295357Y88903D03*
X307820Y95724D03*
X301183Y107103D03*
Y110003D03*
Y112803D03*
X296478Y149203D03*
X296800Y139762D03*
X306000Y165662D03*
X295685Y165447D03*
X296478Y158703D03*
X306730Y173842D03*
X304651Y251962D03*
X291759D03*
X306736Y290662D03*
X302765D03*
X298184D03*
X293763D03*
X298587Y508074D03*
X300520Y552262D03*
X307987Y577658D03*
X293805Y569397D03*
Y565997D03*
X298000Y587890D03*
X308417Y585158D03*
X308447Y592255D03*
X306144Y602225D03*
X305612Y622530D03*
Y625030D03*
Y627530D03*
X296405Y630732D03*
Y634132D03*
X295962Y679374D03*
X294679Y688446D03*
Y685046D03*
X291600Y705162D03*
X298273Y715400D03*
X297087Y721249D03*
X304602Y727968D03*
X293027Y755985D03*
X303647Y1307981D03*
X303723Y1353316D03*
Y1355853D03*
X304051Y1365453D03*
X306667Y1361597D03*
X302805Y1379941D03*
Y1376541D03*
X296170Y1622852D03*
X310400Y50362D03*
X314657Y71803D03*
Y68903D03*
X323040Y73122D03*
X323117Y81168D03*
Y76938D03*
X322875Y84318D03*
X316364Y89212D03*
X310459Y75892D03*
X320430Y78002D03*
X313357Y89503D03*
X313457Y96803D03*
X311057Y107103D03*
Y110003D03*
Y112803D03*
X308175Y144202D03*
X308500Y165662D03*
X311200Y165562D03*
X309230Y173842D03*
X309756Y177449D03*
Y181449D03*
X310970Y195362D03*
X308790Y197622D03*
X320270Y200462D03*
X319370Y214492D03*
X316370D03*
X319370Y217492D03*
X316370D03*
X323314Y210645D03*
X306910Y228162D03*
X309910D03*
X306910Y225162D03*
X309910D03*
X322658Y229254D03*
X319718Y223750D03*
X317981Y237724D03*
X320940Y238372D03*
X317129Y251962D03*
X316463Y290662D03*
X316444Y559125D03*
X317860Y572322D03*
X319520Y577658D03*
X312007Y588675D03*
X319520Y582658D03*
X316127Y592785D03*
X318560Y587632D03*
X321276Y599298D03*
X317386Y623207D03*
X308605Y629525D03*
Y627025D03*
X319557Y736225D03*
X317967Y746985D03*
Y771875D03*
X320578Y1290197D03*
X323028Y1297967D03*
X320428D03*
Y1295467D03*
X323028D03*
Y1292967D03*
X320428D03*
X320245Y1357401D03*
X313841Y1365553D03*
X309841Y1364815D03*
X318051Y1367043D03*
X316579Y1364585D03*
X309841Y1367871D03*
X322575Y1358151D03*
X332500Y150738D03*
X326216Y138787D03*
X326900Y162287D03*
X323420Y207549D03*
X326168Y207580D03*
X334485Y216809D03*
X337000Y216862D03*
X335575Y214170D03*
X328588Y209677D03*
X334500Y219362D03*
X337000D03*
X328939Y229139D03*
X335385Y235309D03*
X335412Y222176D03*
X329648Y252202D03*
X341295Y290239D03*
X329002Y290662D03*
X330674Y365702D03*
X328167Y379073D03*
X336270Y402992D03*
X329050Y607402D03*
X331339Y709313D03*
X328120Y710862D03*
X335677Y715215D03*
X327107Y732665D03*
X335467Y725335D03*
X338097Y736235D03*
X335126Y728323D03*
X327096Y736005D03*
X336446Y746486D03*
X338667Y772452D03*
X341527Y778362D03*
X339148Y1269717D03*
X339088Y1272287D03*
X339028Y1274887D03*
X325688Y1290167D03*
X325718Y1287587D03*
X328078Y1288747D03*
X323178Y1290197D03*
X323208Y1287617D03*
X328168Y1280967D03*
X325748Y1284987D03*
X328108Y1286147D03*
X328138Y1283567D03*
X328018Y1291317D03*
X339035Y1280218D03*
X339040Y1277594D03*
X328065Y1299248D03*
X325538Y1297937D03*
Y1292937D03*
Y1295437D03*
X328058Y1293917D03*
X328070Y1296624D03*
X335679Y1330518D03*
X334973Y1333353D03*
X338795Y1338799D03*
X336179Y1342753D03*
X324905Y1357401D03*
X327235Y1358151D03*
X332475Y1357945D03*
X327875Y1363945D03*
Y1361045D03*
X330041Y1362315D03*
X329941Y1359315D03*
X332475Y1363345D03*
Y1360445D03*
X340440Y120552D03*
X343450Y131167D03*
X342700Y139662D03*
X355189Y144267D03*
X351100Y150412D03*
X348100Y185162D03*
X345600Y188162D03*
X356295Y219362D03*
X353145D03*
X342000Y252612D03*
X354672Y252693D03*
X354145Y290591D03*
X345411Y364702D03*
Y376923D03*
X343354Y391643D03*
X347340Y407462D03*
X348880Y703442D03*
X354100Y720743D03*
X352879Y728657D03*
X348037Y728735D03*
X348730Y735098D03*
Y731698D03*
X344264Y1272455D03*
X341754Y1272485D03*
X344252Y1269948D03*
X341742Y1269978D03*
X344258Y1267117D03*
X341748Y1267147D03*
X341754Y1274985D03*
X344264Y1274955D03*
X355036Y1272433D03*
Y1269933D03*
X355378Y1262027D03*
X355318Y1264597D03*
X355258Y1267197D03*
X355036Y1274933D03*
X341605Y1280248D03*
X344115Y1280218D03*
X344264Y1277455D03*
X341754Y1277485D03*
X355048Y1277440D03*
X355025Y1280248D03*
X352373Y1334603D03*
X354703Y1335353D03*
X345969Y1342755D03*
X341969Y1342017D03*
X350179Y1344245D03*
X348707Y1341787D03*
X341969Y1345073D03*
X354850Y1371908D03*
X351850D03*
X349260Y1373418D03*
X351850Y1375408D03*
X354850D03*
X351850Y1378408D03*
X354850D03*
X351850Y1381408D03*
X354850D03*
X349260Y1376918D03*
Y1379918D03*
X349636Y1399601D03*
X352713Y1399336D03*
X355513Y1402306D03*
X352513D03*
X349513D03*
X355325Y1405386D03*
X349463Y1405286D03*
X352463D03*
X355325Y1408386D03*
X346426Y1414401D03*
X352401Y1414432D03*
X355325Y1414386D03*
Y1417386D03*
X352401Y1411432D03*
X355325Y1411386D03*
X352401Y1408432D03*
X349123Y1411376D03*
X349323Y1408406D03*
X349073Y1414356D03*
X346256Y1417301D03*
X352231Y1417332D03*
X348903Y1417256D03*
X363625Y127662D03*
X361800Y122522D03*
X366060Y133912D03*
X363525Y158702D03*
X361190Y210762D03*
X357303Y213159D03*
X371551Y224862D03*
X367306Y252811D03*
X366498Y290264D03*
X357660Y318850D03*
X364014Y366391D03*
Y378649D03*
X364179Y392037D03*
X370200Y409582D03*
X373720Y431362D03*
X365720Y440562D03*
X365771Y449480D03*
X359669Y686744D03*
X359639Y690114D03*
X360470Y705965D03*
X363101Y697348D03*
Y693948D03*
X360990Y726862D03*
X358902Y736225D03*
X355946Y728800D03*
X359790Y729835D03*
X358902Y739755D03*
Y743035D03*
Y754945D03*
Y746405D03*
Y773352D03*
X371578Y1248967D03*
X371458Y1254137D03*
X371330Y1256687D03*
X371518Y1251537D03*
X371278Y1259257D03*
X360198Y1269777D03*
X357546Y1272403D03*
Y1269903D03*
X360138Y1272347D03*
X357828Y1264567D03*
X357888Y1261997D03*
X360378Y1264627D03*
X360438Y1262057D03*
X357768Y1267167D03*
X360318Y1267227D03*
X357546Y1274903D03*
X360128Y1274957D03*
X371218Y1261857D03*
X371225Y1267188D03*
X371230Y1264564D03*
X357558Y1277410D03*
X357535Y1280218D03*
X360120Y1277654D03*
X367694Y1317092D03*
X367807Y1319592D03*
X368391Y1328161D03*
X370923Y1325373D03*
X357033Y1334603D03*
X359363Y1335353D03*
X362147Y1336553D03*
X360003Y1338247D03*
X364269Y1338017D03*
X364073Y1334903D03*
X360003Y1341147D03*
X362147Y1339653D03*
X364347Y1340853D03*
X364647Y1371990D03*
X361647D03*
X358647D03*
X367647D03*
X370552Y1372073D03*
X364647Y1375490D03*
X361647D03*
X358647D03*
Y1378490D03*
X370552Y1375573D03*
X367647Y1375490D03*
X355713Y1399336D03*
X361703Y1399386D03*
X364703D03*
X367703D03*
X370703D03*
X358703Y1402386D03*
X361703D03*
X364703D03*
X367703D03*
X370703D03*
X358713Y1399336D03*
X358573Y1405336D03*
X361573D03*
X364573D03*
X367573D03*
X370573D03*
X358703Y1414606D03*
X361703D03*
X364703D03*
X361703Y1417386D03*
X358703D03*
X364703D03*
X367703D03*
Y1414606D03*
X358217Y1411405D03*
X370517Y1414615D03*
X370717Y1417405D03*
X357917Y1408205D03*
X367948Y1531529D03*
X371850Y1534062D03*
X368600Y1543200D03*
X367140Y1645390D03*
X366700Y1649000D03*
X370500Y1654362D03*
X370635Y1675820D03*
X369300Y1680400D03*
Y1682900D03*
X380930Y122022D03*
X383160Y124322D03*
X383060Y128491D03*
X372530Y122972D03*
X373200Y126052D03*
X379295Y131002D03*
X379860Y252162D03*
X379112Y290386D03*
X385720Y320902D03*
X376500Y366391D03*
Y378649D03*
X377136Y390307D03*
X390220Y392062D03*
X383060Y403542D03*
X379220Y436362D03*
X376220D03*
X382220D03*
X389920Y461362D03*
X379220Y470962D03*
X387500Y495362D03*
X389020Y522862D03*
X371970Y683892D03*
X381010Y734732D03*
X376638Y1248997D03*
X374088Y1248937D03*
X374028Y1251507D03*
X373823Y1256896D03*
X376333Y1256866D03*
X376518Y1254167D03*
X376578Y1251567D03*
X373968Y1254107D03*
X373835Y1259403D03*
X376345Y1259373D03*
X387478Y1248967D03*
X387358Y1254137D03*
X387117Y1256851D03*
X387418Y1251537D03*
X387117Y1259351D03*
X373835Y1261903D03*
Y1264403D03*
X376345Y1261873D03*
Y1264373D03*
X376285Y1267218D03*
X373735Y1267158D03*
X387117Y1261851D03*
X387129Y1264358D03*
X387125Y1267188D03*
X384501Y1321177D03*
X386831Y1321927D03*
X378097Y1329329D03*
X374097Y1328591D03*
X382307Y1330819D03*
X380835Y1328361D03*
X374097Y1331647D03*
X373552Y1372073D03*
X377025Y1371990D03*
X380025D03*
X373532Y1378598D03*
X373552Y1375573D03*
X380025Y1378490D03*
X377025D03*
X380025Y1375490D03*
X377025D03*
Y1381490D03*
X380025D03*
X376825Y1399386D03*
X379825D03*
X373703D03*
X379825Y1402386D03*
X376825D03*
X373703D03*
X376825Y1405386D03*
X379825D03*
X373573Y1405336D03*
X374027Y1411365D03*
X373703Y1414606D03*
X376825Y1414386D03*
X379825D03*
X376825Y1417386D03*
Y1411386D03*
X379825D03*
X373703Y1417386D03*
X376825Y1408386D03*
X379825D03*
X374307Y1408135D03*
X382489Y1428478D03*
X385667Y1433425D03*
X386827Y1429525D03*
X377830Y1534342D03*
X374900Y1534102D03*
X381120D03*
X377720Y1539862D03*
X374720D03*
X374800Y1546400D03*
X385100Y1539700D03*
X381800Y1539600D03*
X381000Y1546500D03*
X384000D03*
X378000Y1546400D03*
X387930Y1585155D03*
X384600Y1595100D03*
X382220Y1591870D03*
X374391Y1648476D03*
X385123Y1639732D03*
X378547D03*
X380170Y1660002D03*
X372640Y1662112D03*
X380077Y1654049D03*
X372009Y1682584D03*
X375430Y1676462D03*
X376610Y1688252D03*
X396380Y62742D03*
X402100Y62632D03*
X399240Y62722D03*
X404910Y62562D03*
X388735Y117322D03*
X395980Y148272D03*
X388965Y215067D03*
X388720Y218362D03*
X394720Y206362D03*
X402700Y234167D03*
X392616Y252162D03*
X396294Y281585D03*
X392083Y290954D03*
X404215Y291140D03*
X398720Y321202D03*
X398661Y323761D03*
X390876Y365640D03*
X390843Y378439D03*
X403875Y365640D03*
X404120Y378439D03*
X404291Y391433D03*
X391149Y404304D03*
X403720Y405552D03*
X388720Y430862D03*
X403220Y436362D03*
X395520Y448362D03*
X400080Y472652D03*
X402500Y495362D03*
X394500Y522862D03*
X400589Y575236D03*
X398796Y1161570D03*
Y1153070D03*
Y1170070D03*
X403738Y1249027D03*
X403618Y1254197D03*
X403498Y1256747D03*
X403678Y1251597D03*
X392538Y1248997D03*
X389928Y1251507D03*
X389988Y1248937D03*
X389868Y1254107D03*
X392298Y1256717D03*
X392418Y1254167D03*
X389627Y1256821D03*
X392478Y1251567D03*
X392238Y1259287D03*
X389627Y1259321D03*
X403438Y1259317D03*
X392220Y1264594D03*
X392228Y1261897D03*
X389627Y1261821D03*
X389639Y1264328D03*
X389635Y1267158D03*
X392185Y1267218D03*
X403385Y1267248D03*
X403378Y1261917D03*
X403390Y1264624D03*
X399935Y1317092D03*
Y1319592D03*
X389161Y1321177D03*
X391491Y1321927D03*
X392131Y1324821D03*
X396397Y1324591D03*
X394197Y1323091D03*
X396397Y1321691D03*
X400073Y1327653D03*
X403051Y1325373D03*
X394297Y1326091D03*
X392131Y1327721D03*
X396397Y1327491D03*
X400888Y1395508D03*
X392947Y1397827D03*
X390934Y1404085D03*
X401079Y1399208D03*
X400924Y1408227D03*
X400926Y1404707D03*
X392517Y1419015D03*
X400991Y1417264D03*
X390934Y1407605D03*
X390914Y1412991D03*
X403125Y1425008D03*
X390687Y1431713D03*
X390777Y1435152D03*
X394067Y1435323D03*
X401244Y1440773D03*
X396822Y1439340D03*
X396946Y1537632D03*
X396768Y1541810D03*
X404920Y1539362D03*
X396946Y1556810D03*
X391330Y1585155D03*
X404030Y1595390D03*
Y1591990D03*
X394360Y1616380D03*
X392550Y1618650D03*
X397406Y1633142D03*
X402590Y1618952D03*
X401740Y1648082D03*
X404240D03*
X404320Y1645452D03*
X401820D03*
X391563Y1640244D03*
X397406Y1636542D03*
X397400Y1641000D03*
X390180Y1668212D03*
X396824Y1673662D03*
X407970Y59612D03*
X407790Y62652D03*
X415800Y62665D03*
Y67465D03*
X419901Y117491D03*
X408284Y163662D03*
X420865Y215067D03*
X410996Y218834D03*
X420752Y239562D03*
X405139Y239908D03*
X417765Y252162D03*
X404985D03*
X417218Y291274D03*
X419920Y338162D03*
X416220Y364062D03*
X418704Y379201D03*
X416762Y367353D03*
X418540Y392163D03*
X416514Y407028D03*
X412720Y439362D03*
X417880Y461942D03*
X418520Y473562D03*
X419460Y1161570D03*
Y1153370D03*
Y1169597D03*
X406248Y1248997D03*
X408798Y1249057D03*
X408511Y1256866D03*
X406001Y1256896D03*
X406128Y1254167D03*
X408678Y1254227D03*
X406188Y1251567D03*
X419638Y1248967D03*
X419295Y1256851D03*
X419518Y1254137D03*
X419578Y1251537D03*
X419295Y1259351D03*
X408738Y1251627D03*
X408523Y1259373D03*
X406013Y1259403D03*
X419295Y1261851D03*
X419307Y1264358D03*
X419285Y1267188D03*
X408523Y1264373D03*
X406013Y1264403D03*
Y1261903D03*
X408523Y1261873D03*
X405895Y1267218D03*
X408445Y1267278D03*
X416629Y1321177D03*
X418959Y1321927D03*
X410225Y1329329D03*
X406225Y1328591D03*
X414435Y1330819D03*
X412963Y1328361D03*
X406225Y1331647D03*
X418320Y1383862D03*
X422320D03*
X414333Y1385292D03*
X410933Y1384648D03*
X414909Y1395658D03*
X408915Y1402606D03*
X411150Y1408163D03*
X410912Y1418177D03*
X408968Y1410427D03*
X411162Y1414126D03*
X416926Y1426471D03*
X412416Y1431645D03*
X419861Y1429718D03*
X419302Y1434700D03*
X422708Y1437560D03*
X410074Y1424993D03*
X416999Y1441908D03*
X413599D03*
X407625Y1552572D03*
X419820Y1555862D03*
X409140Y1566892D03*
X405000Y1566670D03*
X412600Y1601000D03*
X408600Y1607400D03*
X419780Y1602802D03*
X414406Y1624992D03*
Y1628392D03*
X405990Y1618952D03*
X416020Y1620862D03*
X412456Y1649838D03*
X417960Y1650072D03*
X410700Y1655310D03*
X409857Y1682767D03*
X421320Y1671699D03*
X410249Y1673082D03*
X427120Y59862D03*
X428500Y65016D03*
Y70016D03*
X435340Y122196D03*
X428889Y121515D03*
X428883Y131015D03*
X429780Y149373D03*
Y153477D03*
Y157466D03*
Y161466D03*
X433695Y209862D03*
X421200Y232562D03*
X423145Y227862D03*
X426490Y244262D03*
X429702Y290763D03*
X425720Y319492D03*
X432380Y346522D03*
X422420Y338162D03*
X431781Y379201D03*
X434006Y365203D03*
X433596Y391163D03*
X431920Y405288D03*
X428720Y439362D03*
X437720Y435362D03*
X431570Y435512D03*
X437520Y476337D03*
X431220Y496362D03*
X434343Y504233D03*
Y509733D03*
Y498733D03*
X431220Y507143D03*
Y512623D03*
Y501643D03*
X434343Y515233D03*
Y526233D03*
Y520733D03*
X431220Y518133D03*
Y523362D03*
X434620Y535762D03*
X434343Y542733D03*
X434320Y540153D03*
X434343Y547769D03*
Y552769D03*
X421960Y1161570D03*
Y1153370D03*
Y1169597D03*
X422148Y1248937D03*
X424698Y1248997D03*
X422088Y1251507D03*
X421805Y1256821D03*
X422028Y1254107D03*
X424458Y1256717D03*
X424578Y1254167D03*
X424638Y1251567D03*
X421805Y1259321D03*
X424398Y1259287D03*
X436068Y1248967D03*
X435828Y1256687D03*
X435948Y1254137D03*
X436008Y1251537D03*
X435768Y1259257D03*
X421805Y1261821D03*
X421817Y1264328D03*
X421795Y1267158D03*
X424345Y1267218D03*
X424380Y1264594D03*
X424388Y1261897D03*
X435715Y1267188D03*
X435720Y1264564D03*
X435708Y1261857D03*
X432063Y1317092D03*
Y1319592D03*
X421289Y1321177D03*
X423619Y1321927D03*
X428525Y1321691D03*
X426325Y1323091D03*
X424259Y1324821D03*
X428525Y1324591D03*
X432628Y1327845D03*
X435179Y1325373D03*
X424259Y1327721D03*
X426425Y1326091D03*
X428525Y1327491D03*
X426320Y1383862D03*
X430320D03*
X439030Y1383692D03*
X436780Y1387387D03*
X436467Y1391687D03*
X438458Y1402169D03*
X438645Y1426890D03*
X437299Y1436774D03*
X433539Y1430613D03*
X425030Y1434292D03*
X433897Y1434670D03*
X427546Y1443411D03*
X433954Y1439029D03*
X424146Y1443411D03*
X435396Y1551810D03*
X424820Y1552605D03*
X431620Y1541362D03*
X434430Y1567562D03*
X424570Y1579466D03*
X433350Y1579509D03*
X424800Y1616600D03*
X432200Y1607060D03*
X423180Y1602802D03*
X432500Y1613822D03*
X430015Y1626608D03*
X433670Y1639562D03*
X426728Y1636495D03*
X451418Y78782D03*
X446640Y104552D03*
X446746Y152662D03*
X453028Y154864D03*
X452500Y213362D03*
Y222362D03*
X452071Y254862D03*
X442265Y290939D03*
X439120Y314562D03*
X442220Y323362D03*
X448220Y323582D03*
Y319862D03*
X446000Y339362D03*
X455000Y340362D03*
X450500Y358862D03*
X443770Y371042D03*
X451062Y397262D03*
X447490Y409052D03*
X443300Y410962D03*
X447750Y414112D03*
X453020Y414262D03*
X449420Y424162D03*
X451520Y475837D03*
X442520Y476337D03*
X453680Y515072D03*
X451320Y533562D03*
X448276Y1161570D03*
X445776D03*
X443276D03*
X445776Y1153370D03*
X448276D03*
X443276D03*
X448276Y1170069D03*
X445776D03*
X443276D03*
X441128Y1248997D03*
X438578Y1248937D03*
X438518Y1251507D03*
X440858Y1256866D03*
X438348Y1256896D03*
X441008Y1254167D03*
X438458Y1254107D03*
X441068Y1251567D03*
X440870Y1259373D03*
X438360Y1259403D03*
X451642Y1256851D03*
X451878Y1254107D03*
X451642Y1259351D03*
X451938Y1251507D03*
X451998Y1248937D03*
X438360Y1261903D03*
X440870Y1261873D03*
Y1264373D03*
X438360Y1264403D03*
X438225Y1267158D03*
X440775Y1267218D03*
X451642Y1261851D03*
X451654Y1264358D03*
X451645Y1267158D03*
X448757Y1321177D03*
X451087Y1321927D03*
X442353Y1329329D03*
X438353Y1328591D03*
X446563Y1330819D03*
X445091Y1328361D03*
X438353Y1331647D03*
X443842Y1389106D03*
X448020Y1391862D03*
X443424Y1397869D03*
X439391Y1398266D03*
X441369Y1394260D03*
X451048Y1404914D03*
X447110Y1403812D03*
X448114Y1396812D03*
X445339Y1415731D03*
X446230Y1407722D03*
X445230Y1411719D03*
X445723Y1419730D03*
X443850Y1423404D03*
X451080Y1433740D03*
X440164Y1433982D03*
X445294Y1430415D03*
X443715Y1436052D03*
X452520Y1564862D03*
X448328Y1582476D03*
X446020Y1570412D03*
X452020Y1580412D03*
X448740Y1574862D03*
X444458Y1602654D03*
X437383Y1602629D03*
X454661Y1609235D03*
X442974Y1615615D03*
X448181Y1614401D03*
X443800Y1610712D03*
X449940Y1647412D03*
X447090Y1647472D03*
X444940Y1641842D03*
X438340Y1652266D03*
X441740D03*
X462620Y120948D03*
X462320Y115948D03*
X453346Y149864D03*
X461900Y215244D03*
X466300Y217803D03*
X461900Y222921D03*
X466300Y225480D03*
X468323Y254562D03*
X465236Y296973D03*
X461736Y301098D03*
Y306098D03*
X463198Y311587D03*
X465000Y340362D03*
X456660Y359172D03*
X460800Y358962D03*
X467211Y371902D03*
X459220Y393762D03*
X463500Y383562D03*
X455720Y404762D03*
X458600Y414262D03*
X465421Y428078D03*
X456520Y476337D03*
X461520D03*
X453727Y518036D03*
X457456Y522516D03*
X470880Y572692D03*
X467130Y600122D03*
X456818Y1256687D03*
X454388Y1254077D03*
X454152Y1256821D03*
X456998Y1251537D03*
X456758Y1259257D03*
X454152Y1259321D03*
X468258Y1249107D03*
X468018Y1256827D03*
X468138Y1254277D03*
X468198Y1251677D03*
X467958Y1259397D03*
X457058Y1248967D03*
X454508Y1248907D03*
X454448Y1251477D03*
X456938Y1254137D03*
X456705Y1267188D03*
X454155Y1267128D03*
X456748Y1261867D03*
X456740Y1264564D03*
X454152Y1261821D03*
X454164Y1264328D03*
X467905Y1267328D03*
X467910Y1264704D03*
X467898Y1261997D03*
X464191Y1317092D03*
Y1319592D03*
X453417Y1321177D03*
X455747Y1321927D03*
X458453Y1323091D03*
X460653Y1321691D03*
Y1324591D03*
X456387Y1324821D03*
X464191Y1327793D03*
X467307Y1325373D03*
X458553Y1326091D03*
X460653Y1327491D03*
X456387Y1327721D03*
X459550Y1401348D03*
X465947Y1398355D03*
X459321Y1393009D03*
Y1396409D03*
X458441Y1414893D03*
X468880Y1418400D03*
X456619Y1431189D03*
X463140Y1451562D03*
X463207Y1547543D03*
X453595Y1551470D03*
X459520Y1546962D03*
X466905Y1567847D03*
X467400Y1556700D03*
X460020Y1580412D03*
X457220Y1584020D03*
X466520Y1574862D03*
X457220Y1603562D03*
X460200Y1589900D03*
X456510Y1614472D03*
X469488Y1607362D03*
X460910Y1629172D03*
Y1625772D03*
X455681Y1622492D03*
X458978Y1634481D03*
X463344Y1637622D03*
X469580Y1640272D03*
X468040Y1651657D03*
X466460Y1672332D03*
X466180Y1678392D03*
X481880Y147069D03*
X481246Y161364D03*
X476220Y158772D03*
X470900Y234787D03*
X486800Y259162D03*
X478500Y258862D03*
X474736Y302098D03*
X478995Y293787D03*
X479736Y303598D03*
Y308598D03*
X486720Y360862D03*
X482720D03*
X475508Y359266D03*
X476585Y370727D03*
X472720Y391362D03*
X485020Y414162D03*
X471920Y416687D03*
X474169Y476196D03*
X479169D03*
X474044Y503725D03*
X478510Y602942D03*
X472960Y602152D03*
X482780Y607012D03*
X473698Y1161570D03*
X471198D03*
X473698Y1153370D03*
X471198D03*
X473698Y1170070D03*
X471198D03*
X473318Y1249137D03*
X470768Y1249077D03*
X473035Y1256866D03*
X470525Y1256896D03*
X473198Y1254307D03*
X470648Y1254247D03*
X473258Y1251707D03*
X470708Y1251647D03*
X473047Y1259373D03*
X470537Y1259403D03*
X484098Y1248997D03*
X483819Y1256851D03*
X483978Y1254167D03*
X484038Y1251567D03*
X483819Y1259351D03*
X472965Y1267358D03*
X470415Y1267298D03*
X470537Y1261903D03*
X473047Y1261873D03*
Y1264373D03*
X470537Y1264403D03*
X483819Y1261851D03*
X483831Y1264358D03*
X483745Y1267218D03*
X480885Y1321177D03*
X485545D03*
X483215Y1321927D03*
X474481Y1329329D03*
X470481Y1328591D03*
X478691Y1330819D03*
X477219Y1328361D03*
X470481Y1331647D03*
X483560Y1401712D03*
X474983Y1400385D03*
X485141Y1405430D03*
X481997Y1409955D03*
X470987Y1409965D03*
X484921Y1413246D03*
X470890Y1435838D03*
X478449Y1448158D03*
X482633Y1449091D03*
Y1446091D03*
X470111Y1548269D03*
X483348Y1548062D03*
X475110Y1548112D03*
X477968Y1548122D03*
X480848Y1548120D03*
X486210Y1547960D03*
X482400Y1558320D03*
X472220Y1626732D03*
X472210Y1622735D03*
X477905Y1663242D03*
Y1659242D03*
X475150Y1654302D03*
X477835Y1677462D03*
X488748Y72264D03*
X499580Y78442D03*
X489730Y76132D03*
X498330Y96112D03*
X498730Y128592D03*
X498700Y212685D03*
Y220362D03*
X503100Y215244D03*
X500925Y231262D03*
X503100Y222921D03*
X496028Y258590D03*
X499096Y252462D03*
X489091Y293787D03*
X498636Y296273D03*
X495136Y300398D03*
Y305398D03*
X486861D03*
X495036Y310398D03*
X486710Y313582D03*
X492150Y336810D03*
X498720Y360862D03*
X490720D03*
Y368862D03*
X489520Y411862D03*
X494020Y414262D03*
X492970Y409252D03*
X502070Y427937D03*
X488169Y475696D03*
X493169Y476196D03*
X498169D03*
X486500Y556212D03*
X491043Y550447D03*
X486608Y1248967D03*
X489158Y1249027D03*
X486329Y1256821D03*
X486488Y1254137D03*
X488918Y1256747D03*
X489038Y1254197D03*
X486548Y1251537D03*
X489098Y1251597D03*
X486329Y1259321D03*
X488858Y1259317D03*
X500228Y1259237D03*
X486329Y1261821D03*
X486341Y1264328D03*
X488840Y1264624D03*
X488848Y1261927D03*
X488805Y1267248D03*
X486255Y1267188D03*
X500138Y1269637D03*
X500150Y1272344D03*
X500198Y1267037D03*
Y1264467D03*
X500168Y1261807D03*
X500150Y1275224D03*
Y1278104D03*
X487875Y1321927D03*
X492878Y1322618D03*
X490678Y1324018D03*
X496319Y1330493D03*
Y1333043D03*
X499435Y1338799D03*
X488539Y1325772D03*
X492878Y1325518D03*
X488539Y1328672D03*
X490778Y1327018D03*
X492878Y1328418D03*
X496319Y1341264D03*
X491089Y1446091D03*
Y1449091D03*
X499489D03*
Y1446091D03*
X489230Y1643592D03*
X516236Y92948D03*
X513586Y92799D03*
X510600Y92782D03*
X517290Y104252D03*
X513700Y117862D03*
X510900Y111962D03*
X503270Y128592D03*
X507320D03*
X515690Y147852D03*
X519010Y147912D03*
X518186Y139821D03*
X519236Y202404D03*
X518670Y219192D03*
X512500Y209862D03*
Y223362D03*
X508500Y232862D03*
X508000Y241862D03*
X508502Y298813D03*
X503040Y287928D03*
X508500Y303362D03*
X508136Y309398D03*
X502239Y315404D03*
X507160Y332452D03*
X510720Y360862D03*
X514720D03*
X502720D03*
X506720Y368862D03*
X509720Y390362D03*
X513720D03*
X505720Y398362D03*
X502260Y397742D03*
X511320Y437962D03*
X513444Y457522D03*
X516970Y592942D03*
X504135Y615612D03*
X505398Y1259377D03*
X502858Y1259257D03*
X502718Y1271417D03*
X505218Y1271447D03*
X505290Y1267254D03*
X505338Y1261947D03*
X505278Y1264547D03*
X502750Y1267134D03*
X502798Y1261827D03*
X502738Y1264427D03*
X502718Y1274114D03*
X505218Y1274144D03*
X515898Y1271447D03*
X515950Y1274144D03*
X505220Y1280054D03*
X502718Y1276994D03*
X505218Y1277024D03*
X502680Y1280054D03*
X515960D03*
X515950Y1277024D03*
X513013Y1334603D03*
X517673D03*
X515343Y1335353D03*
X506609Y1342755D03*
X502609Y1342017D03*
X510819Y1344245D03*
X509347Y1341787D03*
X502609Y1345073D03*
X509246Y1420002D03*
X505777Y1425579D03*
X507964Y1448979D03*
Y1445979D03*
X529720Y30792D03*
X519764Y40328D03*
X523164D03*
X529720Y43054D03*
X534720Y42922D03*
X533915Y59822D03*
X519742Y71436D03*
X523142D03*
X523978Y59074D03*
X529078Y59282D03*
X527520Y69633D03*
X528590Y72922D03*
X518450Y101602D03*
X527310Y98147D03*
Y94747D03*
X527160Y129243D03*
X523220Y170362D03*
X534765Y161067D03*
X526920Y161362D03*
X529507Y202448D03*
X522337Y202404D03*
X531298Y284280D03*
X536420Y309422D03*
X523682Y307541D03*
Y304541D03*
X526980Y322582D03*
X521820Y336762D03*
X531720Y360862D03*
X527720D03*
X523670Y368892D03*
X525720Y390362D03*
X529720D03*
X521720Y398362D03*
X532650Y446396D03*
Y442376D03*
X521885Y452442D03*
X532650Y450330D03*
Y454270D03*
X533410Y475932D03*
X525820Y473662D03*
X524425Y489112D03*
Y495112D03*
X519520Y484027D03*
X522805Y482155D03*
X531258Y505473D03*
X521561Y505969D03*
Y500469D03*
Y511469D03*
X524220Y505862D03*
Y500362D03*
Y511362D03*
X521561Y516969D03*
Y522469D03*
X536000Y520362D03*
X524220Y516862D03*
X524720Y525293D03*
Y519743D03*
X521561Y527969D03*
Y539819D03*
X524920D03*
X524820Y545319D03*
X523699Y571545D03*
X528500Y566722D03*
X523890Y592387D03*
X531472Y579750D03*
X521118Y1273097D03*
X518488Y1271477D03*
X521058Y1275667D03*
X518490Y1274144D03*
X521058Y1278277D03*
X521020Y1280974D03*
X518500Y1280054D03*
X518490Y1277024D03*
X530398Y1288557D03*
X530548Y1283377D03*
X530428Y1285947D03*
X530410Y1291254D03*
X532558Y1289967D03*
X532618Y1287367D03*
X532678Y1284797D03*
X530450Y1297014D03*
Y1294134D03*
X532570Y1295554D03*
Y1298434D03*
Y1292674D03*
X525008Y1336287D03*
X520643Y1338247D03*
X522809Y1339517D03*
X522783Y1334882D03*
X520643Y1341147D03*
X520003Y1335353D03*
X528447Y1353316D03*
Y1355816D03*
X524892Y1341462D03*
X522818Y1342930D03*
X528929Y1364212D03*
X531563Y1361597D03*
X539720Y30792D03*
X534720D03*
X542050Y47452D03*
X539720Y42862D03*
X550971Y42902D03*
X544720Y42892D03*
X548609Y48082D03*
X537315Y59822D03*
X541002Y71436D03*
X544402D03*
X548070Y79372D03*
X542460Y99172D03*
X539475Y118772D03*
X547395Y147302D03*
X543083Y146338D03*
X540460Y200392D03*
X544390Y236512D03*
X550390Y231742D03*
X548390Y236512D03*
X546390Y231742D03*
X542050Y231722D03*
X539639Y271972D03*
X539830Y274912D03*
X537720Y278212D03*
X547420Y306862D03*
X544920D03*
X549220Y339687D03*
X535720Y360862D03*
X546758Y360502D03*
X547810Y414472D03*
X549670Y419892D03*
X542870Y438320D03*
X548464Y456534D03*
X548780Y475932D03*
X548550Y480382D03*
X546210Y519642D03*
X541820Y575130D03*
X541722Y568054D03*
X537730Y577440D03*
X547020Y590332D03*
X550320Y583362D03*
X536626Y590500D03*
X537560Y598102D03*
X537648Y1290037D03*
X535058Y1290007D03*
X535148Y1287397D03*
X543660Y1302934D03*
X541100D03*
X538560D03*
X535110Y1292704D03*
Y1295584D03*
Y1298464D03*
X537650Y1292704D03*
X540210D03*
X537650Y1298464D03*
Y1295584D03*
X540210Y1298464D03*
Y1295584D03*
X536020Y1302904D03*
X545141Y1357401D03*
X549801D03*
X538737Y1365553D03*
X534737Y1364815D03*
X542947Y1367043D03*
X541475Y1364585D03*
X534737Y1367871D03*
X547471Y1358151D03*
X563482Y40826D03*
X554720Y32862D03*
X565184Y47982D03*
X558058Y46352D03*
X554983Y45312D03*
X553650Y48842D03*
X555175Y71436D03*
X558575D03*
X551470Y79372D03*
X567865Y92656D03*
X559000Y102862D03*
X561000Y98862D03*
X552395Y134340D03*
X566500Y125097D03*
X551231Y122671D03*
X564890Y142173D03*
X555220Y164787D03*
X555545Y156462D03*
X555195Y184862D03*
Y171862D03*
X554872Y196635D03*
X559400Y201162D03*
X557248Y198909D03*
X564600Y202662D03*
X552489Y212022D03*
X553402Y231292D03*
X552089Y253202D03*
Y257202D03*
X562461Y272161D03*
X561324Y301149D03*
X566730Y300992D03*
X555520Y309827D03*
X563790Y331846D03*
X561290D03*
X558790D03*
X562200Y419412D03*
X559300Y414112D03*
X559730Y434772D03*
X557829Y454479D03*
X558220Y459362D03*
X563281Y543113D03*
X563700Y538477D03*
X560640Y540613D03*
X566140Y554972D03*
Y551472D03*
X559927Y548457D03*
X556820Y570462D03*
X557430Y583572D03*
X566510Y1352217D03*
X554837Y1359315D03*
X557037Y1363715D03*
Y1357915D03*
Y1360815D03*
X554937Y1362315D03*
X552771Y1361045D03*
Y1363945D03*
X552131Y1358151D03*
X555057Y1449395D03*
X572500Y32862D03*
X568500D03*
X581500Y41862D03*
X573190Y42912D03*
X567507Y45869D03*
X575330Y47672D03*
X570208Y47982D03*
X579930Y72052D03*
X577300Y66682D03*
X577880Y75442D03*
X570150Y102862D03*
X579080Y119402D03*
X573360Y140532D03*
X573115Y161232D03*
X569470Y171702D03*
X581120Y155062D03*
X568245Y167112D03*
X579481Y198378D03*
X579170Y190092D03*
X579481Y194378D03*
Y206378D03*
X578450Y218562D03*
X579245Y221362D03*
X567730Y225362D03*
X578390D03*
X567730Y221362D03*
X581755Y236978D03*
X575359Y265132D03*
X582510Y296657D03*
X577676Y300268D03*
X577480Y303822D03*
X582510Y304052D03*
Y311571D03*
X570440Y331930D03*
X567630Y331958D03*
X574800Y322462D03*
X571830Y348772D03*
X572360Y351962D03*
X571720Y381862D03*
X575050Y383602D03*
X577720Y381862D03*
X574491Y376549D03*
X580370Y383670D03*
X581090Y426970D03*
X571930Y421232D03*
X571110Y442656D03*
X569490Y437600D03*
X571110Y446706D03*
X567320Y454962D03*
Y459962D03*
Y457462D03*
X577220Y449462D03*
X578920Y466462D03*
X583045Y488212D03*
X583220Y493212D03*
X568840Y501046D03*
X584173Y498422D03*
X568520Y504162D03*
Y506662D03*
X577470Y505592D03*
X578925Y516846D03*
X571627Y548124D03*
X569050Y578292D03*
X572057Y577242D03*
X571555Y1352487D03*
X570645Y1361358D03*
X576220Y1423862D03*
X571620Y1424492D03*
X584950Y54842D03*
X586260Y52222D03*
X599800Y43152D03*
X597955Y48047D03*
X593369Y45682D03*
X586600Y60602D03*
X590680Y83591D03*
X592307Y94262D03*
X597287D03*
X594720Y97220D03*
X588245Y132142D03*
X598410Y124102D03*
X598390Y126802D03*
X589690Y161732D03*
X592220Y173862D03*
X596795Y179287D03*
X590281Y180698D03*
X599720Y184887D03*
X593220D03*
X584795Y233362D03*
X591310Y219582D03*
X592220Y249362D03*
X595415Y246515D03*
X591727Y285862D03*
X593763Y293999D03*
X588850Y291622D03*
X599620Y314762D03*
X595520Y314862D03*
X583820Y314662D03*
X590820Y330962D03*
X590720Y327862D03*
Y324582D03*
X590470Y319192D03*
X593120Y342782D03*
X583685Y363271D03*
X586185D03*
X586070Y352302D03*
X591839Y426112D03*
X595380Y416660D03*
X591720Y433937D03*
X595520Y439762D03*
X597220Y458688D03*
X599080Y448062D03*
X584100Y477952D03*
X592520Y467662D03*
X590210Y484132D03*
X599645Y479862D03*
X598661Y486922D03*
X587100Y493842D03*
X592400Y479162D03*
X591070Y504900D03*
X594090Y501957D03*
X587100Y496342D03*
X591425Y522337D03*
X591500Y516862D03*
X596880Y534812D03*
X592340Y744624D03*
X598693Y742072D03*
X611810Y34400D03*
X612822Y43232D03*
X606880Y44682D03*
X614400Y46012D03*
X603063Y48023D03*
X606020Y84562D03*
X615220Y76862D03*
X615170Y73812D03*
X601220Y73862D03*
Y76862D03*
X603720Y98362D03*
X608620Y94162D03*
X617585Y97257D03*
X613020Y94162D03*
X617409D03*
X603880Y93902D03*
X600220Y96862D03*
X614384Y119342D03*
X606040Y153432D03*
X606190Y144002D03*
X602580Y151052D03*
X603019Y146399D03*
X615573Y179484D03*
X615572Y176442D03*
X611381Y200378D03*
X613970Y188752D03*
X611381Y209878D03*
X614200Y265792D03*
X605350Y293092D03*
X605870Y298172D03*
X605560Y303372D03*
X607590Y314732D03*
X609040Y317282D03*
X615635Y317637D03*
X614130Y328762D03*
X605305Y331162D03*
X615180Y336812D03*
X605898Y372984D03*
X609690Y402812D03*
X605220Y416362D03*
X610720Y436362D03*
X600800Y430900D03*
X614220Y436362D03*
X610720Y442862D03*
X614220D03*
Y447862D03*
X602910Y461862D03*
X610720Y457862D03*
X614220D03*
X610720Y452862D03*
X604360Y452120D03*
X614220Y467862D03*
Y472862D03*
Y477862D03*
X605469Y467562D03*
X610720Y462862D03*
X614220D03*
X601220Y486922D03*
X600645Y504362D03*
X606200Y510862D03*
X611870Y512560D03*
X606220Y517762D03*
X607328Y537481D03*
X610797Y537528D03*
X607720Y550862D03*
X610720D03*
X613220Y654662D03*
X603276Y741375D03*
X600460Y744912D03*
X613047Y741492D03*
X602768Y758385D03*
X616675Y31777D03*
X624633Y49193D03*
X629820Y42562D03*
Y45062D03*
X619562Y49193D03*
X624140Y46672D03*
X622271Y44782D03*
X629000Y67362D03*
X628590Y58622D03*
X622271Y57952D03*
X623300Y95762D03*
X620540Y100112D03*
X632300Y104472D03*
X626699Y119182D03*
X630951D03*
X631290Y153702D03*
X615970Y161522D03*
X628195Y175914D03*
X628194Y172872D03*
X617370Y188752D03*
X630040D03*
X626640D03*
X628730Y216472D03*
X631730D03*
X628730Y220472D03*
Y224472D03*
X631730Y220472D03*
Y224472D03*
X622730Y230362D03*
X630795Y236862D03*
X618470Y265732D03*
X629564Y253127D03*
X621060Y271066D03*
X633150Y301457D03*
X627950Y298897D03*
X627600Y309134D03*
X632143Y306575D03*
X630220Y314362D03*
X623365Y316742D03*
X631146Y317768D03*
X619474Y331162D03*
X619100Y374638D03*
X621720Y373362D03*
X622490Y402162D03*
X628500Y402362D03*
X624220Y411362D03*
X629220D03*
X623220Y426362D03*
X625500Y421362D03*
X629220D03*
Y426362D03*
X628900Y431050D03*
X625620Y447862D03*
X625900Y431050D03*
X625620Y442862D03*
X629220D03*
X622220D03*
X617220Y436362D03*
X622220Y452862D03*
Y447862D03*
X629220Y457862D03*
X626400Y462812D03*
X625620Y457862D03*
X622220D03*
X629220Y452862D03*
X625620D03*
X629220Y447862D03*
X626390Y467882D03*
X626210Y478002D03*
X626310Y472902D03*
X629220Y462862D03*
X622220D03*
X622520Y467862D03*
X629220Y487310D03*
X622860D03*
X626720Y482880D03*
X623670Y507862D03*
X629480Y508862D03*
X633000Y508700D03*
X629920Y516652D03*
X623000Y546900D03*
X629220Y643462D03*
X626720D03*
X617252Y739354D03*
X623497Y748235D03*
X626017Y745083D03*
X620870Y762072D03*
X617940Y763552D03*
X630417Y757135D03*
X628970Y1670880D03*
X637220Y31462D03*
X643880Y42142D03*
X647447Y46322D03*
X641200Y46762D03*
X638500Y57362D03*
X635000D03*
X637000Y68142D03*
X634500Y73422D03*
X645330Y77132D03*
Y72972D03*
X640220Y85542D03*
X634690D03*
X647220Y96929D03*
X639901Y103462D03*
X640000Y108542D03*
X639970Y113892D03*
X640130Y166362D03*
X643170Y171362D03*
X649870Y181942D03*
X645263Y235689D03*
X640295Y234237D03*
X645109Y249202D03*
Y260202D03*
X643800Y294327D03*
Y298297D03*
Y306547D03*
Y302247D03*
X645990Y314482D03*
X643800Y310962D03*
X633350Y314362D03*
X647100Y357372D03*
X636075Y389862D03*
X649075Y389937D03*
X632620Y389862D03*
X645925Y389937D03*
X638700Y400962D03*
X647700Y399162D03*
X643500Y400962D03*
X643940Y411482D03*
X637220Y411362D03*
X644220Y426362D03*
X640720Y418862D03*
X644220Y421362D03*
X637220Y416362D03*
Y426362D03*
X637195Y421362D03*
X647420Y434162D03*
X640720Y431362D03*
X644000Y438862D03*
X644220Y431362D03*
X638250Y439250D03*
X637220Y431362D03*
X644220Y452862D03*
X640820Y457902D03*
X637220Y452862D03*
X640720D03*
X640920Y447862D03*
X644220D03*
X637195Y457862D03*
X637220Y467862D03*
Y472862D03*
Y477862D03*
X644220D03*
Y462862D03*
X641235Y477377D03*
X640798Y472934D03*
X637220Y462862D03*
X640820Y467862D03*
X640620Y483422D03*
X642580Y508172D03*
X645220Y504362D03*
X646815Y517974D03*
X648296Y528255D03*
X637020Y522362D03*
X642630Y517870D03*
X640130D03*
X633147Y758595D03*
X647725Y1643719D03*
X643725Y1643467D03*
X648225Y1658482D03*
X642725Y1658562D03*
X635410Y1664220D03*
X637540Y1669480D03*
X636702Y1677610D03*
X645725Y1691182D03*
X640725Y1691452D03*
X650725Y1690682D03*
X646225Y1708169D03*
X642225Y1708457D03*
X648220Y1716912D03*
X636160Y1710662D03*
X639745Y1722362D03*
Y1718362D03*
X648220Y1722921D03*
X651943Y33535D03*
X656439Y47264D03*
X659839D03*
X663543Y43328D03*
X656950Y59012D03*
X651680Y73812D03*
X656500Y69662D03*
X661587D03*
X661600Y75562D03*
X657165Y79131D03*
X656426Y75431D03*
X652320Y123362D03*
X662498Y124960D03*
X650790Y149871D03*
Y140699D03*
X662880Y149912D03*
Y146912D03*
X651730Y177212D03*
X662560Y214152D03*
X662780Y210362D03*
Y205362D03*
Y207862D03*
X659880Y210762D03*
Y205762D03*
Y208262D03*
X650705Y270947D03*
X662891Y357442D03*
X662680Y354362D03*
X651520Y378662D03*
X658720Y399862D03*
X652000Y402362D03*
X653100Y407862D03*
X655820Y452662D03*
X655800Y461432D03*
X652195Y457862D03*
X655820Y467662D03*
X663000Y489500D03*
X663014Y493860D03*
X655220Y486862D03*
X661865Y505334D03*
X663720Y523806D03*
X665990Y517131D03*
X661220Y526862D03*
X650794Y515039D03*
X652577Y1000775D03*
X653690Y1392362D03*
X653761Y1396300D03*
X663187Y1395170D03*
Y1397720D03*
X666303Y1403476D03*
X663687Y1407279D03*
X654540Y1427605D03*
Y1424205D03*
X661100Y1451012D03*
X662660Y1548120D03*
X663410Y1553982D03*
X664590Y1631620D03*
X663097Y1642667D03*
X651725Y1643397D03*
X656725Y1660769D03*
X663118Y1655557D03*
X663043Y1651557D03*
X663145Y1672862D03*
Y1668862D03*
X653420Y1698662D03*
X663645Y1722862D03*
X680200Y39062D03*
X677560Y40572D03*
X672250Y40812D03*
X666943Y43328D03*
X682290Y46822D03*
X670612Y47264D03*
X674012D03*
X674035Y74522D03*
X678050Y58157D03*
X673987Y87662D03*
X677820Y89462D03*
X680578Y75992D03*
X674540Y80652D03*
X670800Y85932D03*
X667940Y80142D03*
X671320Y91192D03*
X677790Y104880D03*
X673720Y110362D03*
X674145Y113487D03*
X677978Y119668D03*
Y115668D03*
X675560Y117120D03*
X668300Y132400D03*
X665650Y147692D03*
X673713Y237725D03*
X674731Y359924D03*
X680600Y364282D03*
X683100Y369550D03*
X673220Y388362D03*
X675295Y399862D03*
X670720D03*
X668695Y408362D03*
Y404262D03*
X665870Y433942D03*
X675220Y508862D03*
X680220Y495887D03*
X670220Y503837D03*
X680220Y508862D03*
X675220Y521862D03*
X670720D03*
Y516862D03*
X680220Y530362D03*
X673340Y530922D03*
X673617Y744735D03*
X669700Y746626D03*
X677887Y742121D03*
X669778Y759929D03*
X670037Y1336396D03*
X664987D03*
X667487D03*
X664987Y1338896D03*
X667487D03*
X670037D03*
Y1333896D03*
X664987D03*
X667487D03*
X664987Y1348896D03*
X667487D03*
X664987Y1346396D03*
X667487D03*
X664987Y1343896D03*
Y1341396D03*
X667487D03*
Y1343896D03*
X670037Y1341396D03*
Y1343896D03*
Y1346396D03*
Y1348896D03*
X679881Y1399280D03*
X673477Y1409386D03*
X669477Y1406694D03*
X677619Y1408887D03*
X675876Y1406619D03*
X669477Y1409415D03*
X674149Y1434149D03*
X671149D03*
X668649D03*
X674149Y1426149D03*
Y1431149D03*
Y1428649D03*
X671149Y1426149D03*
X668649D03*
X671149Y1431149D03*
X668649Y1428649D03*
Y1431149D03*
X671149Y1428649D03*
X677319Y1428359D03*
Y1433359D03*
Y1430859D03*
X682160Y1548040D03*
X665410Y1548180D03*
X679207Y1560482D03*
X678877Y1566798D03*
X678621Y1571072D03*
X678610Y1582154D03*
X666560Y1581000D03*
X678619Y1579070D03*
X666600Y1584900D03*
X678900Y1595400D03*
X678771Y1585945D03*
X666700Y1595500D03*
X678900Y1589800D03*
X666700Y1591900D03*
X678900Y1592600D03*
X666700Y1588500D03*
X679640Y1617520D03*
Y1614000D03*
X679270Y1604040D03*
X675710Y1620320D03*
X673420Y1650057D03*
X671290Y1646320D03*
X668695Y1662235D03*
X671610Y1673792D03*
X671620Y1668303D03*
X677940Y1670110D03*
X678490Y1695660D03*
X674195Y1712362D03*
X675120Y1716242D03*
X674195Y1728362D03*
X672270Y1721612D03*
X687120Y39632D03*
X692289Y40633D03*
X689940Y38952D03*
X696800Y42108D03*
X696838Y47940D03*
X683440Y42832D03*
X687344Y46940D03*
X692389Y46439D03*
X694751Y70212D03*
X690027Y70142D03*
X685780Y70022D03*
X699475Y69982D03*
X685968Y58157D03*
X694400D03*
X681980D03*
X690510Y59132D03*
X696700Y72462D03*
X692389Y72692D03*
X687664Y73202D03*
X696370Y78512D03*
X696727Y81552D03*
Y84052D03*
X681053Y104668D03*
X695720Y102162D03*
X694220Y104862D03*
X688019Y109845D03*
X687030Y113090D03*
X687034Y115896D03*
X697615Y123697D03*
X687238Y171071D03*
X685600Y364282D03*
X690600D03*
X695600D03*
X683500Y381200D03*
X685210Y388852D03*
X694920Y388797D03*
X687500Y399402D03*
X692330Y388751D03*
X685220Y391652D03*
X692402Y391250D03*
X695220Y399862D03*
X685270Y408362D03*
Y404262D03*
X692400Y404682D03*
X683320Y490662D03*
X685220Y495887D03*
X690580Y482992D03*
X694510Y482942D03*
X686120Y481862D03*
X695220Y495887D03*
X690220D03*
X695220Y508862D03*
X685220D03*
X690220Y506362D03*
X685220Y503837D03*
X690220Y508882D03*
X690330Y503530D03*
X695257Y503847D03*
X695220Y516852D03*
X685220D03*
X690220Y519662D03*
X695220D03*
X689720Y530862D03*
X695220Y530662D03*
X683457Y745175D03*
X696810Y1300162D03*
X692280Y1302532D03*
X684555Y1338896D03*
X689605Y1336396D03*
Y1338896D03*
X687105Y1336396D03*
X684555D03*
X687105Y1338896D03*
X689605Y1333896D03*
X687105D03*
X684555D03*
X689605Y1348896D03*
X687105D03*
X689605Y1346396D03*
X687105D03*
X684555Y1341396D03*
Y1343896D03*
Y1346396D03*
Y1348896D03*
X689605Y1341396D03*
Y1343896D03*
X687105Y1341396D03*
Y1343896D03*
X684541Y1399280D03*
X682211Y1400030D03*
X686871D03*
X691777Y1405594D03*
Y1399794D03*
X689577Y1401194D03*
X687511Y1402924D03*
X691777Y1402694D03*
X689677Y1404194D03*
X687511Y1405824D03*
X694596Y1396198D03*
X694129Y1420283D03*
X696754Y1419809D03*
X691129Y1420283D03*
X681899Y1434049D03*
Y1426049D03*
Y1431049D03*
Y1428549D03*
X694129Y1423303D03*
X691129D03*
X696694Y1427949D03*
Y1425449D03*
Y1430449D03*
X696784Y1422614D03*
X683930Y1552562D03*
Y1555062D03*
Y1557562D03*
X692100Y1567190D03*
X692026Y1580490D03*
X697197Y1640667D03*
X697122Y1636667D03*
X689200Y1648843D03*
X686220Y1640667D03*
X697595Y1666862D03*
X687045Y1673362D03*
X706370Y46782D03*
X701838Y42202D03*
Y47940D03*
X703900Y72112D03*
X701400D03*
X713000Y69662D03*
X697720Y58162D03*
X710200Y69662D03*
X706867Y58197D03*
X703100Y58157D03*
X712500Y79862D03*
X710486Y77695D03*
X700500Y74862D03*
X698710Y86035D03*
X705390Y85792D03*
X703000Y84862D03*
X706720Y100462D03*
X699220Y102162D03*
X702720D03*
X701220Y104862D03*
X697720D03*
X712733Y117488D03*
Y114588D03*
X712290Y106722D03*
X712340Y128093D03*
X700600Y125309D03*
X707008Y125804D03*
X705800Y167788D03*
Y171188D03*
X704770Y182999D03*
Y179599D03*
Y194810D03*
Y191410D03*
Y218432D03*
Y206621D03*
Y215032D03*
Y203221D03*
X700600Y364282D03*
X705600D03*
X710600D03*
X709000Y354000D03*
X715600Y363900D03*
X705700Y361400D03*
X709400Y378200D03*
X713220Y378362D03*
X711200Y396500D03*
X707220Y399362D03*
X709160Y386730D03*
X713220Y388362D03*
X707400Y396200D03*
X713220Y399862D03*
X705195Y408362D03*
Y404262D03*
X705780Y411022D03*
X712770Y406822D03*
X705720Y488862D03*
X703220Y490362D03*
X705720Y484862D03*
X711220Y503842D03*
X705220D03*
Y508862D03*
X711220Y508882D03*
X710720Y521362D03*
X705220D03*
X701757Y521324D03*
X705220Y530362D03*
X710940Y591172D03*
X698602Y580536D03*
X705240Y594020D03*
X702740D03*
X712060Y638542D03*
X708680Y638812D03*
X708310Y646032D03*
X704320Y645262D03*
X704000Y740862D03*
X700500Y745862D03*
X703545Y745907D03*
X711720Y1286162D03*
X707720Y1290162D03*
X705720Y1286662D03*
X704795Y1294559D03*
X707320Y1301162D03*
X708137Y1336396D03*
Y1338896D03*
X703087Y1336396D03*
X705587D03*
Y1338896D03*
X703087D03*
X708137Y1333896D03*
X705587D03*
X703087D03*
Y1346396D03*
X705587D03*
X703087Y1348896D03*
X705587D03*
X708137Y1341396D03*
Y1343896D03*
X705587Y1341396D03*
X703087D03*
Y1343896D03*
X705587D03*
X708137Y1348896D03*
Y1346396D03*
X701330Y1395195D03*
Y1397695D03*
X704446Y1403476D03*
X701830Y1407326D03*
X711620Y1409386D03*
X707620Y1406694D03*
Y1409660D03*
X699754Y1419809D03*
X699694Y1427949D03*
Y1425449D03*
Y1430449D03*
X699784Y1422614D03*
X712222Y1570703D03*
X702112Y1571683D03*
Y1575683D03*
Y1579683D03*
X711102Y1575683D03*
X714162Y1574333D03*
X713052Y1579683D03*
X712582Y1584843D03*
X704497Y1598927D03*
X702112Y1587683D03*
Y1591683D03*
X713102Y1601307D03*
X715775Y1599024D03*
X714380Y1589960D03*
X702112Y1595683D03*
X712512Y1596338D03*
X711350Y1590720D03*
X711780Y1614590D03*
X704370Y1604580D03*
X706103Y1617107D03*
X708857Y1613462D03*
X710570Y1629890D03*
X708830Y1623115D03*
X705516Y1620296D03*
X710540Y1636070D03*
X708999Y1646762D03*
X703719Y1646768D03*
X697595Y1662862D03*
X700460Y1660918D03*
X709678Y1658485D03*
X697730Y1677460D03*
X704759Y1677001D03*
X723041Y-13200D03*
Y-9800D03*
X724620Y40062D03*
X728720Y43562D03*
X719820Y45862D03*
X717320Y44062D03*
X729293Y58062D03*
X724644Y58362D03*
X719949Y58862D03*
X715990Y69662D03*
X725740Y69580D03*
X721990Y69762D03*
X718900Y69662D03*
X727700Y60562D03*
X728591Y71960D03*
X722415Y77862D03*
X718425Y77882D03*
X728090Y75132D03*
X719100Y85262D03*
X727518Y90984D03*
X715933Y117488D03*
Y114588D03*
X729933Y108388D03*
X728733Y132088D03*
Y129288D03*
X720433Y135088D03*
X717433D03*
X728733Y126388D03*
X719933Y124488D03*
X723133D03*
X715940Y157362D03*
X718213Y159241D03*
X720633Y160788D03*
X716698Y185687D03*
Y173687D03*
Y177087D03*
Y197187D03*
Y200587D03*
Y189087D03*
Y209021D03*
Y212421D03*
X717020Y220862D03*
X719720Y220142D03*
X722500Y365500D03*
X724897Y353887D03*
X721989Y351234D03*
X727000Y365500D03*
X731400D03*
X722500Y374100D03*
X727000D03*
X731400Y375000D03*
X718720Y381892D03*
X728220Y388362D03*
X723195Y408362D03*
Y404262D03*
X725220Y399862D03*
X723220Y508882D03*
X717220D03*
X729220D03*
Y503842D03*
X723220D03*
X717220D03*
X714000Y496132D03*
X723120Y525362D03*
X728220Y521362D03*
X717220D03*
X717296Y525407D03*
X723220Y516852D03*
X729220D03*
X717220D03*
X729212Y531700D03*
X729328Y583076D03*
X729295Y586113D03*
X725207Y579371D03*
X722707D03*
X715860Y585540D03*
X714320Y597462D03*
X723450Y597072D03*
X720240Y598292D03*
X715420Y639162D03*
X719190Y646642D03*
X717720Y643262D03*
X715220D03*
X723340Y642922D03*
X714087Y745865D03*
X720697Y765862D03*
X723460Y1245632D03*
X714720Y1286162D03*
X723054Y1333896D03*
X725604D03*
X728104D03*
X725604Y1338896D03*
X723054Y1336396D03*
X725604D03*
X728104Y1338896D03*
Y1336396D03*
X723054Y1338896D03*
X725604Y1346396D03*
X728104D03*
X725604Y1348896D03*
X728104D03*
X725604Y1343896D03*
Y1341396D03*
X728104Y1343896D03*
Y1341396D03*
X723054Y1348896D03*
Y1346396D03*
Y1343896D03*
Y1341396D03*
X725654Y1405824D03*
Y1402924D03*
X727720Y1401194D03*
X727820Y1404194D03*
X718024Y1399280D03*
X722684D03*
X720354Y1400030D03*
X725014D03*
X715762Y1408887D03*
X714019Y1406619D03*
X717300Y1547370D03*
X715792Y1567461D03*
X720370Y1566910D03*
X723520Y1561604D03*
X724712Y1566820D03*
X716612Y1584635D03*
X717152Y1570093D03*
X728977Y1574453D03*
X717402Y1574433D03*
X724465Y1580092D03*
X722465Y1582092D03*
X726465D03*
X723942Y1574123D03*
X724465Y1590950D03*
X722465Y1588950D03*
X726465D03*
X729052Y1602518D03*
X726092Y1598483D03*
X720987Y1599568D03*
X723542Y1612702D03*
X721488Y1610945D03*
X725910Y1611900D03*
X716688Y1610055D03*
X719168Y1612016D03*
X718195Y1647300D03*
X714203Y1642926D03*
X729150Y1641690D03*
X726810Y1652430D03*
X714071Y1663842D03*
X722630Y1655740D03*
X724500Y1680400D03*
X718758Y1673800D03*
X745900Y40362D03*
X733314Y40862D03*
X740100Y41162D03*
X746100Y46262D03*
X736620Y45262D03*
X745474Y57932D03*
X733642Y58062D03*
X741377Y57932D03*
X737595D03*
X732793Y71436D03*
X736193D03*
X742620Y71762D03*
X735880Y60662D03*
X740819Y82362D03*
X736720Y101662D03*
X745035Y94632D03*
X735770Y94988D03*
X739823Y91052D03*
X741308Y108742D03*
X738600Y136600D03*
X736060Y145532D03*
X740220Y145362D03*
X745725Y167537D03*
X732720Y231362D03*
X734220Y238362D03*
X744247Y312598D03*
X741800Y363200D03*
X742090Y356082D03*
X735600Y351400D03*
X735800Y365500D03*
X732700Y351500D03*
X740200Y375100D03*
X736220Y380787D03*
X742720Y380262D03*
X735800Y375000D03*
X738220Y388362D03*
X742160Y396452D03*
X738220Y383862D03*
X745720Y399862D03*
X735220Y410842D03*
X735745Y408362D03*
Y404262D03*
X733720Y399862D03*
X743980Y443482D03*
X740740Y473822D03*
X741420Y494162D03*
X747600Y506592D03*
X735220Y508862D03*
X745220Y503842D03*
X735220D03*
X735430Y516862D03*
X745220Y522362D03*
Y516852D03*
X730220Y523362D03*
X740840Y521982D03*
X735173Y521362D03*
X736480Y531722D03*
X738980D03*
X733922Y531712D03*
X733117Y580071D03*
Y582571D03*
X733134Y585672D03*
X736710Y603842D03*
Y607242D03*
X735620Y613862D03*
X730690Y655532D03*
X744538Y746524D03*
X737609Y744282D03*
X730889Y746834D03*
X740820Y741762D03*
X729920Y1405594D03*
X732226Y1396212D03*
X729920Y1399794D03*
Y1402694D03*
X733336Y1568341D03*
Y1565341D03*
Y1559341D03*
Y1562341D03*
X730336Y1559341D03*
Y1562341D03*
X745336D03*
Y1559341D03*
Y1565341D03*
Y1568341D03*
X742336Y1562341D03*
Y1559341D03*
Y1565341D03*
Y1568341D03*
X739336Y1562341D03*
Y1559341D03*
Y1565341D03*
Y1568341D03*
X736336D03*
Y1565341D03*
Y1559341D03*
Y1562341D03*
X733336Y1574341D03*
Y1571341D03*
X745336Y1574341D03*
Y1571341D03*
X742336Y1574341D03*
Y1571341D03*
X739336Y1574341D03*
Y1571341D03*
X736336D03*
Y1574341D03*
X730282Y1580391D03*
X741382Y1585251D03*
Y1580121D03*
X735882Y1580391D03*
X730282Y1590651D03*
Y1585521D03*
X735882Y1590651D03*
X741382Y1590691D03*
X732504Y1600321D03*
Y1597321D03*
X744504D03*
Y1600321D03*
X741504Y1597321D03*
Y1600321D03*
X735504Y1597321D03*
Y1600321D03*
X738504Y1597321D03*
Y1600321D03*
X744504Y1609521D03*
Y1612521D03*
X741504Y1609521D03*
X738504D03*
X735504D03*
X741504Y1612521D03*
X738504D03*
X735504D03*
X732504Y1603321D03*
Y1606321D03*
X744504Y1603321D03*
Y1606321D03*
X741504Y1603321D03*
Y1606321D03*
X738504Y1603321D03*
X735504D03*
X738504Y1606321D03*
X735504D03*
X735300Y1648760D03*
X737080Y1655820D03*
X735080Y1662980D03*
X740840Y1655590D03*
X732705Y1669450D03*
X754620Y51602D03*
X758620D03*
X749477Y57932D03*
X755700Y59942D03*
Y62442D03*
X758200Y59942D03*
Y62442D03*
X760700Y59942D03*
Y62442D03*
X747487Y71429D03*
X757693Y100653D03*
Y96423D03*
X750700Y106642D03*
X754800Y97082D03*
X750033Y92888D03*
Y89988D03*
X757340Y92562D03*
X748033Y116288D03*
X747230Y108572D03*
X760390Y111810D03*
X751220Y137864D03*
X747200Y251500D03*
X757150Y280592D03*
X758720Y283262D03*
X759920Y280562D03*
X758412Y298790D03*
X755305Y298847D03*
X748820Y284562D03*
X758390Y295450D03*
X748498Y309640D03*
X759637Y311585D03*
X757936Y303908D03*
X760670Y317432D03*
X747554Y384962D03*
X757430Y408212D03*
X760469Y442647D03*
X750290Y462162D03*
X757365Y459862D03*
X752500Y495762D03*
X757238Y483862D03*
X756642Y496522D03*
Y501744D03*
X751220Y522362D03*
Y516852D03*
X759790Y525522D03*
X755940Y516862D03*
X756650Y526072D03*
X761710Y517651D03*
X757020Y530462D03*
X759820D03*
X754220D03*
X762345Y1284542D03*
Y1287542D03*
Y1290542D03*
X762205Y1293272D03*
X757720Y1375462D03*
Y1384062D03*
X758020Y1397862D03*
X758420Y1406862D03*
X758120Y1414762D03*
X755420Y1426262D03*
Y1422862D03*
X748336Y1562341D03*
Y1559341D03*
Y1565341D03*
Y1568341D03*
X751336D03*
Y1565341D03*
Y1559341D03*
Y1562341D03*
X748336Y1574341D03*
Y1571341D03*
X760112Y1579183D03*
X749612Y1579023D03*
X749652Y1586407D03*
X760152Y1583183D03*
X749612Y1583023D03*
X760112Y1592183D03*
Y1587183D03*
X747504Y1600321D03*
X749662Y1590733D03*
X749612Y1594683D03*
X758360Y1589661D03*
X747504Y1609521D03*
Y1612521D03*
X750504D03*
Y1609521D03*
X747504Y1603321D03*
Y1606321D03*
X761716Y1661194D03*
X751620Y1674312D03*
X759859Y1686090D03*
X759359Y1729520D03*
X752875Y1726670D03*
X774059Y68912D03*
X773420Y143462D03*
X772328Y153728D03*
X771426Y158026D03*
X766320Y264892D03*
X763320D03*
X771630Y258102D03*
X762420Y280562D03*
X777420Y277962D03*
X769789Y296231D03*
X777467Y296315D03*
X769860Y302462D03*
X771377Y314139D03*
X771490Y354942D03*
X768490D03*
X777420Y354962D03*
X774490Y354942D03*
X765000Y354862D03*
X771960Y375162D03*
X767960Y369662D03*
X776000D03*
X764000D03*
X766195Y393212D03*
X773245Y398212D03*
X766195Y403212D03*
Y413212D03*
X773245Y403212D03*
Y408212D03*
X768910Y403260D03*
X771050Y416940D03*
X766195Y423212D03*
Y428212D03*
X768701Y418662D03*
X774982Y446908D03*
X772365Y454862D03*
X768720Y459862D03*
X765315Y454862D03*
Y459862D03*
X772365D03*
X765360Y475412D03*
X765335Y469552D03*
X772364Y475062D03*
X772365Y469862D03*
X765315Y479862D03*
X772365Y488862D03*
X776170Y493422D03*
X766510Y493452D03*
X765386Y483572D03*
X773530Y507062D03*
X765810Y506342D03*
X769745Y502600D03*
X775378Y502502D03*
X765521Y525364D03*
X769220Y530362D03*
X765720D03*
X777020D03*
X772020Y746562D03*
X774384Y744088D03*
X762562Y746444D03*
X769921Y742095D03*
X767421D03*
X764921D03*
X769337Y760775D03*
X762617Y758885D03*
X765345Y1284542D03*
X768335Y1284612D03*
X765345Y1287542D03*
Y1290542D03*
X768335Y1287612D03*
Y1290612D03*
X765205Y1293272D03*
X768195Y1293342D03*
X778005Y1294092D03*
X768520Y1384062D03*
Y1375462D03*
X768620Y1397262D03*
X775375Y1403561D03*
X767820Y1414762D03*
X763152Y1581893D03*
Y1577893D03*
Y1573793D03*
X773952Y1580493D03*
X768714Y1571203D03*
X769452Y1584393D03*
X770252Y1587268D03*
X763152Y1590893D03*
Y1594893D03*
X774052Y1590293D03*
X776922Y1590444D03*
X776052Y1611893D03*
X764920Y1695347D03*
X766880Y1689020D03*
X766603Y1721797D03*
X785180Y120947D03*
X792680D03*
X790180D03*
X787680D03*
X783940Y118637D03*
X786440D03*
X788940D03*
X781440D03*
X782553Y150031D03*
Y152531D03*
X779893Y147521D03*
Y150021D03*
X780820Y278262D03*
X785135Y274822D03*
X785200Y271400D03*
X794057Y301569D03*
X794220Y296062D03*
X785220Y284762D03*
X792943Y312642D03*
X784415Y313734D03*
X793896Y309026D03*
X793820Y304962D03*
X779120Y303410D03*
Y308755D03*
X785000Y355000D03*
X779920Y354962D03*
X782420D03*
X790120Y354862D03*
X792620D03*
X787600Y354900D03*
X795520Y393462D03*
X791075Y388000D03*
X781195Y393212D03*
X781320Y398212D03*
X787720Y408362D03*
X781195Y413212D03*
Y423212D03*
X785560Y417902D03*
X788120Y422942D03*
X791040Y422892D03*
X793660Y422842D03*
X785720Y427862D03*
X789230Y414942D03*
X780020Y441437D03*
Y445287D03*
X784730Y432682D03*
X787320Y444862D03*
Y439862D03*
X791582Y435352D03*
X781205Y454402D03*
X780315Y459862D03*
X787320Y454862D03*
Y449862D03*
Y459862D03*
X787360Y469862D03*
X786220Y464862D03*
X796315Y469290D03*
X780315Y464862D03*
X783340Y474802D03*
X782690Y488862D03*
X793220Y493362D03*
X781170Y493422D03*
X785800Y482762D03*
X793875Y483262D03*
X778670Y493422D03*
X783600Y502462D03*
X783450Y522462D03*
X783400Y511902D03*
X789720Y589862D03*
X785220Y581362D03*
X789720Y587362D03*
X791720Y593862D03*
X793720Y595862D03*
X791969Y618384D03*
X794720Y617862D03*
X783507Y761875D03*
X794157Y761295D03*
X782515Y766702D03*
X791140Y761693D03*
X792045Y1284542D03*
Y1290542D03*
Y1287542D03*
X791905Y1293272D03*
X791260Y1388662D03*
X790380Y1432132D03*
X784352Y1568293D03*
Y1565293D03*
Y1559293D03*
Y1562293D03*
X781352Y1568293D03*
Y1565293D03*
Y1559293D03*
Y1562293D03*
X793352D03*
Y1559293D03*
Y1565293D03*
Y1568293D03*
X790352Y1562293D03*
Y1559293D03*
Y1565293D03*
Y1568293D03*
X787352D03*
Y1565293D03*
Y1559293D03*
Y1562293D03*
X784352Y1574293D03*
Y1571293D03*
X781352Y1574293D03*
Y1571293D03*
X793352Y1574293D03*
Y1571293D03*
X790352Y1574293D03*
Y1571293D03*
X787352D03*
Y1574293D03*
X788079Y1580393D03*
X782479D03*
X793579D03*
X788079Y1590653D03*
X782479D03*
Y1585523D03*
X793579Y1590653D03*
Y1585523D03*
X785052Y1600693D03*
Y1597693D03*
X782052D03*
Y1600693D03*
X794052D03*
X788052D03*
X791052D03*
X794052Y1597693D03*
X788052D03*
X791052D03*
X785052Y1607793D03*
X782052D03*
X779052D03*
X785052Y1611893D03*
X782052D03*
X779052D03*
X794052Y1607793D03*
X791052D03*
X788052D03*
X797052Y1611893D03*
X794052D03*
X788052D03*
X791052D03*
X785052Y1603693D03*
X782052D03*
X794052D03*
X788052D03*
X791052D03*
X808800Y267900D03*
X810920Y280062D03*
X798204Y279146D03*
X797924Y298358D03*
X806450Y310362D03*
X803620Y302962D03*
X805870Y304812D03*
X799720Y300462D03*
X795920Y312662D03*
X803280Y354982D03*
X800646Y354921D03*
X795220Y354862D03*
X806000Y360600D03*
X798400D03*
X805910Y355012D03*
X797900Y354800D03*
X795520Y398212D03*
X800352Y408389D03*
X803120Y428762D03*
X797720Y428412D03*
X798370Y439932D03*
X802010Y439940D03*
X802790Y433832D03*
X795320Y439862D03*
X805720Y432902D03*
X801750Y444330D03*
X795320Y444862D03*
X810860Y454862D03*
X802810D03*
X795320D03*
Y449862D03*
X802810Y464862D03*
Y449862D03*
X810860Y459862D03*
X802810D03*
X795320D03*
X810860Y449862D03*
X798990Y474862D03*
X802865D03*
X795320Y464862D03*
X810815Y474862D03*
X810860Y464862D03*
X810815Y469862D03*
X807220Y493362D03*
X801940Y485932D03*
X804510Y486122D03*
X809510D03*
X799230Y485922D03*
X812510Y486422D03*
X802790Y495652D03*
X805470Y510522D03*
X807640Y506672D03*
X808100Y509900D03*
X797420Y512503D03*
X805445Y587582D03*
X810720Y586862D03*
X811143Y605265D03*
X807945Y594362D03*
X803220D03*
X797200Y599883D03*
X795720Y614862D03*
X796702Y761195D03*
X810850Y770272D03*
X799577Y760985D03*
X807000Y757562D03*
X798035Y1284612D03*
X795045Y1284542D03*
X798035Y1290612D03*
Y1287612D03*
X795045Y1290542D03*
Y1287542D03*
X797895Y1293342D03*
X794905Y1293272D03*
X806323Y1343076D03*
X812130Y1343022D03*
X809210Y1343062D03*
X804100Y1435010D03*
X800000Y1431100D03*
X799352Y1562293D03*
Y1559293D03*
Y1565293D03*
Y1568293D03*
X796352Y1562293D03*
Y1559293D03*
Y1565293D03*
Y1568293D03*
X799352Y1574293D03*
Y1571293D03*
X796352Y1574293D03*
Y1571293D03*
X804652Y1581793D03*
Y1573793D03*
X812652Y1577793D03*
X801652Y1584539D03*
X812698Y1587047D03*
X804652Y1597793D03*
Y1585993D03*
X799152Y1586507D03*
X804652Y1589793D03*
X797052Y1607793D03*
X804652Y1609793D03*
X827114Y115223D03*
X823114D03*
X814570Y145952D03*
X814531Y139851D03*
X820900Y147112D03*
X815060Y280072D03*
X813490Y273862D03*
X816220Y277162D03*
X813293Y287062D03*
X826300Y311962D03*
X823800D03*
X818000Y378800D03*
X813210Y374292D03*
X815710D03*
X825003Y389012D03*
Y397276D03*
X819220Y397664D03*
X824980Y413260D03*
X819220Y412264D03*
X823600Y421194D03*
X815310Y440100D03*
X816810Y464862D03*
X825100Y468900D03*
X824860Y464862D03*
X816400Y472900D03*
X820720Y493862D03*
X822415Y479600D03*
X821720Y511082D03*
X814305Y499503D03*
X819320Y502347D03*
X821720Y527082D03*
X815650Y516807D03*
X821720Y515082D03*
Y523082D03*
X820220Y586862D03*
X814220Y582530D03*
X823720Y594862D03*
X820470Y595112D03*
X815120Y593582D03*
X820613Y744641D03*
X823589Y746924D03*
X822374Y757039D03*
X814770Y763874D03*
X815789Y1008845D03*
X826090Y1334362D03*
Y1339362D03*
Y1329362D03*
Y1344362D03*
X820920Y1344342D03*
X818420D03*
X823352Y1565293D03*
Y1562293D03*
Y1559293D03*
Y1568293D03*
X826352Y1565293D03*
Y1562293D03*
Y1559293D03*
Y1568293D03*
X823352Y1571293D03*
Y1574293D03*
X826352Y1571293D03*
Y1574293D03*
X824479Y1580393D03*
X815652Y1582570D03*
Y1573793D03*
X813352Y1590893D03*
X812652Y1593793D03*
X824479Y1590653D03*
Y1585523D03*
X824052Y1597693D03*
Y1600693D03*
X827052D03*
Y1597693D03*
X815551Y1593793D03*
X818652Y1590444D03*
X812652Y1605793D03*
X824052Y1611893D03*
Y1607793D03*
Y1603693D03*
X827052Y1611893D03*
Y1607793D03*
Y1603693D03*
X821052Y1611893D03*
Y1607793D03*
X818052Y1611893D03*
X812652Y1601793D03*
X840001Y20200D03*
Y16800D03*
X836779Y68008D03*
X828600Y61752D03*
X839898Y87248D03*
X841584Y94181D03*
X837250Y93221D03*
X839360Y114862D03*
X835114Y115223D03*
X845220Y135862D03*
Y129362D03*
X829114Y147123D03*
X828145Y160362D03*
X838220Y163862D03*
X835220D03*
X837320Y175112D03*
X842720Y181360D03*
X837160Y218212D03*
Y213207D03*
X844526Y204968D03*
X838820Y206872D03*
X837500Y229642D03*
X840063Y285022D03*
X839450Y272662D03*
X835400Y268800D03*
X829620Y280345D03*
X829820Y275045D03*
X840850Y278948D03*
X829720Y292762D03*
X839860Y294702D03*
X827620Y302962D03*
X830417Y311865D03*
X836300Y418800D03*
X832400Y427100D03*
X840400Y418900D03*
X831720Y457700D03*
X839640Y449612D03*
X832700Y446800D03*
X830600Y449200D03*
X838220Y459562D03*
X841200Y456500D03*
X832720Y494862D03*
X829720D03*
X838645Y492862D03*
X830870Y480010D03*
X832590Y512888D03*
X829745Y502082D03*
X832370Y525849D03*
X843287Y527817D03*
X841461Y525849D03*
X840990Y529786D03*
X828009Y587913D03*
X831705Y593877D03*
X829230Y582772D03*
X831530Y651932D03*
X830587Y741205D03*
X833120Y743392D03*
X838587Y766825D03*
X841827Y766795D03*
X837127Y758976D03*
X829420Y758422D03*
X841997Y773085D03*
X838020Y1232432D03*
X832090Y1326862D03*
Y1331862D03*
Y1336862D03*
Y1341862D03*
X829352Y1565293D03*
Y1562293D03*
Y1559293D03*
Y1568293D03*
X832352D03*
Y1565293D03*
Y1559293D03*
Y1562293D03*
X835352Y1568293D03*
Y1565293D03*
Y1559293D03*
Y1562293D03*
X838352Y1568293D03*
Y1565293D03*
Y1559293D03*
Y1562293D03*
X841352Y1568293D03*
Y1565293D03*
Y1559293D03*
Y1562293D03*
X829352Y1574293D03*
Y1571293D03*
X832352D03*
Y1574293D03*
X835352Y1571293D03*
Y1574293D03*
X838352Y1571293D03*
Y1574293D03*
X841352Y1571293D03*
Y1574293D03*
X830079Y1580393D03*
X835579D03*
X843652Y1584539D03*
X833052Y1597693D03*
X836052D03*
X830079Y1590653D03*
X835579D03*
X833052Y1600693D03*
X836052D03*
X835579Y1585523D03*
X830052Y1600693D03*
Y1597693D03*
X841152Y1586507D03*
X833052Y1603693D03*
X836052D03*
X839052Y1611893D03*
X833052Y1607793D03*
Y1611893D03*
X836052Y1607793D03*
Y1611893D03*
X830052D03*
Y1607793D03*
Y1603693D03*
X839052Y1607793D03*
X858629Y60293D03*
X850015Y87341D03*
X843855Y87711D03*
X847472Y94754D03*
X847660Y113962D03*
X853100Y113762D03*
X854100Y132972D03*
X854220Y135862D03*
Y129362D03*
X854200Y138562D03*
X848745Y160187D03*
X848709Y156752D03*
X848360Y182872D03*
X845720Y181362D03*
X855858Y212425D03*
X855933Y215375D03*
X860050Y215310D03*
X847580Y232222D03*
X853828Y269043D03*
X850133Y271049D03*
X861865Y273730D03*
X850093Y286625D03*
X855480Y299692D03*
X856243Y286447D03*
X859920Y308852D03*
X859740Y399081D03*
X846040Y399210D03*
X846490Y422131D03*
X850610Y444352D03*
X851606Y447927D03*
X844210Y455902D03*
X846700Y476900D03*
X855200D03*
X857620Y492862D03*
X858600Y511130D03*
X848620Y509752D03*
X853070Y515447D03*
X857195Y522162D03*
X859888Y593970D03*
X859054Y583752D03*
X845523Y582126D03*
X856520Y751262D03*
X859450Y750462D03*
X844957Y763065D03*
X854620Y1242125D03*
X854237Y1250358D03*
X846652Y1581793D03*
Y1573793D03*
X854652Y1577793D03*
X857652Y1582570D03*
Y1573793D03*
X854777Y1586968D03*
X846652Y1597793D03*
X855352Y1590893D03*
X854652Y1593793D03*
X846652Y1585993D03*
X857551Y1593793D03*
X846652Y1589793D03*
X854652Y1605793D03*
Y1601793D03*
X846652Y1609793D03*
X862930Y70072D03*
X866330D03*
X862452Y151590D03*
X867620Y154362D03*
X871145Y163862D03*
X871580Y183370D03*
X875169Y185113D03*
X864859Y187110D03*
X873200Y194262D03*
X871890Y196740D03*
X877971Y196652D03*
X867528Y231788D03*
X875543Y266447D03*
X867700Y268262D03*
X875543Y269347D03*
X863747Y280870D03*
X867237Y273325D03*
X868552Y285537D03*
X874243Y287047D03*
X877322Y296051D03*
X872320Y304936D03*
X869820D03*
X867320D03*
X864820D03*
X860531Y375826D03*
X870700Y386476D03*
Y398620D03*
Y402581D03*
X868113Y409372D03*
X870513Y414276D03*
X862320Y431462D03*
X863415Y445829D03*
X860574Y445404D03*
X861080Y459742D03*
X870360Y493042D03*
X862620Y507162D03*
X868110Y499142D03*
X865290Y499032D03*
X865810Y521862D03*
X866820Y736562D03*
X863925Y737697D03*
X864680Y751582D03*
X874155Y756993D03*
X864700Y778300D03*
X868352Y1568293D03*
Y1565293D03*
Y1559293D03*
Y1562293D03*
X865352Y1568293D03*
Y1565293D03*
Y1559293D03*
Y1562293D03*
X874352D03*
Y1559293D03*
Y1565293D03*
Y1568293D03*
X871352D03*
Y1565293D03*
Y1559293D03*
Y1562293D03*
X868352Y1574293D03*
Y1571293D03*
X865352Y1574293D03*
Y1571293D03*
X874352Y1574293D03*
Y1571293D03*
X871352D03*
Y1574293D03*
X866479Y1580393D03*
X872079D03*
X866052Y1597693D03*
X869052D03*
X866479Y1590653D03*
X869052Y1600693D03*
X866052D03*
X872052Y1597693D03*
X872079Y1590653D03*
X872052Y1600693D03*
X866479Y1585523D03*
X875052Y1597693D03*
Y1600693D03*
X860652Y1590444D03*
X869052Y1603693D03*
X866052D03*
X872052D03*
X869052Y1607793D03*
Y1611893D03*
X866052Y1607793D03*
X863052Y1611893D03*
X866052D03*
X872052Y1607793D03*
Y1611893D03*
X875052Y1603693D03*
Y1607793D03*
Y1611893D03*
X863052Y1607793D03*
X860052Y1611893D03*
X878327Y183169D03*
X876695Y171362D03*
Y176862D03*
X887520Y171362D03*
Y176862D03*
X877724Y200837D03*
X878220Y187449D03*
X888929Y209223D03*
X891620Y209662D03*
X888929Y206723D03*
X891620Y207162D03*
X884003Y278712D03*
X883870Y275802D03*
X883909Y281862D03*
X879587Y270004D03*
X883870Y272652D03*
X887338Y296760D03*
X882520Y327562D03*
X885020D03*
X887520D03*
X890422Y333879D03*
X893440Y336232D03*
X890820Y389362D03*
X890920Y386352D03*
X889453Y458926D03*
X887590Y471552D03*
X889439Y489599D03*
Y492999D03*
X881680Y504742D03*
Y508142D03*
X884512Y523800D03*
X882410Y526132D03*
X888130Y532612D03*
X891530D03*
X887810Y582442D03*
X889000Y737562D03*
X885310Y736442D03*
X886720Y741902D03*
X878192Y879910D03*
X884747Y871745D03*
X879100Y912608D03*
X884619Y916477D03*
X892317Y915872D03*
X880102Y923235D03*
X891560Y1435510D03*
X883352Y1562293D03*
Y1559293D03*
Y1565293D03*
Y1568293D03*
X880352Y1562293D03*
Y1559293D03*
Y1565293D03*
Y1568293D03*
X877352Y1562293D03*
Y1559293D03*
Y1565293D03*
Y1568293D03*
X883352Y1574293D03*
Y1571293D03*
X880352Y1574293D03*
Y1571293D03*
X877352Y1574293D03*
Y1571293D03*
X888652Y1581793D03*
Y1573793D03*
X877579Y1580393D03*
X885652Y1584539D03*
X888652Y1597793D03*
Y1585993D03*
X877579Y1585523D03*
X878052Y1597693D03*
Y1600693D03*
X877579Y1590653D03*
X883152Y1586507D03*
X888652Y1589793D03*
X878052Y1603693D03*
Y1607793D03*
X881052Y1611893D03*
X878052D03*
X881052Y1607793D03*
X888652Y1609793D03*
X908620Y188899D03*
X896620Y209662D03*
X894120D03*
Y207162D03*
X896620D03*
X902350Y208294D03*
X907470Y211980D03*
X902350Y204894D03*
X907470Y215380D03*
X902350Y219068D03*
X907470Y226154D03*
X902350Y222468D03*
X907470Y229554D03*
X906120Y261252D03*
X894770Y283062D03*
X896540Y341132D03*
X902260Y473153D03*
Y475653D03*
X903124Y470797D03*
X900020Y470672D03*
X896060Y481222D03*
Y484622D03*
X907678Y488177D03*
X895340Y497882D03*
Y501282D03*
X901829Y512730D03*
Y516130D03*
X893450Y516862D03*
X901230Y531612D03*
X904630D03*
X894897Y871745D03*
X894965Y917422D03*
X899830Y971484D03*
Y974884D03*
X907770Y1045242D03*
X894830Y1435970D03*
X907352Y1568293D03*
Y1565293D03*
Y1559293D03*
Y1562293D03*
Y1574293D03*
Y1571293D03*
X908479Y1580393D03*
X896652Y1577793D03*
X899652Y1582570D03*
Y1573793D03*
X896672Y1587073D03*
X897352Y1590893D03*
X896652Y1593793D03*
X908479Y1590653D03*
Y1585523D03*
X908052Y1600693D03*
Y1597693D03*
X899551Y1593793D03*
X902652Y1590444D03*
X896652Y1605793D03*
X908052Y1611893D03*
X905052D03*
X902052D03*
X908052Y1607793D03*
X905052D03*
X908052Y1603693D03*
X896652Y1601793D03*
X922726Y176302D03*
X922100Y181791D03*
X917386Y184114D03*
X924920Y196199D03*
X923836Y193563D03*
X923897Y445545D03*
X927034Y445594D03*
X912984Y458135D03*
X909584D03*
X924447Y463012D03*
X921047D03*
X909190Y473392D03*
X912288Y472430D03*
X918532Y492445D03*
X927154Y492103D03*
X924623Y492097D03*
X918078Y495177D03*
X921189Y492086D03*
X918212Y497677D03*
X918131Y503330D03*
X921060Y506086D03*
X923783Y506076D03*
X918212Y500777D03*
X909984Y496330D03*
X926173Y512391D03*
X913394Y521662D03*
X916794D03*
X909600Y521162D03*
X922879Y531976D03*
Y528576D03*
X918420Y804062D03*
X909720Y798861D03*
Y794862D03*
X913720Y799362D03*
X914152Y803294D03*
X921757Y962082D03*
X916974Y962108D03*
X923930Y976652D03*
X917980Y974952D03*
X924440Y996852D03*
X914838Y985989D03*
X918720Y1009937D03*
X910352Y1568293D03*
Y1565293D03*
Y1559293D03*
Y1562293D03*
X922352D03*
Y1559293D03*
Y1565293D03*
Y1568293D03*
X919352Y1562293D03*
Y1559293D03*
Y1565293D03*
Y1568293D03*
X916352Y1562293D03*
Y1559293D03*
Y1565293D03*
Y1568293D03*
X913352D03*
Y1565293D03*
Y1559293D03*
Y1562293D03*
X910352Y1574293D03*
Y1571293D03*
X922352Y1574293D03*
Y1571293D03*
X919352Y1574293D03*
Y1571293D03*
X916352Y1574293D03*
Y1571293D03*
X913352D03*
Y1574293D03*
X919579Y1580393D03*
X914079D03*
X919579Y1590653D03*
X914079D03*
X919579Y1585523D03*
X917052Y1600693D03*
Y1597693D03*
X914052Y1600693D03*
Y1597693D03*
X911052Y1600693D03*
Y1597693D03*
X920052Y1600693D03*
Y1597693D03*
X917052Y1611893D03*
X914052D03*
X911052D03*
X917052Y1607793D03*
X914052D03*
X911052D03*
X920052Y1611893D03*
X923052D03*
Y1607793D03*
X920052D03*
X917052Y1603693D03*
X914052D03*
X911052D03*
X920052D03*
X919488Y1660733D03*
X918020Y1672860D03*
X914500Y1671400D03*
X938160Y173389D03*
X935550Y173329D03*
X940720Y173389D03*
X938160Y176389D03*
X935550Y176329D03*
X940720Y176389D03*
X940424Y184190D03*
X936424D03*
X935770Y191419D03*
X939270D03*
X940410Y188852D03*
X930472Y246093D03*
X938603Y240063D03*
X933122Y246115D03*
X933686Y242922D03*
X935454Y241154D03*
X933217Y380693D03*
Y384693D03*
X941059Y427911D03*
Y424511D03*
X937447Y457862D03*
X934047D03*
X928394Y472201D03*
Y474701D03*
X932373Y495175D03*
X932089Y492691D03*
X929654Y492103D03*
X932218Y499314D03*
X939872Y495813D03*
X932089Y505986D03*
X932289Y502986D03*
X926637Y506069D03*
X929281Y506086D03*
X931720Y524862D03*
X940550Y517400D03*
X940140Y514925D03*
X933773Y530479D03*
X930731D03*
X941050Y532252D03*
Y528852D03*
X938742Y803831D03*
X931573Y816109D03*
X927470Y815112D03*
X935052Y812630D03*
X934260Y808312D03*
X938371Y809311D03*
X930786Y811785D03*
X925220Y817862D03*
X928237Y824844D03*
X926469Y826612D03*
X926823Y962082D03*
X940170Y962842D03*
X939740Y987762D03*
X936998Y985750D03*
X932310Y996812D03*
X927220Y1012362D03*
X931220D03*
X925352Y1562293D03*
Y1559293D03*
Y1565293D03*
Y1568293D03*
Y1574293D03*
Y1571293D03*
X938652Y1581393D03*
X928152Y1584539D03*
X938652Y1593393D03*
Y1585393D03*
X925152Y1586507D03*
X938652Y1589393D03*
X933979Y1661327D03*
X929979Y1661352D03*
X942100Y1671100D03*
X945720Y173389D03*
X943220D03*
X945720Y176389D03*
X943220D03*
X948400Y176499D03*
X949120Y184912D03*
X944250Y194489D03*
Y197889D03*
X957020Y193299D03*
X949550Y192819D03*
X953970Y208275D03*
X947496Y215397D03*
X953970Y204875D03*
X947496Y211997D03*
X957156Y227163D03*
X947496Y226135D03*
X957156Y230563D03*
X947496Y229535D03*
X957020Y264862D03*
X953046Y390103D03*
X951181Y391916D03*
X950660Y399472D03*
X956487Y394831D03*
X949920Y404602D03*
X944032Y437631D03*
Y434231D03*
X945447Y463012D03*
X942047D03*
X946727Y507952D03*
Y504552D03*
X954420Y511252D03*
Y500552D03*
Y497152D03*
Y514652D03*
X954390Y527596D03*
X945524Y515483D03*
X944261Y517871D03*
X941740Y512922D03*
X942610Y515350D03*
X945100Y534464D03*
X955123Y533642D03*
X948415Y534313D03*
X956518Y531567D03*
X957220Y582862D03*
X953594Y787477D03*
X954447Y791735D03*
X951043Y796140D03*
X950190Y791382D03*
X944272Y803410D03*
X943366Y798707D03*
X946786Y795287D03*
X947921Y799761D03*
X944170Y962842D03*
X949560Y981392D03*
X951560Y997422D03*
X956980Y1536260D03*
X953980D03*
X950980D03*
X947980D03*
X944980D03*
Y1551260D03*
X947980D03*
X950980D03*
X953980D03*
X956980D03*
X944980Y1548260D03*
X947980D03*
X950980D03*
X953980D03*
X956980D03*
X944980Y1545260D03*
X947980D03*
X950980D03*
X953980D03*
X956980D03*
X944980Y1542260D03*
X947980D03*
X950980D03*
X953980D03*
X956980D03*
Y1539260D03*
X953980D03*
X950980D03*
X947980D03*
X944980D03*
Y1554260D03*
X947980D03*
X950980D03*
X953980D03*
X956980D03*
X956800Y1663725D03*
X956600Y1666875D03*
X962604Y165313D03*
X962458Y162398D03*
X965150Y193412D03*
X966720Y198099D03*
X970720D03*
X961120Y193299D03*
X968384Y242051D03*
X965884D03*
X960020Y264862D03*
X963020D03*
X962570Y282812D03*
X962882Y314512D03*
X967239Y320073D03*
X963854Y320113D03*
X963300Y347962D03*
X962623Y350642D03*
X970730Y377872D03*
X972220Y386251D03*
Y390239D03*
X975670Y392063D03*
X963856Y398302D03*
X965890Y405967D03*
X963720Y439862D03*
X961320Y476242D03*
X968286Y483941D03*
Y480541D03*
X964347Y509462D03*
X970788Y501230D03*
X964347Y501262D03*
X969351Y512416D03*
X957790Y527596D03*
X963930Y533362D03*
X967330D03*
X959351Y533566D03*
X960920Y644762D03*
Y649762D03*
Y654762D03*
X963720Y647262D03*
Y657262D03*
Y652262D03*
X960820Y665062D03*
X960920Y659762D03*
X963720Y662262D03*
X967750Y1376460D03*
X969000Y1536262D03*
X971700D03*
X969000Y1548262D03*
X971700D03*
X969000Y1545262D03*
X971700D03*
X969000Y1551262D03*
X971700D03*
Y1542262D03*
X969000D03*
X971700Y1539262D03*
X969000D03*
X965904Y1554364D03*
X960904D03*
X969000Y1554262D03*
X971700D03*
X965622Y1579240D03*
Y1576240D03*
Y1573240D03*
X966852Y1585920D03*
X969852D03*
X960852D03*
X963852D03*
X957852D03*
X965086Y1603984D03*
X962086D03*
X980899Y-13200D03*
Y-9800D03*
Y20200D03*
Y16800D03*
X990501Y152397D03*
X986369Y155358D03*
X975690Y157220D03*
X983811Y156694D03*
X985499Y168753D03*
X985431Y181058D03*
X990115Y173039D03*
X987320Y194599D03*
Y198099D03*
Y201599D03*
X977220Y201399D03*
X986020Y191099D03*
X981795Y216623D03*
X978012Y276436D03*
X975512Y282096D03*
X978012D03*
X975512Y279266D03*
X978012D03*
X981470Y268532D03*
X979940Y292262D03*
Y289762D03*
X975512Y294996D03*
X978012D03*
X979940Y284762D03*
Y287262D03*
X988818Y346372D03*
X978000Y362462D03*
X988723Y369650D03*
X991934Y368443D03*
X988908Y373392D03*
X986400Y383123D03*
X983770Y373962D03*
X979766Y377507D03*
X977949Y384205D03*
X980916Y384286D03*
X980856Y392502D03*
X986955Y391939D03*
X983629Y397628D03*
X979559Y399362D03*
X983970Y392562D03*
X991369Y408252D03*
X979240Y425212D03*
X984254Y418379D03*
X987440Y431193D03*
X980720Y512362D03*
X986400Y503200D03*
X986273Y532996D03*
X980535Y532643D03*
X986418Y530019D03*
X975900Y1265062D03*
X987920Y1290662D03*
X985320Y1288762D03*
X992306Y1295049D03*
X979373Y1342724D03*
X974700Y1536262D03*
X980400D03*
X977700D03*
X974700Y1548262D03*
Y1545262D03*
Y1551262D03*
X980400Y1548262D03*
X977700D03*
X980400Y1545262D03*
X977700D03*
X980400Y1551262D03*
X977700D03*
Y1542262D03*
X980400D03*
X974700D03*
X977700Y1539262D03*
X980400D03*
X974700D03*
X984270Y1554364D03*
X974700Y1554262D03*
X980400D03*
X977700D03*
X989270Y1554364D03*
X988988Y1579240D03*
Y1573240D03*
Y1576240D03*
X995000Y150883D03*
X1001500D03*
X995180Y153689D03*
X1006220Y160799D03*
X1002720D03*
X1001101Y165510D03*
X999220Y185299D03*
X1002720D03*
X1006220D03*
X996415Y172579D03*
X1002920Y174799D03*
X990220Y195699D03*
Y199199D03*
X1008120Y198293D03*
X990195Y216823D03*
X990220Y202699D03*
X1000610Y211039D03*
X1005640Y210969D03*
X1001195Y219898D03*
X1005120Y230399D03*
X994743Y289843D03*
X1006232Y343983D03*
X1001440Y359702D03*
X994689Y379348D03*
X1006201Y370004D03*
X999440Y371782D03*
X996922Y367764D03*
X994322Y404090D03*
X1005123Y414662D03*
X997617Y412383D03*
X997394Y415578D03*
X993012Y421570D03*
X997225Y419162D03*
X990840Y431193D03*
X1005720Y498862D03*
X1003220Y512862D03*
X1005520Y510932D03*
X991237Y533043D03*
X1008560Y589682D03*
X1005960Y594682D03*
X1005373Y748826D03*
X995120Y773122D03*
X994942Y777055D03*
X996320Y1280683D03*
Y1284062D03*
X997920Y1278762D03*
X994574Y1297318D03*
X995066Y1536262D03*
X992466D03*
X1001066D03*
X1003766D03*
X998066D03*
X995066Y1551262D03*
X992466D03*
X995066Y1545262D03*
X992466D03*
X995066Y1548262D03*
X992466D03*
X1001066Y1551262D03*
X1003766D03*
X1001066Y1545262D03*
X1003766D03*
X1001066Y1548262D03*
X1003766D03*
X998066Y1551262D03*
Y1545262D03*
Y1548262D03*
Y1542262D03*
X1003766D03*
X1001066D03*
X992466D03*
X995066D03*
X998066Y1539262D03*
X1003766D03*
X1001066D03*
X992466D03*
X995066D03*
X1007636Y1554364D03*
X995066Y1554262D03*
X992466D03*
X1001066D03*
X1003766D03*
X998066D03*
X1002782Y1585920D03*
X999782D03*
X996782D03*
X990782D03*
X993782D03*
X996698Y1604000D03*
X993698D03*
X1008129Y150948D03*
X1009720Y160799D03*
X1013220D03*
X1012791Y157596D03*
X1012000Y185299D03*
X1014900D03*
X1017800D03*
X1017200Y175699D03*
X1014300D03*
X1019900Y175799D03*
X1020645Y190499D03*
X1011320Y202169D03*
X1019355Y218423D03*
X1019802Y214099D03*
X1010005Y208424D03*
X1011720Y229699D03*
X1019355Y222423D03*
X1019530Y226423D03*
X1007820Y229999D03*
X1021118Y294290D03*
X1020720Y310937D03*
X1015520Y302862D03*
X1009800Y343800D03*
X1021695Y364518D03*
X1006710Y372931D03*
X1015096Y373758D03*
X1017163Y367963D03*
X1009883Y367955D03*
X1010420Y416062D03*
X1015420Y410862D03*
X1009009Y419948D03*
X1021239Y416974D03*
X1016261Y432888D03*
X1012861D03*
X1024200Y510362D03*
X1018092Y520212D03*
X1020392Y521826D03*
X1016360Y594682D03*
X1016220Y590862D03*
X1019000Y601042D03*
X1021654Y606302D03*
X1011160Y594682D03*
X1007873Y748826D03*
X1007600Y1298250D03*
X1007610Y1295040D03*
X1021612Y1536262D03*
X1016012D03*
X1018612D03*
Y1551262D03*
X1016012D03*
X1018612Y1545262D03*
X1016012D03*
X1018612Y1548262D03*
X1016012D03*
X1021612Y1551262D03*
Y1545262D03*
Y1548262D03*
X1018612Y1542262D03*
X1016012D03*
X1021612D03*
Y1539262D03*
X1016012D03*
X1018612D03*
Y1554262D03*
X1016012D03*
X1021612D03*
X1012636Y1554364D03*
X1012354Y1579240D03*
Y1573240D03*
Y1576240D03*
X1021942Y1586090D03*
X1032433Y-23211D03*
Y-19811D03*
X1026620Y125662D03*
X1034229Y128953D03*
X1032894Y155185D03*
X1022800Y175799D03*
X1037618Y261200D03*
X1031702Y264130D03*
X1025862Y291727D03*
X1032317Y291284D03*
X1036278Y303993D03*
Y307393D03*
X1033285Y353627D03*
X1029395Y375844D03*
X1025004Y374662D03*
X1031950Y383771D03*
Y387171D03*
X1031153Y390152D03*
X1026820Y394362D03*
X1038320Y407062D03*
Y404462D03*
X1026548Y400571D03*
X1035920Y420062D03*
Y417462D03*
X1026370Y503562D03*
X1032155Y509737D03*
X1025530Y519627D03*
X1033040Y519852D03*
X1038130Y518417D03*
X1040720Y591862D03*
X1024154Y601152D03*
X1029630Y601252D03*
X1026654Y596152D03*
X1035760Y592952D03*
X1033260Y601272D03*
X1038260D03*
X1033817Y735612D03*
X1036954Y734669D03*
X1030660Y735082D03*
X1027212Y1536262D03*
X1024612D03*
Y1551262D03*
X1027212D03*
X1024612Y1545262D03*
X1027212D03*
X1024612Y1548262D03*
X1027212D03*
X1024612Y1542262D03*
X1027212D03*
Y1539262D03*
X1024612D03*
X1031002Y1554364D03*
X1024612Y1554262D03*
X1027212D03*
X1036002Y1554364D03*
X1035720Y1579240D03*
Y1573240D03*
Y1576240D03*
X1030942Y1586090D03*
X1033942D03*
X1024942D03*
X1027942D03*
X1028298Y1604000D03*
X1025298D03*
X1040970Y128332D03*
X1043720Y363462D03*
X1054820Y370162D03*
X1044120Y366362D03*
X1040120Y393962D03*
X1042720D03*
X1041420Y443962D03*
X1043920D03*
X1050470Y447062D03*
X1041444Y506504D03*
X1053690Y520760D03*
X1045720Y591672D03*
X1043260Y601272D03*
X1045760Y596272D03*
X1048260Y601272D03*
X1051680Y614772D03*
X1053745Y742341D03*
X1053354Y1286714D03*
Y1291714D03*
X1039510Y1296655D03*
X1049510D03*
X1044510D03*
X1039510Y1293155D03*
X1049510D03*
X1044510D03*
X1053354Y1296714D03*
X1041798Y1536262D03*
X1047798D03*
X1050498D03*
X1044798D03*
X1039298D03*
X1041798Y1551262D03*
X1039298D03*
X1041798Y1545262D03*
X1039298D03*
X1041798Y1548262D03*
X1039298D03*
X1047798Y1551262D03*
X1050498D03*
X1047798Y1545262D03*
X1050498D03*
X1047798Y1548262D03*
X1050498D03*
X1044798Y1551262D03*
Y1545262D03*
Y1548262D03*
X1039298Y1542262D03*
X1044798D03*
X1050498D03*
X1047798D03*
X1041798D03*
X1044798Y1539262D03*
X1050498D03*
X1047798D03*
X1039298D03*
X1041798D03*
X1054368Y1554364D03*
X1041798Y1554262D03*
X1039298D03*
X1047798D03*
X1050498D03*
X1044798D03*
X1053612Y1586010D03*
X1056898Y1604000D03*
X1067220Y145362D03*
Y142862D03*
Y148362D03*
X1059943Y435314D03*
X1062120Y477462D03*
X1056190Y520760D03*
X1058220Y585862D03*
X1061470D03*
X1056220Y605052D03*
X1055205Y744853D03*
X1063354Y1286714D03*
X1058354D03*
X1063354Y1291714D03*
X1058354D03*
X1063354Y1296714D03*
X1058290Y1296302D03*
X1071179Y1294669D03*
X1066462Y1520088D03*
X1065164Y1536262D03*
X1062464D03*
X1071164D03*
X1068164D03*
X1065164Y1551262D03*
X1062464D03*
X1065164Y1545262D03*
X1062464D03*
X1065164Y1548262D03*
X1062464D03*
X1071164Y1551262D03*
Y1545262D03*
Y1548262D03*
X1068164Y1551262D03*
Y1545262D03*
Y1548262D03*
Y1542262D03*
X1071164D03*
X1062464D03*
X1065164D03*
X1068164Y1539262D03*
X1071164D03*
X1062464D03*
X1065164D03*
Y1554262D03*
X1062464D03*
X1071164D03*
X1068164D03*
X1059368Y1554364D03*
X1059086Y1579240D03*
Y1573240D03*
Y1576240D03*
X1062612Y1586010D03*
X1065612D03*
X1056612D03*
X1059612D03*
X1059898Y1604000D03*
X1071920Y53862D03*
X1079114Y75775D03*
X1080168Y90721D03*
X1081282Y180937D03*
X1086756Y187540D03*
X1077973Y246362D03*
X1083973D03*
X1080973D03*
X1077883Y260842D03*
X1076823Y265438D03*
X1083823D03*
X1083883Y260842D03*
X1080883D03*
X1080323Y265438D03*
X1082853Y269492D03*
X1079853D03*
X1075400Y273762D03*
X1078400D03*
X1081400D03*
X1084400D03*
X1087400D03*
X1076018Y289400D03*
X1079018D03*
X1082018D03*
X1085018D03*
X1084130Y298342D03*
X1086630D03*
X1076353Y363966D03*
X1078853D03*
X1087330Y369061D03*
Y374131D03*
Y379251D03*
X1075462Y386723D03*
X1078151Y413911D03*
X1078120Y411262D03*
X1084245Y435437D03*
X1078545Y435637D03*
X1081045D03*
X1087280Y435437D03*
X1076598Y477087D03*
X1081930Y477132D03*
X1079320Y473892D03*
X1076820D03*
X1073589Y506461D03*
X1082220Y522362D03*
X1085720Y522422D03*
X1073250Y582332D03*
X1084637Y744635D03*
X1083714Y1285144D03*
Y1288144D03*
Y1291144D03*
X1077634Y1294869D03*
X1074387Y1294652D03*
X1074010Y1510650D03*
X1073864Y1536262D03*
X1085830D03*
X1073864Y1551262D03*
Y1545262D03*
Y1548262D03*
X1085830Y1551262D03*
Y1545262D03*
Y1548262D03*
Y1542262D03*
X1073864D03*
X1085830Y1539262D03*
X1073864D03*
X1077734Y1554364D03*
X1073864Y1554262D03*
X1085830D03*
X1082734Y1554364D03*
X1084000Y1647110D03*
X1094644Y67992D03*
X1090279Y126524D03*
X1105580Y132822D03*
X1100630Y130376D03*
X1099030Y245140D03*
X1088018Y289400D03*
X1089130Y298342D03*
X1091630D03*
X1094130D03*
X1089660Y408560D03*
X1095820Y420762D03*
X1090245Y435437D03*
X1093497Y744655D03*
X1089714Y1285144D03*
X1105480Y1517982D03*
X1088530Y1536262D03*
X1091530D03*
X1088530Y1551262D03*
Y1545262D03*
Y1548262D03*
X1094530Y1551262D03*
X1097230D03*
X1094530Y1545262D03*
X1097230D03*
X1094530Y1548262D03*
X1097230D03*
X1091530Y1551262D03*
Y1545262D03*
Y1548262D03*
Y1542262D03*
X1097230D03*
X1094530D03*
X1088530D03*
X1091530Y1539262D03*
X1094530D03*
X1088530D03*
X1101600Y1554364D03*
X1104750Y1549346D03*
X1088530Y1554262D03*
X1094530D03*
X1097230D03*
X1091530D03*
X1092302Y1585650D03*
X1089302D03*
X1098302D03*
X1095302D03*
X1095436Y1603944D03*
X1092436D03*
X1088790Y1641830D03*
X1094225Y1671710D03*
X1091880Y1673720D03*
X1110977Y55505D03*
X1110754Y60028D03*
X1113594Y69862D03*
X1109020Y80592D03*
X1118309Y111687D03*
X1115860Y113883D03*
X1118486Y208942D03*
X1111918Y234718D03*
X1109088Y234668D03*
X1111918Y237718D03*
Y240718D03*
X1109088Y237668D03*
Y240668D03*
X1120190Y255652D03*
X1117820Y456132D03*
X1113207Y744455D03*
X1115853Y1426342D03*
Y1435532D03*
X1114400Y1518237D03*
X1110725Y1518046D03*
X1113725Y1530935D03*
X1115802Y1615010D03*
X1117407Y1628495D03*
X1113990Y1631370D03*
X1113325Y1627975D03*
X1117182Y1625460D03*
X1106480Y1641275D03*
X1113110Y1666460D03*
X1108320Y1680200D03*
X1112130Y1711600D03*
X1112252Y1706170D03*
X1112200Y1709000D03*
X1114150Y1715726D03*
X1110663Y1719189D03*
X1119200Y1730300D03*
Y1727200D03*
X1114300Y1722700D03*
X1119300Y1724100D03*
X1132547Y64864D03*
X1129997Y69864D03*
X1122278Y107549D03*
X1120420Y109829D03*
X1124858Y197309D03*
X1128485Y198159D03*
X1133041Y194137D03*
X1124360Y259712D03*
X1125409Y305797D03*
X1122059Y305673D03*
X1124985Y302578D03*
X1127402Y456174D03*
X1136051Y503324D03*
X1124120Y643762D03*
X1136720Y641362D03*
X1133720Y642862D03*
X1129420Y644062D03*
X1122980Y741312D03*
X1127972Y747250D03*
X1135750Y1255672D03*
X1127179Y1372700D03*
X1124679D03*
Y1370200D03*
X1127179D03*
X1129729Y1372700D03*
Y1370200D03*
Y1375200D03*
X1127179D03*
X1124679D03*
X1129729Y1377700D03*
Y1380200D03*
Y1385200D03*
Y1382700D03*
X1127179D03*
X1124679D03*
X1127179Y1380200D03*
Y1377700D03*
X1124679D03*
Y1380200D03*
Y1385200D03*
X1127179D03*
X1122879Y1431474D03*
Y1434024D03*
X1125995Y1439780D03*
X1123379Y1443583D03*
X1133169Y1445690D03*
X1129169Y1442998D03*
X1135568Y1442923D03*
X1129169Y1445719D03*
X1130841Y1462953D03*
X1128341Y1465453D03*
Y1462953D03*
X1130841Y1465453D03*
X1133841Y1462953D03*
Y1465453D03*
X1128341Y1468453D03*
X1130841D03*
X1133841D03*
X1128341Y1460453D03*
X1130841D03*
X1133841D03*
Y1471453D03*
X1130841D03*
X1128341D03*
X1132187Y1582738D03*
X1135187D03*
X1132187Y1590738D03*
X1135187D03*
X1124862Y1615010D03*
X1140242Y101135D03*
X1152720Y180862D03*
X1148795Y213731D03*
X1141957Y227277D03*
X1144457D03*
X1139457D03*
X1146670Y230110D03*
X1147700Y362731D03*
X1137315Y379592D03*
X1147700Y368041D03*
X1138551Y503324D03*
X1144720Y501362D03*
Y498662D03*
X1142967Y592097D03*
X1138500Y586362D03*
X1142127Y586452D03*
X1140697Y608762D03*
X1150140Y610362D03*
X1144810Y613762D03*
X1142674Y1287608D03*
X1144247Y1372700D03*
Y1370200D03*
X1146797Y1372700D03*
X1149297D03*
X1146797Y1370200D03*
X1149297D03*
X1144247Y1375200D03*
X1146797D03*
X1149297D03*
X1144247Y1377700D03*
Y1380200D03*
Y1385200D03*
Y1382700D03*
X1146797D03*
X1149297D03*
X1146797Y1380200D03*
Y1377700D03*
X1149297Y1380200D03*
Y1377700D03*
Y1385200D03*
X1146797D03*
X1146563Y1436334D03*
X1141903D03*
X1144233Y1435584D03*
X1139573D03*
X1149469Y1437098D03*
X1151669Y1435698D03*
Y1438598D03*
X1137311Y1445191D03*
X1147203Y1441968D03*
X1149569Y1440098D03*
X1151669Y1441498D03*
X1147203Y1439068D03*
X1141591Y1462853D03*
Y1465353D03*
Y1468353D03*
Y1471353D03*
Y1460353D03*
X1150821Y1459607D03*
Y1456587D03*
X1138430Y1524150D03*
X1151497Y1524187D03*
X1153465Y1550301D03*
X1149528D03*
X1145410Y1540640D03*
X1143060Y1538380D03*
X1141654Y1550301D03*
X1137717Y1558020D03*
X1141690Y1552920D03*
X1152187Y1574738D03*
X1142187D03*
X1145187D03*
X1142187Y1582738D03*
X1145187D03*
X1152187D03*
X1141525Y1597630D03*
X1152187Y1590738D03*
X1142187D03*
X1145187D03*
X1140750Y1604330D03*
X1150380Y1602590D03*
X1146960Y1618960D03*
X1152257Y1628910D03*
X1155703Y73679D03*
X1165440Y176450D03*
X1168710Y176590D03*
X1159460Y194090D03*
X1160630Y213870D03*
X1159753Y361281D03*
X1159460Y366025D03*
X1156790Y363231D03*
X1161690Y374110D03*
X1164320Y451062D03*
X1156100Y456342D03*
X1167190Y526922D03*
X1158300Y585862D03*
X1170740Y602132D03*
X1155962Y746193D03*
X1156609Y1286685D03*
X1165279Y1372700D03*
X1162779D03*
X1167829D03*
X1162779Y1370200D03*
X1165279D03*
X1167829D03*
X1162779Y1375200D03*
X1165279D03*
X1167829D03*
Y1377700D03*
Y1380200D03*
Y1385200D03*
Y1382700D03*
X1165279D03*
X1162779D03*
X1165279Y1380200D03*
X1162779D03*
Y1377700D03*
X1165279D03*
X1162779Y1385200D03*
X1165279D03*
X1161022Y1431499D03*
Y1433999D03*
X1164138Y1439780D03*
X1154288Y1432502D03*
X1161522Y1443630D03*
X1167312Y1442998D03*
Y1445964D03*
X1159386Y1464253D03*
Y1466753D03*
X1156386Y1464253D03*
Y1466753D03*
X1159386Y1469253D03*
X1156386D03*
X1153821Y1459607D03*
Y1456587D03*
X1159386Y1461753D03*
X1159476Y1458918D03*
X1156386Y1461753D03*
X1156476Y1458918D03*
X1159446Y1456113D03*
X1156446D03*
X1167245Y1524187D03*
X1159371D03*
X1163308D03*
X1155433D03*
X1165276Y1550301D03*
X1169213D03*
X1157402D03*
X1161339D03*
X1161595Y1574738D03*
X1164595D03*
X1155187D03*
X1161595Y1582738D03*
X1164595D03*
X1155187D03*
X1163079Y1601479D03*
X1161595Y1590738D03*
X1164595D03*
X1155187D03*
X1169460Y1606630D03*
Y1616630D03*
Y1611630D03*
X1158030Y1619250D03*
X1164830Y1628830D03*
X1163970Y1620600D03*
X1169325Y1642600D03*
X1158325D03*
X1162383Y1652505D03*
X1164830Y1654632D03*
X1159930D03*
X1161076Y1680624D03*
X1157700Y1681100D03*
X1174120Y57111D03*
X1175926Y69151D03*
X1180676Y106858D03*
X1187413Y143132D03*
X1181420Y157962D03*
X1181700Y186962D03*
X1173314Y176452D03*
X1170595Y170056D03*
X1181476Y172247D03*
X1184510Y188962D03*
X1173100Y186962D03*
X1172925Y202174D03*
X1181369Y199234D03*
X1183460Y205342D03*
X1181470Y208802D03*
X1172835Y218174D03*
X1181500Y211962D03*
Y218462D03*
Y215962D03*
Y222162D03*
X1186653Y302242D03*
X1181450Y306052D03*
X1174120Y355362D03*
X1169690Y526922D03*
X1172310Y584562D03*
X1181300Y584762D03*
X1177570Y602052D03*
X1175217Y595762D03*
X1173020Y745972D03*
X1175573Y1286765D03*
X1172573D03*
X1182747Y1372700D03*
X1185297D03*
X1182747Y1370200D03*
X1185297D03*
X1182747Y1375200D03*
X1185297D03*
X1182747Y1380200D03*
Y1377700D03*
Y1385200D03*
Y1382700D03*
X1185297D03*
Y1377700D03*
Y1380200D03*
Y1385200D03*
X1184706Y1436334D03*
X1180046D03*
X1182376Y1435584D03*
X1177716D03*
X1171342Y1445650D03*
X1175454Y1445191D03*
X1173711Y1442923D03*
X1171182Y1524187D03*
X1184330Y1573260D03*
X1184290Y1570080D03*
X1171595Y1574738D03*
X1174595D03*
X1171595Y1582738D03*
X1174595D03*
X1183410Y1594450D03*
X1183440Y1591640D03*
X1171595Y1590738D03*
X1174595D03*
X1178140Y1601100D03*
X1184200Y1599900D03*
X1183320Y1597080D03*
X1169968Y1602370D03*
X1174550Y1615630D03*
X1178250Y1609100D03*
X1184200Y1602700D03*
X1185030Y1624660D03*
X1180325Y1642600D03*
X1173383Y1652505D03*
X1184383D03*
X1181930Y1654632D03*
X1175830D03*
X1170930D03*
X1183076Y1680624D03*
X1172076D03*
X1194478Y56986D03*
X1197520Y56962D03*
X1201158Y57130D03*
X1189393Y60183D03*
X1188700Y100700D03*
X1185400Y104000D03*
X1193532Y132644D03*
X1194800Y143112D03*
X1197414Y161592D03*
X1191020Y170862D03*
X1185420Y153762D03*
X1200720Y184862D03*
X1188300Y189062D03*
X1200720Y187862D03*
X1200963Y212648D03*
X1200830Y206002D03*
X1186340Y204492D03*
X1187300Y217862D03*
X1188500Y205772D03*
X1188600Y225962D03*
X1187013Y238972D03*
X1194840Y236592D03*
X1199720Y252362D03*
X1196720D03*
X1188810Y296088D03*
X1186280Y298972D03*
X1193198Y586172D03*
X1195698D03*
X1198198D03*
X1200698D03*
X1185687Y744475D03*
X1187797Y1372700D03*
Y1370200D03*
Y1375200D03*
Y1382700D03*
Y1377700D03*
Y1380200D03*
Y1385200D03*
X1187412Y1437498D03*
X1189612Y1436098D03*
X1191918Y1432516D03*
X1185346Y1442128D03*
X1187512Y1440498D03*
X1189612Y1441898D03*
X1185346Y1439228D03*
X1189612Y1438998D03*
X1187720Y1517688D03*
X1187830Y1522188D03*
X1198546Y1520188D03*
X1187830Y1526688D03*
X1198546Y1524688D03*
X1187720Y1536362D03*
X1198485Y1534313D03*
X1198436Y1529362D03*
X1187720Y1531862D03*
Y1553692D03*
X1198497Y1539667D03*
X1187720Y1548772D03*
X1198436Y1546492D03*
X1187720Y1544292D03*
X1198436Y1551192D03*
Y1556192D03*
Y1561062D03*
X1187720Y1558682D03*
Y1563182D03*
X1194510Y1563076D03*
X1187600Y1622064D03*
X1201600Y1633790D03*
X1199400Y1627800D03*
X1190895Y1642910D03*
X1186000Y1640000D03*
X1197400Y1654942D03*
X1192500D03*
X1186830Y1654632D03*
X1193646Y1680934D03*
X1201106Y1677873D03*
X1190735Y1688390D03*
X1194793Y1698295D03*
X1201505Y1688435D03*
X1192340Y1700422D03*
X1197240D03*
X1193174Y1726414D03*
X1216176Y56742D03*
X1202860Y120392D03*
X1215763Y114363D03*
X1215800Y111300D03*
X1201700Y110000D03*
X1202920Y117162D03*
X1210910Y129502D03*
X1206114Y132962D03*
X1206434Y129492D03*
X1206694Y139512D03*
X1214415Y153962D03*
X1206664Y158952D03*
X1214091Y164962D03*
X1214534Y157462D03*
X1214054Y186092D03*
X1214693Y174962D03*
X1214134Y180972D03*
X1213720Y200309D03*
Y189362D03*
X1204220D03*
X1213720Y195362D03*
X1215720Y204862D03*
X1203200Y202514D03*
X1219060Y213312D03*
X1206660Y224742D03*
X1213540Y224792D03*
X1207220Y243998D03*
X1210900Y265300D03*
X1204475Y350684D03*
X1205165Y380962D03*
X1218870Y418082D03*
X1214000Y599262D03*
X1208980Y598462D03*
X1207100Y600882D03*
X1211277Y744265D03*
X1206757Y744455D03*
X1210288Y754081D03*
X1202300Y753962D03*
X1207607Y754095D03*
X1215896Y756942D03*
X1206432Y758995D03*
X1202307Y757082D03*
X1205820Y1652910D03*
X1210830Y1676500D03*
X1217210Y1684520D03*
X1212305Y1688700D03*
X1216363Y1698605D03*
X1205563Y1698340D03*
X1207180Y1685680D03*
X1208010Y1700467D03*
X1213910Y1700732D03*
X1203110Y1700467D03*
X1203939Y1726459D03*
X1214834Y1726724D03*
X1228425Y91500D03*
X1222100Y91600D03*
X1225100Y91500D03*
X1225700Y108962D03*
X1232182Y110659D03*
X1224614Y116962D03*
X1219534Y116492D03*
X1223500Y111162D03*
X1226400Y125200D03*
X1226093Y134262D03*
X1229500Y125100D03*
X1223100Y130700D03*
X1234093Y144962D03*
X1226093Y140962D03*
X1222593D03*
X1222920Y144909D03*
Y148909D03*
X1222593Y168962D03*
X1222890Y157002D03*
X1226093Y156962D03*
X1222594Y154242D03*
X1226093Y168162D03*
X1225874Y163462D03*
X1222720Y163362D03*
X1226093Y177962D03*
X1222724Y176102D03*
X1226093Y172962D03*
X1223134Y190802D03*
X1225574Y188662D03*
X1228520Y202162D03*
X1229720Y197302D03*
X1226093Y193462D03*
X1225320Y200162D03*
X1233282Y201875D03*
X1223180Y210552D03*
X1233780Y214572D03*
X1231720Y217862D03*
Y209862D03*
X1219220Y243862D03*
Y247148D03*
X1230720Y380362D03*
X1221220D03*
X1232720Y377862D03*
X1224300Y380400D03*
X1223650Y520672D03*
X1230650D03*
X1227150D03*
X1219060Y757272D03*
X1223327Y757615D03*
X1228320Y758598D03*
X1218810Y1700732D03*
X1236620Y58862D03*
X1241010Y110782D03*
X1250010Y117121D03*
X1244200Y112862D03*
X1249362Y111600D03*
X1241035Y114399D03*
X1234746Y136040D03*
X1240728Y136198D03*
X1240904Y151592D03*
X1238604Y150062D03*
X1241100Y145842D03*
X1244120Y167462D03*
X1246272Y164889D03*
X1243100Y160181D03*
X1243184Y182422D03*
X1239874Y182322D03*
X1236410Y201462D03*
X1236220Y189362D03*
X1236593Y197462D03*
X1236584Y205762D03*
X1245486Y203000D03*
X1245593Y211762D03*
X1236620Y221562D03*
X1244720Y230362D03*
X1245514Y224302D03*
X1245593Y219662D03*
X1239045Y224062D03*
X1246878Y248615D03*
X1240500Y248332D03*
Y244332D03*
X1236720Y257362D03*
X1243589Y379595D03*
X1236720Y377862D03*
X1234720Y380362D03*
X1248150Y520672D03*
X1244650D03*
X1241150D03*
X1237650D03*
X1234150D03*
X1242260Y757602D03*
X1261227Y52061D03*
X1258727D03*
X1263454Y83060D03*
X1266464Y83090D03*
X1264098Y88787D03*
X1262320Y96012D03*
X1258539Y100900D03*
X1252520Y92022D03*
X1258539Y109263D03*
X1260641Y114399D03*
X1264220Y110462D03*
X1250424Y108943D03*
X1257581Y114579D03*
X1256093Y149462D03*
X1264663Y158946D03*
X1254994Y157382D03*
X1265010Y162222D03*
X1261899Y174648D03*
X1253624Y201362D03*
X1267315Y220701D03*
X1264874Y217462D03*
X1256504D03*
X1255613Y209568D03*
X1265207Y208442D03*
X1259703Y209808D03*
X1253440Y230552D03*
X1253860Y235622D03*
X1256070Y229512D03*
X1264584Y226592D03*
X1256593Y221462D03*
Y233972D03*
Y225972D03*
X1253950Y246692D03*
X1266715Y244692D03*
X1254370Y241302D03*
X1265065Y249982D03*
X1256494Y243177D03*
X1256574Y238662D03*
X1266518Y237042D03*
X1256584Y248002D03*
X1256454Y252122D03*
X1264854Y253996D03*
Y256496D03*
X1258883Y280558D03*
X1258250Y292986D03*
X1263150Y294726D03*
X1255150Y306211D03*
X1256220Y434362D03*
X1261220Y454362D03*
X1253220Y451362D03*
X1267220D03*
X1260220Y477362D03*
X1255920Y511362D03*
X1251650Y520672D03*
X1255150D03*
X1258667Y751405D03*
X1255520Y747362D03*
X1263486Y739949D03*
X1257672Y1351008D03*
X1276820Y58142D03*
X1282360Y58132D03*
X1279580D03*
X1279390Y87697D03*
X1275820Y87962D03*
X1270329Y101011D03*
X1266722Y101005D03*
X1278456Y96187D03*
X1279415Y90847D03*
X1281704Y95402D03*
X1282824Y108872D03*
X1271284Y108971D03*
X1282764Y135398D03*
X1277820Y140682D03*
X1281093Y144516D03*
X1271954Y159143D03*
X1271593Y165962D03*
X1278093Y184462D03*
X1278993Y193262D03*
X1273093Y200038D03*
X1278183Y201262D03*
X1275493Y193962D03*
X1267289Y192167D03*
X1269904Y192692D03*
X1272893Y191262D03*
X1271315Y220701D03*
X1267773Y208373D03*
X1273093Y213962D03*
X1275727Y209597D03*
X1267618Y225382D03*
X1277661Y225685D03*
X1267593Y229462D03*
X1278783Y221386D03*
X1282176Y221436D03*
X1282654Y226309D03*
X1278320Y239292D03*
X1279493Y248662D03*
X1282645Y255671D03*
Y252271D03*
X1277771Y255173D03*
X1273754Y256504D03*
X1276800Y276562D03*
X1269960Y294536D03*
X1271150Y305792D03*
X1272530Y429362D03*
X1284220D03*
X1280270Y434362D03*
X1272220D03*
X1278380Y463362D03*
X1276220Y477362D03*
X1283220D03*
X1269220D03*
X1274420Y463362D03*
X1275576Y730879D03*
X1266727Y752955D03*
X1279788Y1304042D03*
X1279812Y1353552D03*
X1279334Y1356089D03*
X1275856Y1358098D03*
X1271990Y1358079D03*
X1276891Y1362891D03*
X1282928Y1361833D03*
X1269012Y1371693D03*
Y1368293D03*
X1290291Y-23211D03*
Y-19811D03*
X1285201Y58121D03*
X1293454Y81232D03*
X1289210D03*
X1298640Y93062D03*
X1292880Y93162D03*
X1292899Y98519D03*
X1294354Y103166D03*
X1291704Y109427D03*
X1288093Y125962D03*
X1291478Y137745D03*
X1286150Y131092D03*
X1297605Y145824D03*
X1285710Y249182D03*
X1290293Y247562D03*
X1288637Y240448D03*
X1292630Y240462D03*
X1291071Y275543D03*
Y278543D03*
X1290005Y293768D03*
Y290268D03*
X1294500Y299692D03*
X1291100D03*
X1291500Y312862D03*
Y315362D03*
X1291420Y320662D03*
Y318162D03*
X1295540Y440902D03*
X1301310Y440862D03*
X1291220Y463362D03*
X1294440Y477267D03*
X1296630Y463462D03*
X1300220Y477362D03*
X1284220Y463362D03*
X1289936Y732539D03*
X1290520Y746562D03*
X1292572Y785575D03*
X1297298Y790982D03*
X1296719Y1290197D03*
X1299169Y1295467D03*
Y1297967D03*
X1296569D03*
Y1295467D03*
Y1292967D03*
X1299169D03*
X1296581Y1300474D03*
X1299181D03*
X1296576Y1303298D03*
X1299176D03*
X1290102Y1365789D03*
X1286102Y1365051D03*
X1294312Y1367279D03*
X1292840Y1364821D03*
X1286102Y1368107D03*
X1298836Y1358387D03*
X1296506Y1357637D03*
X1301820Y58672D03*
X1311424Y68652D03*
X1308174D03*
X1311960Y58152D03*
X1311260Y83032D03*
X1310857Y78542D03*
X1307120Y78562D03*
X1310906Y97807D03*
X1314406Y97756D03*
X1308274Y104162D03*
X1314059Y93877D03*
X1307244Y118452D03*
X1306836Y108242D03*
X1302080Y117032D03*
X1302060Y113852D03*
X1300990Y121812D03*
X1315156Y130656D03*
X1314920Y135361D03*
X1313117Y250605D03*
X1314685Y248651D03*
X1307431Y256099D03*
X1309283Y254162D03*
X1311275Y252297D03*
X1305552Y257974D03*
X1308736Y284948D03*
X1312136D03*
X1307042Y292636D03*
X1303642D03*
X1307442Y306998D03*
X1304042D03*
X1317100Y553900D03*
X1308600Y653500D03*
X1303576Y659671D03*
X1311420Y738262D03*
X1305187Y735630D03*
X1315020Y739862D03*
X1307469Y787772D03*
X1301034Y784165D03*
X1304260Y788265D03*
X1309930Y789852D03*
X1306701Y794779D03*
X1305117Y797125D03*
X1309210Y792802D03*
X1315169Y1274887D03*
X1315289Y1269717D03*
X1315229Y1272287D03*
X1304149Y1291317D03*
X1301889Y1284987D03*
X1301829Y1290167D03*
X1301859Y1287587D03*
X1304299Y1280967D03*
X1304269Y1283567D03*
X1304239Y1286147D03*
X1304209Y1288747D03*
X1315176Y1280218D03*
X1315181Y1277594D03*
X1299319Y1290197D03*
X1299349Y1287617D03*
X1301686Y1303268D03*
X1304196Y1299248D03*
X1304189Y1293917D03*
X1304201Y1296624D03*
X1301679Y1292937D03*
Y1295437D03*
Y1297937D03*
X1301691Y1300444D03*
X1311820Y1330518D03*
Y1333018D03*
X1314936Y1338799D03*
X1312650Y1342572D03*
X1308616Y1363345D03*
Y1360445D03*
X1306082Y1359315D03*
X1306182Y1362315D03*
X1304016Y1363945D03*
Y1361045D03*
X1308616Y1357945D03*
X1303496Y1358387D03*
X1301166Y1357637D03*
X1316459Y58697D03*
X1322248Y68487D03*
X1321279Y58767D03*
X1317831Y68652D03*
X1322415Y75480D03*
X1322906Y94212D03*
X1319968Y98266D03*
X1329891Y99455D03*
X1329646Y104954D03*
X1322906Y109733D03*
X1323912Y245111D03*
X1320387Y258901D03*
X1325769Y259001D03*
X1325414Y293556D03*
X1328814D03*
X1319903Y299176D03*
X1323303D03*
X1330101Y540049D03*
X1328530Y747702D03*
X1325210Y744322D03*
X1331519Y1262027D03*
X1331459Y1264597D03*
X1331399Y1267197D03*
X1317889Y1267147D03*
X1320399Y1267117D03*
X1317883Y1269978D03*
X1317895Y1272485D03*
X1320393Y1269948D03*
X1320405Y1272455D03*
X1331177Y1269933D03*
Y1272433D03*
X1317895Y1274985D03*
X1320405Y1274955D03*
X1331177Y1274933D03*
X1331166Y1280248D03*
X1317746D03*
X1320256Y1280218D03*
X1317895Y1277485D03*
X1320405Y1277455D03*
X1331189Y1277440D03*
X1328514Y1334603D03*
X1330844Y1335353D03*
X1322110Y1342755D03*
X1318110Y1342017D03*
X1326320Y1344245D03*
X1324848Y1341787D03*
X1318110Y1345073D03*
X1331288Y1372440D03*
X1327491Y1372358D03*
X1324491Y1372658D03*
X1327491Y1375858D03*
X1331288Y1375940D03*
X1324491Y1375858D03*
X1327491Y1381478D03*
Y1378478D03*
X1331288Y1378560D03*
X1324491Y1381478D03*
Y1378478D03*
X1331304Y1401986D03*
Y1404986D03*
X1327926D03*
X1322228Y1419890D03*
X1322186Y1411326D03*
Y1414326D03*
Y1417326D03*
X1322270Y1422454D03*
X1325084Y1420066D03*
X1325042Y1408502D03*
Y1411502D03*
Y1417502D03*
Y1414502D03*
X1331344Y1414456D03*
X1330804Y1411536D03*
Y1408536D03*
X1331386Y1420020D03*
X1328008D03*
X1331344Y1417456D03*
X1327966Y1408456D03*
Y1411456D03*
Y1417456D03*
Y1414456D03*
X1331428Y1422584D03*
X1328050D03*
X1322312Y1425018D03*
X1325126Y1422630D03*
X1325168Y1425194D03*
X1328092Y1425148D03*
X1331470D03*
X1341752Y-19811D03*
Y-23211D03*
X1333190Y58825D03*
X1347640Y101950D03*
X1345583Y91307D03*
X1336549Y105970D03*
X1344631Y127244D03*
X1332497Y133931D03*
X1343034Y141698D03*
X1344684Y280259D03*
X1336761Y293404D03*
X1340161D03*
X1344720Y423162D03*
X1337220D03*
X1342220D03*
X1339720D03*
X1333143Y540049D03*
X1340420Y538422D03*
Y541822D03*
X1347419Y1259257D03*
X1347379Y1256687D03*
X1336269Y1274957D03*
X1333969Y1264567D03*
X1334029Y1261997D03*
X1333909Y1267167D03*
X1336339Y1269777D03*
X1336279Y1272347D03*
X1347359Y1261857D03*
X1347371Y1264564D03*
X1336519Y1264627D03*
X1336579Y1262057D03*
X1347366Y1267188D03*
X1336459Y1267227D03*
X1333687Y1269903D03*
Y1272403D03*
Y1274903D03*
X1333676Y1280218D03*
X1336261Y1277654D03*
X1333699Y1277410D03*
X1343948Y1317092D03*
Y1319592D03*
X1344532Y1328161D03*
X1347397Y1325320D03*
X1336144Y1341147D03*
X1338288Y1339653D03*
X1340488Y1340853D03*
X1336144Y1338247D03*
X1340214Y1334853D03*
X1340410Y1338017D03*
X1338288Y1336553D03*
X1333174Y1334603D03*
X1335504Y1335353D03*
X1334288Y1372440D03*
X1340288D03*
X1346193Y1372523D03*
X1343193D03*
X1337288Y1372440D03*
Y1375940D03*
X1334288D03*
X1343193Y1376023D03*
X1346193D03*
X1340288Y1375940D03*
X1346304Y1401986D03*
X1343304D03*
X1340304D03*
X1337304D03*
X1334304D03*
Y1404986D03*
X1346304D03*
X1343304D03*
X1340304D03*
X1337304D03*
X1337344Y1414456D03*
X1346344D03*
X1343344D03*
X1340344D03*
X1346534Y1411496D03*
Y1408496D03*
X1334344Y1414456D03*
X1346344Y1417456D03*
X1340344D03*
X1337344D03*
X1334386Y1420020D03*
X1334344Y1417456D03*
X1346386Y1420020D03*
X1343386D03*
X1340386D03*
X1337386D03*
X1343344Y1417456D03*
X1337428Y1422584D03*
X1340428D03*
X1343428D03*
X1334428D03*
X1337328Y1425164D03*
X1340328D03*
X1343328D03*
X1346178Y1425254D03*
X1346278Y1422674D03*
X1334470Y1425148D03*
X1348610Y84712D03*
X1349480Y77072D03*
X1366369Y83820D03*
X1349570Y104147D03*
X1353394Y131812D03*
X1348620Y136162D03*
X1349220Y140362D03*
X1348084Y280259D03*
X1358624Y284644D03*
X1355224D03*
X1356220Y581862D03*
X1356047Y680000D03*
X1358907Y681262D03*
X1361727Y680665D03*
X1352474Y1256866D03*
X1349964Y1256896D03*
X1352486Y1259373D03*
X1349976Y1259403D03*
X1363258Y1256851D03*
Y1259351D03*
X1349876Y1267158D03*
X1352426Y1267218D03*
X1363266Y1267188D03*
X1349976Y1261903D03*
X1352486Y1261873D03*
Y1264373D03*
X1349976Y1264403D03*
X1363258Y1261851D03*
X1363270Y1264358D03*
X1360593Y1321872D03*
X1363098Y1320951D03*
X1354238Y1329329D03*
X1350238Y1328591D03*
X1358448Y1330819D03*
X1356976Y1328361D03*
X1350238Y1331647D03*
X1352666Y1378560D03*
X1349666D03*
X1352666Y1381560D03*
X1349666D03*
X1352666Y1375940D03*
X1349666D03*
X1352126Y1401986D03*
X1349426D03*
X1352126Y1404986D03*
X1349426D03*
X1349508Y1420020D03*
X1352166Y1420456D03*
Y1414456D03*
Y1411456D03*
Y1408456D03*
Y1417456D03*
X1349466Y1411456D03*
Y1408456D03*
Y1417456D03*
Y1414456D03*
X1349278Y1422674D03*
X1364860Y1455172D03*
X1362410Y1445272D03*
X1378839Y87626D03*
X1366369Y92450D03*
X1366714Y109506D03*
X1376991Y176430D03*
X1373591D03*
X1375619Y236261D03*
X1375257Y229756D03*
X1373493Y227762D03*
X1380522Y260236D03*
Y263636D03*
X1368524Y282744D03*
X1365124D03*
X1378306Y657608D03*
X1374668Y659708D03*
X1378306Y669608D03*
X1374668Y671708D03*
X1370207Y682245D03*
X1374668Y683708D03*
X1378306Y681608D03*
X1374668Y695708D03*
X1378306Y693608D03*
Y705608D03*
X1374668Y707708D03*
Y719708D03*
X1378306Y717608D03*
X1374938Y1161569D03*
Y1170069D03*
X1379579Y1259317D03*
X1368379Y1259287D03*
X1379639Y1256747D03*
X1368439Y1256717D03*
X1365768Y1256821D03*
Y1259321D03*
X1365776Y1267158D03*
X1368326Y1267218D03*
X1379519Y1261917D03*
X1379531Y1264624D03*
X1379526Y1267248D03*
X1368361Y1264594D03*
X1368369Y1261897D03*
X1365768Y1261821D03*
X1365780Y1264328D03*
X1376076Y1317092D03*
Y1319592D03*
X1379192Y1325373D03*
X1368272Y1324821D03*
X1372538Y1324591D03*
X1370338Y1323091D03*
X1372538Y1321691D03*
X1365376Y1321938D03*
X1367635Y1320904D03*
X1377214Y1327653D03*
X1368272Y1327721D03*
X1370438Y1326091D03*
X1372538Y1327491D03*
X1377054Y1394028D03*
X1367316Y1399053D03*
Y1403458D03*
X1370577Y1421899D03*
X1367436Y1414778D03*
X1370891Y1410306D03*
X1378417Y1415292D03*
X1367316Y1407458D03*
X1367889Y1419235D03*
X1377075Y1425014D03*
X1365235Y1428637D03*
X1370250Y1433715D03*
X1367620Y1431472D03*
X1367170Y1453142D03*
X1368842Y1449261D03*
X1364800Y1449231D03*
X1368980Y1457122D03*
X1370041Y1460374D03*
X1393250Y93802D03*
X1386684Y145017D03*
X1386404Y149008D03*
X1394182Y171470D03*
X1398182D03*
X1384002Y197668D03*
X1389256D03*
X1380602D03*
X1392656D03*
X1395960Y226422D03*
X1393460D03*
X1386868Y222937D03*
X1384017Y223697D03*
X1386138Y225411D03*
X1384895Y221346D03*
X1381951Y221420D03*
X1380638Y245694D03*
X1386630Y238651D03*
X1380638Y249094D03*
X1386630Y242051D03*
X1381235Y236020D03*
X1390600Y248262D03*
X1388754Y253803D03*
Y257203D03*
X1386273Y268670D03*
Y272070D03*
X1392685Y498992D03*
X1387550Y502922D03*
X1387600Y499182D03*
X1391260Y507082D03*
X1393206Y664708D03*
X1389568Y662608D03*
X1393206Y679208D03*
X1389568Y677108D03*
X1393206Y693708D03*
X1389568Y691608D03*
Y706108D03*
X1393206Y708208D03*
X1393199Y722708D03*
X1389561Y720608D03*
X1385338Y735098D03*
X1388976Y737198D03*
X1396081Y1161569D03*
Y1153369D03*
Y1170069D03*
X1384652Y1256866D03*
X1382142Y1256896D03*
X1384664Y1259373D03*
X1382154Y1259403D03*
X1395436Y1256851D03*
Y1259351D03*
X1384586Y1267278D03*
X1395426Y1267188D03*
X1382036Y1267218D03*
X1382154Y1261903D03*
X1384664Y1261873D03*
Y1264373D03*
X1382154Y1264403D03*
X1395436Y1261851D03*
X1395448Y1264358D03*
X1392770Y1321177D03*
X1395100Y1321927D03*
X1386366Y1329329D03*
X1382366Y1328591D03*
X1390576Y1330819D03*
X1389104Y1328361D03*
X1382366Y1331647D03*
X1396311Y1385712D03*
X1398680Y1380582D03*
X1390474Y1385142D03*
X1387074Y1384272D03*
X1390513Y1395452D03*
X1387066Y1401734D03*
X1387291Y1408163D03*
X1387470Y1418302D03*
X1385109Y1410427D03*
X1390170Y1423942D03*
X1387068Y1413991D03*
X1381066Y1425008D03*
X1393630Y1426562D03*
X1388557Y1431645D03*
X1395907Y1430227D03*
X1395443Y1434700D03*
X1398569Y1437860D03*
X1383429Y1427652D03*
X1392620Y1446708D03*
X1389220D03*
X1382600Y1563480D03*
X1391655Y1570037D03*
X1391055Y1565037D03*
X1384840Y1565640D03*
X1386790Y1563610D03*
X1396600Y1590200D03*
Y1586400D03*
X1393000Y1590300D03*
X1395325Y1606862D03*
X1386200Y1645700D03*
X1386600Y1641400D03*
X1407029Y152732D03*
X1410370Y138742D03*
X1406970D03*
X1407029Y156132D03*
X1401341Y177159D03*
X1404829Y184263D03*
X1404741Y177159D03*
X1408229Y184263D03*
X1412284Y171696D03*
X1407178Y171684D03*
X1403778D03*
X1398006Y197668D03*
X1406786D03*
X1401406D03*
X1410186D03*
X1413900Y225212D03*
X1396900Y228932D03*
X1398831Y1161569D03*
Y1153369D03*
Y1170069D03*
X1411909Y1259257D03*
X1400599Y1256717D03*
X1411969Y1256687D03*
X1397946Y1256821D03*
Y1259321D03*
X1400539Y1259287D03*
X1400521Y1264594D03*
X1400529Y1261897D03*
X1397936Y1267158D03*
X1400486Y1267218D03*
X1411849Y1261857D03*
X1411861Y1264564D03*
X1411856Y1267188D03*
X1397946Y1261821D03*
X1397958Y1264328D03*
X1408204Y1317092D03*
Y1319592D03*
X1411320Y1325373D03*
X1400400Y1324821D03*
X1404666Y1324591D03*
X1402466Y1323091D03*
X1404666Y1321691D03*
X1397430Y1321177D03*
X1399760Y1321927D03*
X1408969Y1327645D03*
X1402566Y1326091D03*
X1400400Y1327721D03*
X1404666Y1327491D03*
X1401655Y1384676D03*
X1406461Y1383862D03*
X1415171Y1383692D03*
X1412961Y1387387D03*
X1412608Y1391687D03*
X1414362Y1402191D03*
X1414786Y1426890D03*
X1413440Y1436774D03*
X1409680Y1430613D03*
X1401371Y1434592D03*
X1410477Y1440117D03*
X1410038Y1434670D03*
X1403687Y1444711D03*
X1400287D03*
X1400220Y1518862D03*
X1409248Y1528862D03*
X1400160Y1543342D03*
X1404433Y1565037D03*
X1400695Y1570037D03*
X1400715Y1565037D03*
X1407440Y1557552D03*
X1404433Y1570037D03*
X1402536Y1576097D03*
X1402680Y1597700D03*
X1401300Y1619917D03*
X1410900Y1624800D03*
X1400000Y1626362D03*
Y1634362D03*
Y1638362D03*
X1410500Y1638862D03*
X1396900Y1642100D03*
X1413950Y184263D03*
X1423110D03*
X1417350D03*
X1426510D03*
X1415684Y171696D03*
X1428336Y232762D03*
X1415340Y231812D03*
X1418630Y220018D03*
X1422030D03*
X1413847Y239528D03*
X1426020Y261501D03*
X1431430Y256383D03*
Y264060D03*
X1426647Y329050D03*
X1417022Y621419D03*
X1424119Y1161520D03*
X1426619D03*
X1424119Y1153369D03*
X1426619D03*
Y1169570D03*
X1424119D03*
X1416999Y1256866D03*
X1414489Y1256896D03*
X1417011Y1259373D03*
X1414501Y1259403D03*
X1427783Y1256851D03*
Y1259351D03*
X1414366Y1267158D03*
X1416916Y1267218D03*
X1427786Y1267158D03*
X1414501Y1261903D03*
X1417011Y1261873D03*
Y1264373D03*
X1414501Y1264403D03*
X1427783Y1261851D03*
X1427795Y1264358D03*
X1424898Y1321177D03*
X1427228Y1321927D03*
X1418494Y1329329D03*
X1414494Y1328591D03*
X1422704Y1330819D03*
X1421232Y1328361D03*
X1414494Y1331647D03*
X1418990Y1387452D03*
X1422594Y1383301D03*
X1419995Y1397492D03*
X1415620Y1396652D03*
X1419055Y1392497D03*
X1426872Y1405811D03*
X1423256Y1403728D03*
X1424255Y1396612D03*
X1421480Y1415731D03*
X1422371Y1407722D03*
X1421371Y1411719D03*
X1421864Y1419730D03*
X1419991Y1423404D03*
X1424930Y1433850D03*
X1416272Y1433949D03*
X1421435Y1430415D03*
X1419746Y1435932D03*
X1414350Y1516435D03*
X1426020Y1521535D03*
X1414590Y1532255D03*
X1414350Y1521335D03*
X1427120Y1537355D03*
X1414590Y1537155D03*
X1414740Y1543475D03*
Y1548375D03*
X1427320Y1548575D03*
X1425620Y1556662D03*
X1416060Y1574922D03*
X1422680Y1582100D03*
X1419450Y1596150D03*
X1423700Y1600400D03*
X1434600Y59262D03*
X1444275Y57262D03*
X1432220Y61862D03*
X1440800Y66862D03*
X1447340Y157402D03*
X1442434Y210757D03*
X1430120Y225182D03*
X1436060Y220018D03*
X1432660D03*
X1431636Y230448D03*
X1444570Y238372D03*
X1431933Y238125D03*
X1431431Y267378D03*
X1436120Y315772D03*
X1436270Y312592D03*
X1436335Y309407D03*
X1436320Y305862D03*
Y303362D03*
X1436050Y321352D03*
X1436120Y318272D03*
X1436232Y344176D03*
X1433418Y729104D03*
X1444099Y1259397D03*
X1432899Y1259257D03*
X1444159Y1256827D03*
X1432959Y1256687D03*
X1430293Y1256821D03*
Y1259321D03*
X1444051Y1264704D03*
X1444039Y1261997D03*
X1444046Y1267328D03*
X1432889Y1261867D03*
X1432881Y1264564D03*
X1432846Y1267188D03*
X1430296Y1267128D03*
X1430293Y1261821D03*
X1430305Y1264328D03*
X1440332Y1317092D03*
Y1319592D03*
X1443448Y1325373D03*
X1432528Y1324821D03*
X1436794Y1324591D03*
X1434594Y1323091D03*
X1436794Y1321691D03*
X1429558Y1321177D03*
X1431888Y1321927D03*
X1441332Y1327793D03*
X1434694Y1326091D03*
X1432528Y1327721D03*
X1436794Y1327491D03*
X1437443Y1406289D03*
X1444997Y1392885D03*
X1435462Y1393009D03*
Y1396409D03*
X1434312Y1415197D03*
X1443112Y1417929D03*
X1445020Y1412672D03*
X1443676Y1432624D03*
X1433750Y1429208D03*
X1439742Y1436924D03*
X1434720Y1454862D03*
X1440440Y1454892D03*
X1444468Y1570610D03*
X1433720Y1569762D03*
X1440105Y1593352D03*
X1446700Y1598400D03*
X1438300Y1606800D03*
Y1602600D03*
X1430250Y1612812D03*
X1441800Y1628700D03*
Y1624500D03*
X1438547Y1638212D03*
X1443617D03*
X1431575Y1634842D03*
X1442573Y1649862D03*
X1442587Y1659242D03*
X1438320Y1668292D03*
X1438220Y1673955D03*
X1446715Y1679957D03*
X1446000Y67802D03*
X1458720Y145362D03*
X1450270Y143022D03*
X1450720Y153362D03*
X1448820Y148092D03*
X1450720Y169862D03*
Y161862D03*
X1449740Y166912D03*
X1450720Y181862D03*
Y177862D03*
Y173862D03*
X1462561Y205982D03*
X1457361D03*
X1459961Y210432D03*
X1456150Y214382D03*
X1449110Y233742D03*
X1455600Y297200D03*
X1456770Y342942D03*
X1460849Y343327D03*
X1462790Y359042D03*
X1462870Y355012D03*
X1449777Y362021D03*
X1459900Y370823D03*
X1455920Y373941D03*
X1463600Y374462D03*
X1449777Y371039D03*
X1455642Y409646D03*
X1449296Y407347D03*
X1449600Y402322D03*
X1456777Y418596D03*
Y426546D03*
X1457176Y656992D03*
X1460814Y654892D03*
Y666892D03*
X1457176Y668992D03*
X1460814Y678892D03*
X1457176Y680992D03*
X1460814Y690892D03*
X1457176Y704992D03*
Y692992D03*
X1460814Y702892D03*
X1457176Y716992D03*
X1460814Y714892D03*
X1456237Y726945D03*
X1457620Y736195D03*
X1460187Y729805D03*
X1455692Y731401D03*
X1457714Y741622D03*
X1447149Y1161569D03*
X1449649D03*
X1447299Y1153369D03*
X1449799D03*
X1447149Y1170069D03*
X1449649D03*
X1449176Y1256866D03*
X1446666Y1256896D03*
X1449188Y1259373D03*
X1446678Y1259403D03*
X1459960Y1259351D03*
Y1256851D03*
X1449106Y1267358D03*
X1459886Y1267218D03*
X1446556Y1267298D03*
X1446678Y1261903D03*
X1449188Y1261873D03*
Y1264373D03*
X1446678Y1264403D03*
X1459960Y1261851D03*
X1459972Y1264358D03*
X1457026Y1321177D03*
X1461686D03*
X1459356Y1321927D03*
X1450622Y1329329D03*
X1446622Y1328591D03*
X1454832Y1330819D03*
X1453360Y1328361D03*
X1446622Y1331647D03*
X1459968Y1402765D03*
X1451176Y1399026D03*
X1451198Y1403047D03*
X1460224Y1407545D03*
X1458138Y1409955D03*
X1461062Y1413246D03*
X1455006Y1447938D03*
X1459111Y1445669D03*
Y1448669D03*
X1457577Y1526689D03*
X1457817Y1542509D03*
X1457967Y1553729D03*
X1458200Y1565037D03*
Y1560037D03*
X1448620Y1556162D03*
X1456030Y1590302D03*
X1456120Y1586262D03*
X1453600Y1595662D03*
X1451500Y1612800D03*
X1454167Y1638302D03*
X1459127D03*
X1448507Y1638212D03*
X1448920Y1675062D03*
X1474142Y61767D03*
X1462000Y153362D03*
X1470220Y169862D03*
X1473090Y204502D03*
X1472335Y209362D03*
X1467761Y205982D03*
X1471308Y230640D03*
X1463833Y230448D03*
X1474660Y252878D03*
X1463808Y244948D03*
X1463833Y235566D03*
X1473820Y265962D03*
X1471510Y252878D03*
X1471690Y259862D03*
X1463950Y258172D03*
X1463330Y264060D03*
X1463510Y273878D03*
X1475452Y289708D03*
X1475352Y306308D03*
X1476826Y312177D03*
X1467700Y370953D03*
X1472758Y370817D03*
X1465836Y408668D03*
X1470942Y409718D03*
X1475250Y401812D03*
X1469777Y418396D03*
X1469951Y429251D03*
X1469720Y434542D03*
X1469760Y452622D03*
X1471460Y633402D03*
X1468060D03*
X1465171Y647132D03*
X1469020Y647102D03*
X1472076Y657392D03*
Y671892D03*
X1475714Y659492D03*
Y673992D03*
X1472076Y686392D03*
X1475714Y688492D03*
X1472076Y700892D03*
X1475714Y702992D03*
X1470841Y721493D03*
X1472076Y715392D03*
X1475714Y717492D03*
X1468876Y728392D03*
X1472514Y730492D03*
X1464999Y1259317D03*
X1476369Y1259237D03*
X1465059Y1256747D03*
X1462470Y1259321D03*
Y1256821D03*
X1476291Y1275224D03*
X1464946Y1267248D03*
X1464989Y1261927D03*
X1464981Y1264624D03*
X1476339Y1264467D03*
Y1267037D03*
X1476309Y1261807D03*
X1476279Y1269637D03*
X1476291Y1272344D03*
X1462396Y1267188D03*
X1462470Y1261821D03*
X1462482Y1264328D03*
X1476291Y1278104D03*
X1464016Y1321927D03*
X1466819Y1324018D03*
X1469019Y1322618D03*
X1473956Y1341068D03*
X1472460Y1330493D03*
Y1333043D03*
X1475576Y1338799D03*
X1469019Y1325518D03*
X1464680Y1325772D03*
X1469019Y1328418D03*
X1466919Y1327018D03*
X1464680Y1328672D03*
X1467567Y1445669D03*
Y1448669D03*
X1475967Y1445669D03*
Y1448669D03*
X1478320Y1522962D03*
X1472565Y1623635D03*
X1478061Y1633864D03*
X1463767Y1638302D03*
X1476570Y1661124D03*
X1482650Y-19811D03*
Y-23211D03*
X1493120Y240412D03*
X1487958Y236062D03*
X1490060Y255378D03*
X1485320Y260362D03*
X1478745Y281508D03*
X1493289Y280027D03*
X1478526Y289677D03*
X1481445Y289708D03*
X1479745Y312208D03*
X1478426Y306277D03*
X1481345Y306308D03*
X1481484Y361688D03*
X1481766Y372288D03*
X1489443D03*
X1494784Y374188D03*
X1486040Y368392D03*
X1481766Y406238D03*
X1490384Y407292D03*
X1493384Y411313D03*
X1482650Y411190D03*
X1495527Y406215D03*
X1486880Y416863D03*
X1484805Y427577D03*
X1489310Y426822D03*
X1481539Y1259377D03*
X1478999Y1259257D03*
X1481479Y1261947D03*
X1481419Y1264547D03*
X1481431Y1267254D03*
X1478939Y1261827D03*
X1478879Y1264427D03*
X1478891Y1267134D03*
X1481359Y1271447D03*
X1492039D03*
X1481359Y1274144D03*
X1492091D03*
X1478859Y1271417D03*
Y1274114D03*
X1481361Y1280054D03*
X1492101D03*
X1478821D03*
X1481359Y1277024D03*
X1492091D03*
X1478859Y1276994D03*
X1489154Y1334603D03*
X1493814D03*
X1491484Y1335353D03*
X1482750Y1342755D03*
X1478750Y1342017D03*
X1486960Y1344245D03*
X1485488Y1341787D03*
X1478750Y1345073D03*
X1485387Y1420002D03*
X1481918Y1425579D03*
X1484442Y1445557D03*
Y1448557D03*
X1482830Y1525162D03*
X1480800Y1663600D03*
X1510500Y125992D03*
X1508959Y215802D03*
X1503020D03*
X1499922Y211240D03*
X1496720Y225292D03*
X1504484Y234562D03*
X1508410Y230842D03*
X1510017Y225516D03*
X1501840Y225502D03*
X1512420Y239116D03*
X1510810Y249742D03*
X1509040Y243362D03*
X1504890Y249862D03*
X1506600Y239092D03*
X1504650Y254392D03*
X1508049Y280056D03*
X1498984Y282797D03*
X1508558Y291175D03*
X1512244Y311522D03*
X1505922Y304583D03*
X1509539Y308467D03*
X1498184Y361723D03*
Y369798D03*
X1495150Y369842D03*
X1503450Y385843D03*
X1509638Y738627D03*
X1509350Y741315D03*
X1504747Y747293D03*
X1503514Y801361D03*
Y797961D03*
X1497199Y1275667D03*
X1497259Y1273097D03*
X1494629Y1271477D03*
X1494631Y1274144D03*
X1506569Y1285947D03*
X1508819Y1284797D03*
X1506539Y1288557D03*
X1508759Y1287367D03*
X1508699Y1289967D03*
X1494641Y1280054D03*
X1494631Y1277024D03*
X1506551Y1291254D03*
X1497199Y1278277D03*
X1497161Y1280974D03*
X1506689Y1283377D03*
X1506591Y1297014D03*
Y1294134D03*
X1508711Y1295554D03*
Y1298434D03*
Y1292674D03*
X1496784Y1341147D03*
X1498924Y1334882D03*
X1498950Y1339517D03*
X1501149Y1336287D03*
X1496784Y1338247D03*
X1496144Y1335353D03*
X1504588Y1353316D03*
Y1355816D03*
X1501033Y1341462D03*
X1498959Y1342930D03*
X1505570Y1364212D03*
X1507704Y1361597D03*
X1510027Y1425825D03*
X1507617Y1424045D03*
X1522920Y116180D03*
X1513900Y117762D03*
X1518575Y138662D03*
X1521115Y193262D03*
X1524539Y215551D03*
X1522009Y210825D03*
X1518110Y215551D03*
X1526998Y209645D03*
X1527732Y219488D03*
X1514520Y231116D03*
X1526152Y225114D03*
X1514593Y249698D03*
Y235116D03*
X1519758Y265161D03*
X1522786Y262558D03*
X1522258Y265161D03*
X1519833Y277297D03*
X1522258Y288956D03*
X1517669Y291516D03*
X1515940Y795815D03*
Y799215D03*
X1513789Y1290037D03*
X1511289Y1287397D03*
X1511199Y1290007D03*
X1513791Y1292704D03*
X1516351D03*
X1513791Y1298464D03*
Y1295584D03*
X1516351D03*
Y1298464D03*
X1511251Y1292704D03*
Y1298464D03*
Y1295584D03*
X1521282Y1357401D03*
X1525942D03*
X1514878Y1365553D03*
X1510878Y1364815D03*
X1519088Y1367043D03*
X1517616Y1364585D03*
X1510878Y1367871D03*
X1523612Y1358151D03*
X1512177Y1427795D03*
X1516137Y1432135D03*
X1513657Y1429985D03*
X1544010Y27552D03*
X1536310Y47492D03*
X1534060Y100162D03*
X1530660D03*
X1533520Y110662D03*
X1529500Y122122D03*
X1535575Y118862D03*
X1540090Y122782D03*
X1536925Y129937D03*
X1529500Y125862D03*
X1535520Y151562D03*
X1529233Y153162D03*
X1535450Y155262D03*
X1542401Y141561D03*
X1534720Y199803D03*
X1528720Y199862D03*
X1533385Y193108D03*
X1533148Y211614D03*
X1531824Y207677D03*
X1534194Y217519D03*
X1529670Y225522D03*
X1535561Y225393D03*
X1531110Y264862D03*
X1539150Y267132D03*
X1540958Y307756D03*
X1539720Y589862D03*
Y581862D03*
X1540377Y634165D03*
X1541211Y646178D03*
X1533178Y1360815D03*
X1530978Y1359315D03*
X1528912Y1361045D03*
X1531078Y1362315D03*
X1533178Y1363715D03*
X1528912Y1363945D03*
X1533178Y1357915D03*
X1528272Y1358151D03*
X1556413Y19495D03*
X1549308Y26431D03*
X1552708D03*
X1552960Y124359D03*
X1553189Y127781D03*
X1556049Y147711D03*
X1545763Y159305D03*
X1551160Y189342D03*
X1557900Y220362D03*
X1557760Y214792D03*
X1550353Y217352D03*
X1557320Y203297D03*
X1559400Y229832D03*
X1545668Y305266D03*
X1545768Y302766D03*
X1543958Y307556D03*
X1546458Y307856D03*
X1543858Y310056D03*
X1543720Y581862D03*
X1548720D03*
X1552720Y589862D03*
Y581862D03*
X1554753Y628860D03*
X1553312Y636815D03*
X1559354Y655716D03*
Y659116D03*
X1550487Y681565D03*
X1550320Y696562D03*
X1550917Y704332D03*
X1550390Y709885D03*
X1570586Y19495D03*
X1573986D03*
X1559813D03*
X1563481Y26431D03*
X1566881D03*
X1573560Y245078D03*
X1574760Y251032D03*
X1559722Y243110D03*
X1570675Y267857D03*
X1573246Y306650D03*
X1572396Y309450D03*
X1563714Y572792D03*
X1567114D03*
X1559557Y593290D03*
X1564768Y708159D03*
X1562871Y732316D03*
Y735716D03*
X1571577Y747145D03*
X1567547Y755485D03*
X1571920Y762662D03*
X1568490Y758162D03*
X1570374Y760093D03*
X1584759Y19495D03*
X1588159D03*
X1577654Y26431D03*
X1591828D03*
X1581054D03*
X1576589Y300927D03*
X1588314Y592553D03*
X1585714D03*
X1583114D03*
X1590914D03*
X1588254Y595103D03*
X1588284Y597613D03*
X1585654Y595103D03*
X1585684Y597613D03*
X1583084D03*
X1583054Y595103D03*
X1588284Y608655D03*
X1585684D03*
X1583084D03*
X1590854Y595103D03*
X1590884Y597613D03*
Y608655D03*
X1588254Y613715D03*
X1588224Y611205D03*
X1585654Y613715D03*
X1585624Y611205D03*
X1583024D03*
X1583054Y613715D03*
X1590854D03*
X1590824Y611205D03*
X1591368Y628727D03*
X1591428Y626177D03*
X1588928D03*
X1588868Y628727D03*
X1591398Y631237D03*
X1588898D03*
X1591368Y650877D03*
X1591338Y648367D03*
X1591398Y645817D03*
X1588868Y650877D03*
X1588838Y648367D03*
X1588898Y645817D03*
X1591368Y653377D03*
X1588868D03*
X1591448Y657677D03*
X1588948D03*
Y660177D03*
X1591448D03*
X1588968Y665237D03*
X1591468D03*
X1588938Y662727D03*
X1591438D03*
X1588938Y679807D03*
X1588878Y682357D03*
X1588908Y684867D03*
X1591438Y679807D03*
X1591378Y682357D03*
X1591408Y684867D03*
X1591328Y696727D03*
X1591388Y694177D03*
X1588888D03*
X1588828Y696727D03*
X1591358Y699277D03*
X1588858D03*
X1591358Y718837D03*
X1591328Y716327D03*
X1591388Y713777D03*
X1588858Y718837D03*
X1588828Y716327D03*
X1588888Y713777D03*
X1590915Y755793D03*
X1598933Y19495D03*
X1602333D03*
X1595228Y26431D03*
X1603747Y192951D03*
X1603530Y202402D03*
X1603706Y211526D03*
X1603580Y206902D03*
X1604200Y234642D03*
X1604240Y227892D03*
X1603920Y222922D03*
X1604270Y231490D03*
X1604240Y238242D03*
X1602980Y560002D03*
X1593514Y592553D03*
X1601830Y590685D03*
X1604430D03*
X1607200Y583962D03*
X1593484Y597613D03*
X1593454Y595103D03*
X1593484Y608655D03*
X1593424Y611205D03*
X1593454Y613715D03*
X1601830Y615201D03*
X1604430D03*
X1598868Y628727D03*
X1598928Y626177D03*
X1593868Y628727D03*
X1593928Y626177D03*
X1596428D03*
X1596368Y628727D03*
X1598898Y631237D03*
X1593898D03*
X1596398D03*
X1598868Y650877D03*
X1598838Y648367D03*
X1596368Y650877D03*
X1593868D03*
X1596338Y648367D03*
X1593838D03*
X1598898Y645817D03*
X1596398D03*
X1593898D03*
X1598868Y653377D03*
X1596368D03*
X1593868D03*
X1598948Y657677D03*
X1593948D03*
X1596448D03*
Y660177D03*
X1593948D03*
X1598948D03*
X1596468Y665237D03*
X1593968D03*
X1598968D03*
X1596438Y662727D03*
X1593938D03*
X1598938D03*
X1593938Y679807D03*
X1596438D03*
X1593878Y682357D03*
X1596378D03*
X1593908Y684867D03*
X1596408D03*
X1598878Y682357D03*
X1598908Y684867D03*
X1598938Y679807D03*
X1596288Y688902D03*
X1598888D03*
X1598828Y696727D03*
X1593828D03*
X1593888Y694177D03*
X1596388D03*
X1596328Y696727D03*
X1593858Y699277D03*
X1596358D03*
X1598888Y694177D03*
X1596288Y691502D03*
X1598858Y699277D03*
X1598888Y691502D03*
X1598858Y718837D03*
X1598828Y716327D03*
X1596358Y718837D03*
X1593858D03*
X1596328Y716327D03*
X1593828D03*
X1596388Y713777D03*
X1593888D03*
X1598888D03*
X1596250Y721452D03*
X1598850D03*
X1599010Y724002D03*
X1598440Y736692D03*
X1592760Y736652D03*
X1595600D03*
X1606788Y756199D03*
X1602788D03*
X1621920Y25962D03*
X1622220Y49862D03*
X1623881Y129627D03*
X1610788Y756199D03*
X1614788D03*
X1618788D03*
X1615062Y1421241D03*
X1613047Y1415669D03*
X1614927Y1426076D03*
Y1429896D03*
X1624353Y1428766D03*
Y1431316D03*
X1617215Y1440822D03*
X1634799Y19495D03*
X1638199D03*
X1627694Y26431D03*
X1631094D03*
X1633111Y206693D03*
X1632342Y216015D03*
X1635835Y343002D03*
X1636800Y429982D03*
X1639800D03*
X1636800Y426982D03*
X1639800D03*
X1636800Y438982D03*
X1639800D03*
X1636800Y435982D03*
X1639800D03*
X1636800Y432982D03*
X1639800D03*
X1638928Y756199D03*
X1630928D03*
X1634928D03*
X1638277Y1269065D03*
X1640812Y1270020D03*
X1631203Y1367492D03*
X1628653D03*
X1626153D03*
X1628653Y1372492D03*
X1631203D03*
X1626153D03*
X1631203Y1369992D03*
X1628653D03*
X1626153D03*
X1628653Y1379992D03*
Y1382492D03*
Y1377492D03*
Y1374992D03*
X1631203Y1377492D03*
Y1374992D03*
Y1379992D03*
Y1382492D03*
X1626153Y1379992D03*
Y1382492D03*
Y1374992D03*
Y1377492D03*
X1630643Y1440290D03*
X1627469Y1437072D03*
X1624853Y1440875D03*
X1634643Y1442982D03*
X1638785Y1442483D03*
X1637042Y1440215D03*
X1630643Y1443090D03*
X1635315Y1465745D03*
Y1462745D03*
X1632315Y1468745D03*
X1629815D03*
X1632315Y1465745D03*
X1629815D03*
X1632315Y1462745D03*
X1629815D03*
X1635315Y1468745D03*
Y1460245D03*
X1629815D03*
X1632315D03*
X1629815Y1457745D03*
X1632315D03*
X1635315D03*
X1639645Y1473645D03*
X1648972Y19495D03*
X1652372D03*
X1641867Y26431D03*
X1645267D03*
X1650020Y408952D03*
X1647310Y408922D03*
X1650020Y411452D03*
X1647310Y411422D03*
X1654110Y434177D03*
X1657755Y517910D03*
X1651851Y532057D03*
X1651112Y545572D03*
X1645530Y549160D03*
X1653230Y549322D03*
X1642720Y560862D03*
X1656238Y592113D03*
X1649833Y594946D03*
X1653794Y594956D03*
X1653774Y598576D03*
X1649844Y598555D03*
X1656955Y611090D03*
X1645300Y612202D03*
X1653220Y620662D03*
X1645681Y624011D03*
X1648581D03*
X1651481D03*
X1654809Y638101D03*
X1653319Y642311D03*
X1652351Y639573D03*
X1648811Y628277D03*
X1647081Y626211D03*
X1645917Y628917D03*
Y633577D03*
X1645167Y631247D03*
Y635907D03*
X1650081Y626111D03*
X1651711Y628277D03*
X1651635Y651836D03*
X1652581Y646311D03*
X1643582Y652601D03*
X1655637Y646311D03*
X1641082Y652601D03*
X1649363Y649485D03*
X1654809Y672101D03*
X1652351Y673573D03*
X1645681Y658011D03*
X1648581D03*
X1648811Y662277D03*
X1647081Y660211D03*
X1645917Y662917D03*
Y667577D03*
X1645167Y665247D03*
Y669907D03*
X1650081Y660111D03*
X1651481Y658011D03*
X1651711Y662277D03*
X1641082Y686601D03*
X1651635Y685836D03*
X1652581Y680311D03*
X1653319Y676311D03*
X1643582Y686601D03*
X1655113Y680835D03*
X1649363Y683485D03*
X1654809Y706101D03*
X1648811Y696277D03*
X1645167Y703907D03*
X1645917Y701577D03*
X1645167Y699247D03*
X1645917Y696917D03*
X1650081Y694111D03*
X1645681Y692011D03*
X1647081Y694211D03*
X1648581Y692011D03*
X1651711Y696277D03*
X1651481Y692011D03*
X1641082Y720601D03*
X1651635Y719836D03*
X1652581Y714311D03*
X1653319Y710311D03*
X1652351Y707573D03*
X1643582Y720601D03*
X1655637Y714311D03*
X1649363Y717485D03*
X1651509Y756492D03*
X1650771Y1367492D03*
X1648271D03*
X1645721D03*
X1648271Y1372492D03*
X1650771D03*
X1645721D03*
X1650771Y1369992D03*
X1648271D03*
X1645721D03*
X1648271Y1379992D03*
Y1382492D03*
X1650771Y1379992D03*
Y1382492D03*
X1648271Y1377492D03*
Y1374992D03*
X1650771Y1377492D03*
Y1374992D03*
X1645721Y1377492D03*
Y1374992D03*
Y1379992D03*
Y1382492D03*
X1641047Y1432876D03*
X1645707D03*
X1643377Y1433626D03*
X1648037D03*
X1655762Y1429794D03*
X1648677Y1436220D03*
X1653243Y1435690D03*
X1651043Y1434190D03*
X1653243Y1432790D03*
X1651143Y1437190D03*
X1653243Y1438590D03*
X1648677Y1439120D03*
X1655295Y1453879D03*
X1652295D03*
X1643065Y1462645D03*
Y1465645D03*
Y1468645D03*
Y1460145D03*
Y1457645D03*
X1655295Y1456899D03*
X1652295D03*
X1642645Y1473645D03*
X1646958Y1501553D03*
X1671828Y26431D03*
X1668100Y180852D03*
X1667739Y187187D03*
X1666690Y193290D03*
X1674432Y216981D03*
X1672596Y220541D03*
X1668426Y222432D03*
X1664866Y225162D03*
X1660861Y227548D03*
X1664970Y472112D03*
X1662447Y480619D03*
X1665790Y523417D03*
X1662262Y537334D03*
X1659740Y542222D03*
X1661872Y534703D03*
X1660243Y532071D03*
X1668917Y549992D03*
X1666902Y555115D03*
X1663502D03*
X1658738Y592113D03*
X1661238D03*
X1664197Y602191D03*
X1669222Y604490D03*
X1670700Y594562D03*
X1672500Y596462D03*
X1660660Y602273D03*
X1664410Y617953D03*
X1668920Y617637D03*
X1660754Y609837D03*
X1669397Y614064D03*
X1663471Y609837D03*
X1666686Y757162D03*
X1669303Y1372492D03*
X1664253D03*
X1666753D03*
X1669303Y1367492D03*
Y1369992D03*
X1666753Y1367492D03*
X1664253D03*
Y1369992D03*
X1666753D03*
X1669303Y1379992D03*
Y1382492D03*
Y1377492D03*
Y1374992D03*
X1666753Y1379992D03*
X1664253D03*
X1666753Y1382492D03*
X1664253D03*
X1666753Y1377492D03*
X1664253D03*
Y1374992D03*
X1666753D03*
X1662496Y1428791D03*
Y1431291D03*
X1665612Y1437072D03*
X1662996Y1440922D03*
X1672786Y1442982D03*
X1668786Y1440290D03*
Y1443256D03*
X1657920Y1453405D03*
X1660920D03*
X1657860Y1466545D03*
Y1464045D03*
X1657950Y1456210D03*
X1657860Y1459045D03*
Y1461545D03*
X1660950Y1456210D03*
X1660860Y1466545D03*
Y1464045D03*
Y1459045D03*
Y1461545D03*
X1666123Y1493362D03*
Y1501362D03*
Y1533862D03*
Y1520862D03*
Y1545862D03*
X1671673Y1550815D03*
X1666123Y1557557D03*
X1666198Y1561557D03*
X1671660Y1569412D03*
X1666198Y1581321D03*
X1678933Y19495D03*
X1682333D03*
X1686001Y26431D03*
X1689401D03*
X1675228D03*
X1678994Y217231D03*
X1690208Y421855D03*
X1689095Y462640D03*
X1684940Y463030D03*
X1685779Y491230D03*
X1690229Y481845D03*
X1687238Y485496D03*
X1681817Y495290D03*
X1675664Y513802D03*
X1690999Y513107D03*
X1683702Y514687D03*
X1676600Y523902D03*
X1688768Y518107D03*
X1689544Y543874D03*
X1689506Y539882D03*
X1679941Y552222D03*
X1678860Y556752D03*
X1683369Y562698D03*
Y566098D03*
X1676644Y655345D03*
Y652745D03*
X1679244Y655345D03*
X1681864Y655286D03*
X1679244Y652745D03*
X1676624Y642404D03*
X1676644Y644945D03*
Y647545D03*
Y650145D03*
X1679244Y642345D03*
X1681864Y642286D03*
X1679244Y644945D03*
Y647545D03*
X1681864Y644886D03*
Y647486D03*
Y650086D03*
Y652686D03*
X1679244Y650145D03*
X1673860Y726522D03*
X1681810Y752955D03*
X1688912Y1372492D03*
X1686362D03*
Y1367492D03*
Y1369992D03*
X1688912Y1367492D03*
Y1369992D03*
Y1377492D03*
Y1374992D03*
Y1382492D03*
Y1379992D03*
X1686362D03*
Y1382492D03*
Y1374992D03*
Y1377492D03*
X1679190Y1432876D03*
X1683850D03*
X1681520Y1433626D03*
X1686180D03*
X1686820Y1436520D03*
X1688886Y1434790D03*
X1688986Y1437790D03*
X1676928Y1442483D03*
X1675185Y1440215D03*
X1686820Y1439420D03*
X1680720Y1487062D03*
X1679508Y1498303D03*
X1678340Y1500862D03*
X1679508Y1517803D03*
X1677930Y1520362D03*
X1679508Y1538803D03*
X1678340Y1541362D03*
X1678230Y1590542D03*
X1674220Y1585321D03*
X1696506Y19495D03*
X1693106D03*
X1703617Y26459D03*
X1700217D03*
X1703570Y50649D03*
X1700170D03*
X1702490Y204780D03*
X1704223Y209707D03*
Y212207D03*
X1701164Y209758D03*
X1698566Y214904D03*
X1696066D03*
X1693725Y217409D03*
X1698566Y212404D03*
X1696066D03*
X1698725Y217409D03*
X1696225D03*
X1701164Y212258D03*
X1704264Y217458D03*
X1701264D03*
X1704264Y214958D03*
X1701264D03*
X1698566Y209704D03*
X1696066D03*
X1693466Y209504D03*
Y214704D03*
Y212204D03*
X1693725Y219909D03*
X1698725D03*
X1696225D03*
X1704264Y219958D03*
X1701264D03*
X1704185Y222710D03*
X1698220Y369652D03*
X1699809Y403985D03*
X1695579D03*
X1702959Y404243D03*
X1707780Y410738D03*
X1697161Y406602D03*
X1692429Y403985D03*
X1701124Y423802D03*
X1694050Y416643D03*
X1695455Y422287D03*
X1707544Y431745D03*
X1707568Y420370D03*
X1690140Y434160D03*
X1693720Y455862D03*
X1697220D03*
X1702127Y468719D03*
X1693236Y472650D03*
X1691151Y493678D03*
X1689943Y479304D03*
X1701811Y501318D03*
X1701635Y497177D03*
X1699300Y498632D03*
X1697210Y500802D03*
X1694050Y501422D03*
X1693711Y498527D03*
X1691129Y501697D03*
X1707200Y498962D03*
X1699553Y513107D03*
X1707552Y506731D03*
X1707716Y513562D03*
X1702930Y526102D03*
X1699265Y521507D03*
X1690999Y525507D03*
X1701726Y518107D03*
X1699666Y541507D03*
X1699251Y533642D03*
X1691104Y530503D03*
X1691445Y535011D03*
X1704886Y534564D03*
X1689769Y537339D03*
X1699107Y555783D03*
X1703306Y550064D03*
X1703452Y639381D03*
X1700852D03*
X1698232Y639440D03*
X1700852Y655141D03*
X1703452Y647341D03*
Y649941D03*
Y652541D03*
Y644741D03*
X1700852Y647341D03*
Y649941D03*
Y652541D03*
Y644741D03*
X1698232Y655200D03*
Y644800D03*
Y647400D03*
Y650000D03*
Y652600D03*
X1703452Y641981D03*
X1700852D03*
X1698232Y642040D03*
X1700922Y657781D03*
X1698302Y657840D03*
X1698048Y705662D03*
X1701320Y705678D03*
X1698020Y702962D03*
X1696402Y709533D03*
X1699110Y727452D03*
X1705035Y729210D03*
X1704973Y753019D03*
X1703310Y749455D03*
X1690620Y760702D03*
X1691412Y1372492D03*
Y1367492D03*
Y1369992D03*
Y1377492D03*
Y1374992D03*
Y1382492D03*
Y1379992D03*
X1691086Y1436290D03*
Y1433390D03*
X1693392Y1429808D03*
X1691086Y1439190D03*
X1704723Y1500862D03*
Y1520362D03*
Y1541362D03*
X1705003Y1564057D03*
X1707220Y15662D03*
X1715210Y18282D03*
X1714589Y21562D03*
X1709589Y26062D03*
X1719589Y25862D03*
X1717089D03*
X1710106Y48720D03*
Y40020D03*
X1720895Y68062D03*
X1716875D03*
X1712520Y117862D03*
X1712720Y111862D03*
X1719943Y112667D03*
Y116667D03*
X1713418Y130862D03*
X1721418Y135327D03*
X1717418D03*
X1714490Y142920D03*
X1717140Y148910D03*
X1711700Y140200D03*
X1717619Y165909D03*
X1718110Y159040D03*
X1719530Y162950D03*
X1722078Y189483D03*
X1720310Y191252D03*
X1707159Y217580D03*
Y215080D03*
Y210080D03*
Y222580D03*
Y225080D03*
Y220080D03*
X1713720Y381152D03*
X1717220D03*
X1719200Y371162D03*
X1713720Y391652D03*
Y384652D03*
Y388152D03*
X1717220Y391652D03*
Y388152D03*
Y384652D03*
X1709000Y413362D03*
X1706500D03*
X1709000Y415862D03*
X1706500D03*
X1721220Y458362D03*
X1713977Y457137D03*
X1708977Y458542D03*
X1721936Y469263D03*
X1716134Y478443D03*
X1715711Y474399D03*
X1713977Y470804D03*
X1708977D03*
X1716148Y483720D03*
X1716087Y495665D03*
X1716156Y487685D03*
X1716278Y491676D03*
X1707552Y503331D03*
X1709844Y516106D03*
X1707610Y534113D03*
X1709356Y541144D03*
X1709680Y545432D03*
X1716110Y532632D03*
X1707346Y547504D03*
X1717987Y569705D03*
X1716480Y691410D03*
X1710550Y691327D03*
X1712824Y696476D03*
X1710122Y703509D03*
X1713920Y700962D03*
X1709828Y719283D03*
X1713450Y728222D03*
X1719727Y1472088D03*
X1726720Y49862D03*
X1733720D03*
X1730220D03*
X1736040Y41792D03*
X1732810Y52482D03*
X1736040Y44292D03*
X1730140Y52552D03*
X1727600Y52582D03*
X1725320Y67962D03*
X1723018Y101667D03*
X1723218Y93267D03*
X1738220Y98862D03*
X1736720Y101862D03*
X1729080Y118132D03*
X1739720Y120892D03*
X1728999Y112895D03*
X1730765Y151362D03*
X1733920D03*
X1723670Y149102D03*
X1728320Y169862D03*
X1723090Y173072D03*
Y177072D03*
X1734857Y184865D03*
X1737470Y177147D03*
X1737500Y217962D03*
Y214962D03*
Y211962D03*
Y208962D03*
Y226962D03*
Y223962D03*
Y220962D03*
X1725344Y359334D03*
X1728300Y377787D03*
X1733780Y390620D03*
X1729810D03*
X1737660D03*
X1734290Y423820D03*
X1727700Y417265D03*
X1739316Y480939D03*
X1730954Y478062D03*
X1725522Y482869D03*
X1733354Y490869D03*
Y486869D03*
X1738014Y1287344D03*
X1724431Y1336311D03*
X1734717Y1404340D03*
X1729700Y1462932D03*
X1733200D03*
X1736700D03*
X1736400Y1458942D03*
Y1455442D03*
X1731600Y1457230D03*
X1726120Y1490262D03*
X1726149Y1496270D03*
X1724649Y1513945D03*
X1727674D03*
X1729310Y1520951D03*
X1735310D03*
X1724649Y1505895D03*
X1727674D03*
X1726310Y1530445D03*
X1732310D03*
X1729310D03*
X1735310D03*
X1726310Y1520951D03*
X1732310D03*
X1751065Y39017D03*
X1754620Y39062D03*
X1747720Y31862D03*
Y34362D03*
X1740858Y72330D03*
Y79830D03*
Y74830D03*
Y82330D03*
X1745220Y98862D03*
X1741720D03*
X1743720Y101862D03*
X1740220D03*
X1748720Y97362D03*
X1745010Y122952D03*
X1750820Y119972D03*
X1738520Y151362D03*
X1751220Y147562D03*
X1748465D03*
X1754120Y171562D03*
X1750920Y171662D03*
X1754234Y190836D03*
X1752078Y216728D03*
X1740500Y217962D03*
Y214962D03*
Y211962D03*
Y208962D03*
X1747600Y209062D03*
X1744600D03*
X1751800Y206762D03*
X1752078Y226728D03*
Y224228D03*
Y221728D03*
Y219228D03*
X1740500Y226962D03*
Y223962D03*
Y220962D03*
X1746484Y279682D03*
X1749450Y293862D03*
X1756204Y301695D03*
X1752000Y306562D03*
X1756933Y372452D03*
X1744380Y382892D03*
X1744510Y377452D03*
X1747080Y435870D03*
X1746720Y464862D03*
X1752316Y703969D03*
Y695669D03*
X1752217Y692988D03*
X1752276Y720529D03*
X1752316Y712269D03*
X1747814Y1287344D03*
X1742714Y1287244D03*
X1754165Y1304422D03*
Y1307422D03*
Y1301422D03*
Y1295422D03*
Y1298422D03*
Y1310422D03*
X1738740Y1451742D03*
X1740200Y1462932D03*
X1745111Y1463262D03*
X1747677Y1507388D03*
X1744677D03*
X1747304Y1524976D03*
X1744304D03*
X1762420Y21562D03*
X1765238Y22062D03*
X1768026Y24165D03*
X1769669Y15244D03*
X1761998Y15187D03*
X1765260Y18262D03*
X1757320Y15872D03*
X1758672Y26431D03*
X1755272D03*
X1767220Y26962D03*
X1758669Y50649D03*
X1755269D03*
X1762738Y53262D03*
X1767220Y53342D03*
X1767185Y48817D03*
X1767400Y39915D03*
X1769274Y50742D03*
X1771774Y53682D03*
X1758063Y72623D03*
X1767170Y83607D03*
X1767990Y76797D03*
X1760478Y90027D03*
X1770368Y72691D03*
X1757978Y116727D03*
X1760978D03*
X1763678Y106127D03*
X1769278Y108027D03*
Y110927D03*
Y113727D03*
X1755978Y108427D03*
Y111027D03*
X1760478Y106127D03*
X1758300Y128242D03*
X1763435Y166862D03*
X1765820Y182282D03*
X1767300Y174587D03*
X1755078Y216928D03*
X1761500Y214062D03*
X1765000D03*
X1768500D03*
X1755078Y219428D03*
Y221928D03*
Y224428D03*
X1760104Y301648D03*
X1761936Y310709D03*
X1769230Y310478D03*
X1756800Y364048D03*
Y368048D03*
X1770280Y372452D03*
X1770220Y377452D03*
Y382952D03*
X1757066Y435721D03*
X1757650Y461393D03*
X1768560Y539042D03*
X1766060D03*
X1768317Y686375D03*
X1755112Y703948D03*
Y695648D03*
X1755013Y692967D03*
X1757612Y703948D03*
Y695648D03*
X1755072Y720508D03*
X1755112Y712248D03*
X1757572Y720508D03*
X1757612Y712248D03*
X1757165Y1304422D03*
X1760165D03*
Y1307422D03*
X1757165D03*
X1769165Y1301422D03*
X1766165D03*
X1763165D03*
X1757165D03*
X1760165D03*
X1769165Y1295422D03*
X1766165D03*
X1763165D03*
X1760165D03*
X1757165D03*
X1760165Y1298422D03*
X1757165D03*
X1763165D03*
X1766165D03*
X1769165D03*
X1758352Y1317368D03*
Y1322168D03*
X1757165Y1310422D03*
X1760165D03*
X1759987Y1325375D03*
Y1328275D03*
X1763829Y1337548D03*
X1766829D03*
Y1340448D03*
X1769829Y1337548D03*
Y1340448D03*
X1766829Y1343348D03*
X1769829Y1346248D03*
Y1343348D03*
Y1349148D03*
Y1351858D03*
X1782305Y13647D03*
X1775556Y21471D03*
X1775830Y26522D03*
X1777754Y37746D03*
X1781774Y54462D03*
X1774274Y50742D03*
X1776710Y53562D03*
X1779411Y50692D03*
X1774328Y60087D03*
X1779778Y70027D03*
X1774328Y62987D03*
X1775580Y73330D03*
X1779778Y72927D03*
X1787790Y85132D03*
X1781485Y88192D03*
X1785142Y76032D03*
X1773611Y88293D03*
X1778578Y97927D03*
X1778478Y90627D03*
X1784178Y108227D03*
Y111127D03*
Y113927D03*
X1780320Y153162D03*
X1774950Y167392D03*
X1779500Y171692D03*
X1777520Y178403D03*
Y173903D03*
X1782600Y175932D03*
X1778778Y216928D03*
X1783878D03*
X1772000Y214062D03*
X1778778Y219428D03*
Y221928D03*
X1783878Y224428D03*
Y226928D03*
Y219428D03*
Y221928D03*
X1786089Y287641D03*
X1783563D03*
X1777354Y295489D03*
X1783018Y301729D03*
X1782324Y410432D03*
Y403932D03*
Y425432D03*
Y418932D03*
X1782420Y447137D03*
X1781470Y452065D03*
X1778310Y591152D03*
X1781720Y592742D03*
X1778165Y1307422D03*
Y1304422D03*
Y1301422D03*
X1775165D03*
X1772165D03*
X1778165Y1295422D03*
X1775165D03*
X1772165D03*
Y1298422D03*
X1775165D03*
X1778165D03*
X1784165Y1307422D03*
Y1304422D03*
X1781165Y1307422D03*
Y1304422D03*
X1784165Y1301422D03*
Y1295422D03*
Y1298422D03*
X1781165Y1301422D03*
Y1295422D03*
Y1298422D03*
X1781829Y1324448D03*
X1784829D03*
X1778829D03*
X1778165Y1310422D03*
Y1312922D03*
X1784165Y1310422D03*
Y1312922D03*
X1781165Y1310422D03*
Y1312922D03*
X1781829Y1333148D03*
Y1330248D03*
Y1327348D03*
X1784829Y1333148D03*
Y1330248D03*
Y1327348D03*
X1781829Y1337548D03*
Y1340448D03*
X1784829Y1337548D03*
Y1340448D03*
X1778829Y1333148D03*
Y1330248D03*
Y1327348D03*
Y1337548D03*
X1772829D03*
X1775829D03*
X1778829Y1340448D03*
X1775829D03*
X1772829D03*
X1781829Y1346248D03*
Y1343348D03*
Y1349148D03*
Y1351858D03*
Y1354758D03*
X1772829Y1346248D03*
X1775829D03*
X1778829D03*
X1772829Y1343348D03*
X1775829D03*
X1778829D03*
X1772829Y1349148D03*
X1775829D03*
X1778829D03*
X1772829Y1351858D03*
X1775829D03*
X1778829D03*
X1772829Y1354758D03*
X1775829D03*
X1778829D03*
X1799920Y52594D03*
X1788238Y82292D03*
Y78062D03*
Y74912D03*
X1803215Y154032D03*
X1793269Y287641D03*
X1790743D03*
X1791619Y294441D03*
X1789093D03*
X1800160Y362542D03*
X1800340Y387062D03*
X1791494Y386536D03*
X1792450Y410615D03*
X1792507Y403932D03*
X1792220Y425432D03*
X1792335Y418775D03*
X1796020Y451162D03*
X1791888Y683805D03*
X1800450Y1505230D03*
X1795561Y1524729D03*
X1806920Y150862D03*
X1808910Y143902D03*
X1813335Y155435D03*
X1813325Y177257D03*
X1807220Y179897D03*
X1817157Y373829D03*
X1816224Y410432D03*
X1816994Y398052D03*
X1815724Y423932D03*
X1810792Y417432D03*
X1812161Y472521D03*
X1814537Y1322105D03*
X1813700Y1494762D03*
X1807150Y1505675D03*
X1818289Y1501591D03*
X1811494Y1505349D03*
X1813994Y1507891D03*
X1825762Y167662D03*
X1835760Y185772D03*
X1829695Y226333D03*
X1832295D03*
X1827095D03*
X1824095D03*
X1834895D03*
Y223733D03*
X1824095D03*
X1827095D03*
X1832295D03*
X1829695D03*
X1832295Y233933D03*
X1829695D03*
X1827095D03*
X1824095D03*
X1829695Y231433D03*
X1832295D03*
X1829695Y228933D03*
X1832295D03*
X1827095Y231433D03*
X1824095D03*
X1827095Y228933D03*
X1824095D03*
X1834895Y233933D03*
Y231433D03*
Y228933D03*
X1828204Y328654D03*
X1829189Y363731D03*
X1829434Y406348D03*
X1834005Y401421D03*
X1821280Y413432D03*
X1834600Y406442D03*
X1826914Y431718D03*
X1829514Y1498198D03*
Y1500807D03*
X1832114Y1498198D03*
Y1500807D03*
X1824995Y1502201D03*
X1846691Y166450D03*
X1844157Y182210D03*
X1848435Y172187D03*
X1838880Y195162D03*
X1837895Y226333D03*
Y223733D03*
Y233933D03*
Y231433D03*
Y228933D03*
X1836294Y383592D03*
X1838379Y453921D03*
G54D31*
X174685Y647210D03*
X174393Y678354D03*
X195316Y1430034D03*
X383224Y1354446D03*
X412990D03*
X443326D03*
X458600Y1379662D03*
X472700Y1353962D03*
X526478Y1449795D03*
X708795Y1429579D03*
X1131715Y1532913D03*
X1168627Y1466363D03*
X1175215Y1532913D03*
X1359365Y1353946D03*
X1389131D03*
X1419467D03*
X1434200Y1379362D03*
X1449233Y1353946D03*
X1502956Y1449373D03*
X1670101Y1463655D03*
X1682882Y628017D03*
Y678952D03*
X1769790Y204632D03*
X1799350D03*
X1826405Y269763D03*
Y299056D03*
G54D26*
X70472Y173228D03*
Y236220D03*
G54D45*
X450000Y278543D03*
X470000D03*
X483500Y246362D03*
X473500D03*
X480000Y278543D03*
X490000D03*
X500000D03*
X498563Y607067D03*
X510000Y278543D03*
X520000D03*
X518563Y607067D03*
X508563D03*
X549236Y1441207D03*
X569236D03*
X688500Y1611900D03*
Y1621900D03*
X1041435Y143357D03*
X1056225Y143131D03*
X1041435Y163357D03*
X1056225Y163131D03*
X1099970Y1712570D03*
Y1722570D03*
X1689646Y115669D03*
X1679646D03*
X1689646Y125669D03*
Y135669D03*
X1679646Y125669D03*
Y135669D03*
X1689646Y145669D03*
Y155669D03*
X1679646Y145669D03*
Y155669D03*
X1689646Y165669D03*
X1679646D03*
X1689646Y175669D03*
X1679646D03*
X1771457Y1624646D03*
Y1644646D03*
G54D17*
X27699Y1258727D03*
Y1255381D03*
Y1265420D03*
Y1262074D03*
X36399Y960892D03*
Y957546D03*
Y967585D03*
X43841Y994357D03*
X36399Y1054593D03*
X43841Y1255381D03*
Y1258727D03*
Y1252034D03*
Y1262074D03*
Y1265420D03*
X57299Y766798D03*
X52541Y964239D03*
Y957546D03*
Y954200D03*
Y1021129D03*
Y1024475D03*
Y1051247D03*
X57399Y1258727D03*
X52820Y1253862D03*
X57399Y1265420D03*
Y1262074D03*
X66099Y780184D03*
Y773491D03*
Y786877D03*
Y803609D03*
Y796916D03*
Y790223D03*
Y816995D03*
Y810302D03*
Y833727D03*
Y823688D03*
Y827034D03*
Y847113D03*
Y840420D03*
Y853806D03*
Y860499D03*
Y863845D03*
Y883924D03*
Y877231D03*
Y870538D03*
Y890617D03*
Y897310D03*
Y900656D03*
Y914042D03*
Y907349D03*
Y927428D03*
Y920735D03*
Y934121D03*
Y944160D03*
Y937467D03*
Y960892D03*
Y950853D03*
Y957546D03*
Y980971D03*
Y974278D03*
Y967585D03*
Y994357D03*
Y987664D03*
Y1027822D03*
Y1021129D03*
Y1047900D03*
Y1041207D03*
Y1034515D03*
Y1061286D03*
Y1054593D03*
Y1074672D03*
Y1067979D03*
Y1091404D03*
Y1081365D03*
Y1084711D03*
Y1098097D03*
Y1111483D03*
Y1104790D03*
Y1128215D03*
Y1118176D03*
Y1121522D03*
Y1141601D03*
Y1134908D03*
Y1148294D03*
Y1154987D03*
Y1158333D03*
Y1171719D03*
Y1165026D03*
Y1185105D03*
Y1178412D03*
Y1191798D03*
Y1208530D03*
Y1201837D03*
Y1195144D03*
Y1221916D03*
Y1215223D03*
Y1238648D03*
Y1228609D03*
Y1231955D03*
Y1245341D03*
X73541Y1255381D03*
Y1258727D03*
Y1252034D03*
Y1265420D03*
Y1262074D03*
X82241Y770144D03*
X86999Y766798D03*
X82241Y776837D03*
Y786877D03*
Y783530D03*
Y800263D03*
Y793570D03*
Y813648D03*
Y806955D03*
Y820341D03*
Y830381D03*
Y823688D03*
Y850459D03*
Y843766D03*
Y837074D03*
Y867192D03*
Y860499D03*
Y857152D03*
Y873885D03*
Y880577D03*
Y887270D03*
Y897310D03*
Y893963D03*
Y917389D03*
Y910696D03*
Y904003D03*
Y924081D03*
Y934121D03*
Y930774D03*
Y947507D03*
Y940814D03*
Y964239D03*
Y957546D03*
Y954200D03*
Y977625D03*
Y970932D03*
Y991011D03*
Y984318D03*
Y994357D03*
Y1021129D03*
Y1024475D03*
Y1031168D03*
Y1044554D03*
Y1037861D03*
Y1051247D03*
Y1071326D03*
Y1064633D03*
Y1078018D03*
Y1094751D03*
Y1088058D03*
Y1081365D03*
Y1108137D03*
Y1101444D03*
Y1124869D03*
Y1118176D03*
Y1114829D03*
Y1144948D03*
Y1138255D03*
Y1131562D03*
Y1161680D03*
Y1154987D03*
Y1151641D03*
Y1175066D03*
Y1168373D03*
Y1181759D03*
Y1191798D03*
Y1188452D03*
Y1205184D03*
Y1198491D03*
Y1218570D03*
Y1211877D03*
Y1225263D03*
Y1241995D03*
Y1235302D03*
Y1228609D03*
X87099Y1258727D03*
X82241Y1248688D03*
X84334Y1254263D03*
X87099Y1265420D03*
Y1262074D03*
X95799Y960892D03*
Y957546D03*
Y967585D03*
X103241Y994357D03*
X95799Y1054593D03*
X103241Y1255381D03*
Y1258727D03*
Y1252034D03*
Y1265420D03*
Y1262074D03*
X116567Y766775D03*
X125499Y780184D03*
Y773491D03*
Y786877D03*
Y803609D03*
Y796916D03*
Y790223D03*
Y816995D03*
Y810302D03*
Y833727D03*
Y823688D03*
Y827034D03*
Y847113D03*
Y840420D03*
Y853806D03*
Y860499D03*
Y863845D03*
Y883924D03*
Y877231D03*
Y870538D03*
Y890617D03*
Y897310D03*
Y900656D03*
Y914042D03*
Y907349D03*
Y927428D03*
Y920735D03*
Y934121D03*
Y944160D03*
Y937467D03*
Y960892D03*
Y950853D03*
X111941Y964239D03*
X125499Y957546D03*
X111941D03*
Y954200D03*
X125499Y980971D03*
Y974278D03*
Y967585D03*
Y994357D03*
Y987664D03*
X111941Y1021129D03*
Y1024475D03*
X125499Y1027822D03*
Y1021129D03*
Y1047900D03*
Y1041207D03*
Y1034515D03*
Y1061286D03*
X111941Y1051247D03*
X125499Y1054593D03*
Y1074672D03*
Y1067979D03*
Y1091404D03*
Y1081365D03*
Y1084711D03*
Y1098097D03*
Y1111483D03*
Y1104790D03*
Y1128215D03*
Y1118176D03*
Y1121522D03*
Y1141601D03*
Y1134908D03*
Y1148294D03*
Y1154987D03*
Y1158333D03*
Y1171719D03*
Y1165026D03*
Y1185105D03*
Y1178412D03*
Y1191798D03*
Y1208530D03*
Y1201837D03*
Y1195144D03*
Y1221916D03*
Y1215223D03*
Y1238648D03*
Y1228609D03*
Y1231955D03*
Y1245341D03*
X116799Y1258727D03*
X111941Y1248688D03*
X114191Y1254604D03*
X116799Y1265420D03*
Y1262074D03*
X141641Y770144D03*
Y776837D03*
Y786877D03*
Y783530D03*
Y800263D03*
Y793570D03*
Y813648D03*
Y806955D03*
Y820341D03*
Y830381D03*
Y823688D03*
Y850459D03*
Y843766D03*
Y837074D03*
Y867192D03*
Y860499D03*
Y857152D03*
Y873885D03*
Y880577D03*
Y887270D03*
Y897310D03*
Y893963D03*
Y917389D03*
Y910696D03*
Y904003D03*
Y924081D03*
Y934121D03*
Y930774D03*
Y947507D03*
Y940814D03*
Y964239D03*
Y957546D03*
Y954200D03*
Y977625D03*
Y970932D03*
Y991011D03*
Y984318D03*
Y994357D03*
Y1021129D03*
Y1024475D03*
Y1031168D03*
Y1044554D03*
Y1037861D03*
Y1051247D03*
Y1057940D03*
Y1071326D03*
Y1064633D03*
Y1078018D03*
Y1094751D03*
Y1088058D03*
Y1081365D03*
Y1108137D03*
Y1101444D03*
Y1124869D03*
Y1118176D03*
Y1114829D03*
Y1144948D03*
Y1138255D03*
Y1131562D03*
Y1161680D03*
Y1154987D03*
Y1151641D03*
Y1175066D03*
Y1168373D03*
Y1181759D03*
Y1191798D03*
Y1188452D03*
Y1205184D03*
Y1198491D03*
Y1218570D03*
Y1211877D03*
Y1225263D03*
X129933Y1238461D03*
X141641Y1241995D03*
Y1235302D03*
Y1228609D03*
X132941Y1255381D03*
Y1258727D03*
Y1252034D03*
X141641Y1248688D03*
X143675Y1255567D03*
X132941Y1265420D03*
Y1262074D03*
X146367Y766775D03*
X155199Y960892D03*
Y957546D03*
X160130Y1251847D03*
X146499Y1258727D03*
Y1265420D03*
Y1262074D03*
X176099Y766798D03*
X171341Y957546D03*
Y954200D03*
X162641Y994357D03*
X176199Y1258727D03*
X162641Y1255381D03*
Y1258727D03*
Y1252034D03*
X171341Y1248688D03*
X171947Y1255837D03*
X176199Y1265420D03*
X162641D03*
Y1262074D03*
X176199D03*
X184899Y780184D03*
Y773491D03*
Y786877D03*
Y803609D03*
Y796916D03*
Y790223D03*
Y883924D03*
Y890617D03*
Y897310D03*
Y900656D03*
Y914042D03*
Y907349D03*
Y960892D03*
Y957546D03*
Y1061286D03*
Y1111483D03*
Y1104790D03*
Y1128215D03*
Y1118176D03*
Y1121522D03*
Y1134908D03*
Y1185105D03*
Y1178412D03*
Y1191798D03*
Y1208530D03*
Y1201837D03*
Y1195144D03*
X192341Y1255381D03*
Y1258727D03*
Y1252034D03*
Y1265420D03*
Y1262074D03*
X188897Y1578182D03*
X192297D03*
X188897Y1590094D03*
X192297D03*
X201041Y770144D03*
X205799Y766798D03*
X201041Y776837D03*
Y786877D03*
Y783530D03*
Y800263D03*
Y793570D03*
Y880577D03*
Y887270D03*
Y897310D03*
Y893963D03*
Y910696D03*
Y904003D03*
Y957546D03*
Y954200D03*
Y994357D03*
X201141Y1108137D03*
Y1101444D03*
X201041Y1124869D03*
X201141Y1118177D03*
Y1114830D03*
X201041Y1131562D03*
X201141Y1175066D03*
Y1181759D03*
Y1191799D03*
Y1188452D03*
Y1205184D03*
Y1198491D03*
X205899Y1258727D03*
X201041Y1248688D03*
X201193Y1257900D03*
X205899Y1265420D03*
Y1262074D03*
X200957Y1578182D03*
X204357D03*
X200957Y1590094D03*
X204357D03*
X194197Y1614292D03*
X197597D03*
X206257D03*
X214599Y960892D03*
Y957546D03*
X222041D03*
Y954200D03*
Y994357D03*
Y1255381D03*
X219660Y1260492D03*
X222041Y1252034D03*
Y1265420D03*
Y1262074D03*
X225077Y1578182D03*
X213017D03*
X216417D03*
X225077Y1590094D03*
X213017D03*
X216417D03*
X209657Y1614292D03*
X218317D03*
X221717D03*
X235499Y766798D03*
X236391Y1002557D03*
X240521Y1000395D03*
X237841Y1000437D03*
X233891Y1002557D03*
X231391D03*
X228891D03*
X235599Y1258727D03*
X230741Y1248688D03*
X235480Y1265406D03*
X235599Y1262074D03*
X237137Y1578182D03*
X240537D03*
X228477D03*
X237137Y1590094D03*
X240537D03*
X228477D03*
X230377Y1614292D03*
X233777D03*
X244299Y960892D03*
Y957546D03*
X251741D03*
Y954200D03*
Y994357D03*
X254881Y999650D03*
X257561Y999608D03*
X244299Y1061286D03*
X248047Y1259155D03*
X250467Y1259175D03*
X251707Y1252034D03*
X249603Y1266204D03*
X251699Y1265254D03*
X249197Y1578182D03*
X252597D03*
X249197Y1590094D03*
X252597D03*
X242437Y1614292D03*
X254497D03*
X245837D03*
X272529Y111053D03*
X265442D03*
X261899D03*
Y108553D03*
X265442D03*
X268985Y111053D03*
Y108553D03*
X272529D03*
X260441Y1057940D03*
Y1248688D03*
X273317Y1578182D03*
X261257D03*
X264657D03*
X273317Y1590094D03*
X261257D03*
X264657D03*
X266557Y1614292D03*
X257897D03*
X269957D03*
X285377Y1578182D03*
X288777D03*
X276717D03*
X285377Y1590094D03*
X288777D03*
X276717D03*
X278617Y1614292D03*
X282017D03*
X297437Y1578182D03*
X300837D03*
X297437Y1590094D03*
X300837D03*
X290677Y1614292D03*
X302737D03*
X294077D03*
X306137D03*
X321557Y1578182D03*
X309497D03*
X312897D03*
X321557Y1590094D03*
X309497D03*
X312897D03*
X314797Y1614292D03*
X318197D03*
X333617Y1578182D03*
X337017D03*
X324957D03*
X333617Y1590094D03*
X337017D03*
X324957D03*
X330257Y1614292D03*
X338917D03*
X326857D03*
X345677Y1578182D03*
X349077D03*
X345677Y1590094D03*
X349077D03*
X350977Y1614292D03*
X342317D03*
X354377D03*
X369797Y1578182D03*
X357737D03*
X361137D03*
X369797Y1590094D03*
X357737D03*
X361137D03*
X363037Y1614292D03*
X366437D03*
X373197Y1578182D03*
Y1590094D03*
X375097Y1614292D03*
X378497D03*
X476451Y1578182D03*
X485111D03*
X473051D03*
X476451Y1590094D03*
X485111D03*
X473051D03*
X478351Y1614292D03*
X481751D03*
X500571Y1578182D03*
X488511D03*
X497171D03*
X500571Y1590094D03*
X488511D03*
X497171D03*
X490411Y1614292D03*
X493811D03*
X512631Y1578182D03*
X509231D03*
X512631Y1590094D03*
X509231D03*
X514531Y1614292D03*
X502471D03*
X517931D03*
X505871D03*
X524691Y1578182D03*
X533351D03*
X521291D03*
X524691Y1590094D03*
X533351D03*
X521291D03*
X526591Y1614292D03*
X529991D03*
X536751Y1578182D03*
X548811D03*
X545411D03*
X536751Y1590094D03*
X548811D03*
X545411D03*
X538651Y1614292D03*
X542051D03*
X560871Y1578182D03*
X557471D03*
X560871Y1590094D03*
X557471D03*
X562771Y1614292D03*
X550711D03*
X566171D03*
X554111D03*
X572931Y1578182D03*
X581591D03*
X569531D03*
X572931Y1590094D03*
X581591D03*
X569531D03*
X574831Y1614292D03*
X578231D03*
X597051Y1578182D03*
X584991D03*
X593651D03*
X597051Y1590094D03*
X584991D03*
X593651D03*
X598951Y1614292D03*
X586891D03*
X590291D03*
X609111Y1578182D03*
X605711D03*
X609111Y1590094D03*
X605711D03*
X611011Y1614292D03*
X614411D03*
X602351D03*
X629658Y766478D03*
X620799Y960892D03*
Y957546D03*
X623347Y999665D03*
X625780Y1000198D03*
X620899Y1061286D03*
X629931Y1258727D03*
X632080Y1262074D03*
X629699Y1255381D03*
X631270Y1264942D03*
X621171Y1578182D03*
X629831D03*
X617771D03*
X621171Y1590094D03*
X629831D03*
X617771D03*
X623071Y1614292D03*
X626471D03*
X636941Y957546D03*
Y954200D03*
X644347Y1003135D03*
X640327D03*
X640467Y1000735D03*
X647447Y1002865D03*
X647397Y1000135D03*
X644257Y1000325D03*
X636946Y1258414D03*
X647690Y1260812D03*
X637041Y1252034D03*
X645897Y1248785D03*
X647877Y1254076D03*
X636877Y1261235D03*
X645291Y1578182D03*
X633231D03*
X641891D03*
X645291Y1590094D03*
X633231D03*
X641891D03*
X647191Y1614292D03*
X635131D03*
X638531D03*
X667677Y441636D03*
X650499Y960892D03*
Y957546D03*
X650107Y1002825D03*
X650599Y1258727D03*
X666741Y1255381D03*
X664630Y1259442D03*
X649587Y1266766D03*
X661400Y1263522D03*
X657351Y1578182D03*
X653951D03*
X657351Y1590094D03*
X653951D03*
X662651Y1614292D03*
X659251D03*
X650591D03*
X674628Y424313D03*
X671479Y421163D03*
X667660Y429037D03*
X674628Y427462D03*
X677778Y414864D03*
Y424313D03*
X671479Y414864D03*
X674628Y421163D03*
Y418013D03*
X677778D03*
Y421163D03*
X668329D03*
X677778Y427462D03*
Y430612D03*
X674628Y436911D03*
X671479D03*
X677778Y433761D03*
X668329Y436911D03*
X677778Y440061D03*
X674628D03*
X677778Y436911D03*
Y443210D03*
X680928Y440061D03*
X674628Y430612D03*
X671479Y443211D03*
X677778Y449510D03*
X668329Y452659D03*
X674628D03*
X671479D03*
X677778D03*
X668329Y455809D03*
X671479Y458959D03*
X674628D03*
X668329D03*
X677778D03*
Y455809D03*
X674628D03*
X668067Y462090D03*
X677778Y462108D03*
X671479Y455809D03*
X680928Y458959D03*
X674628Y449510D03*
Y462108D03*
X677778Y477856D03*
Y471557D03*
Y474707D03*
X671479Y465258D03*
X674628D03*
X668329D03*
X677778D03*
Y468407D03*
X671479Y481006D03*
X667350Y470680D03*
X671479Y474707D03*
X674628Y484006D03*
X680299Y766798D03*
Y780184D03*
Y773491D03*
Y786877D03*
Y803609D03*
Y796916D03*
Y790223D03*
Y883924D03*
Y890617D03*
Y897310D03*
Y900656D03*
Y914042D03*
Y907349D03*
Y960892D03*
Y957546D03*
X666641D03*
Y954200D03*
X672063Y998632D03*
X680299Y1061286D03*
Y1111483D03*
Y1104790D03*
Y1128215D03*
Y1118176D03*
Y1121522D03*
Y1134908D03*
Y1185105D03*
Y1178412D03*
Y1191798D03*
Y1208530D03*
Y1201837D03*
Y1195144D03*
Y1258727D03*
X666741Y1252034D03*
X675537Y1248885D03*
X677980Y1262074D03*
X666741D03*
X666646Y1264464D03*
X680046Y1264964D03*
X695055Y112678D03*
Y115178D03*
X687227Y414864D03*
X690376Y421163D03*
Y418013D03*
Y414864D03*
X693526Y427462D03*
X687227Y424313D03*
X690376Y427462D03*
X680928Y414864D03*
Y418013D03*
X684077Y421163D03*
X680928Y427462D03*
X684077Y418013D03*
Y427462D03*
X680928Y421163D03*
X684077Y424313D03*
X687227Y427462D03*
X696676D03*
X693526Y421163D03*
Y424313D03*
X690376D03*
X696676Y421163D03*
Y424313D03*
Y418013D03*
X680928Y436911D03*
Y433761D03*
X693526Y430612D03*
X696676Y440061D03*
Y443210D03*
X684077Y430612D03*
Y440061D03*
X687227Y436911D03*
Y443210D03*
X684077D03*
Y436911D03*
X680928Y443210D03*
X690376Y436911D03*
Y443210D03*
X687227Y440061D03*
X693526Y433761D03*
X696676D03*
X684077D03*
X687227Y430612D03*
X690376D03*
X696676D03*
X687227Y433761D03*
X680928Y430612D03*
X687227Y462108D03*
X680928Y455809D03*
X693526Y462108D03*
X680928Y449510D03*
X687227D03*
X690376Y462108D03*
X684077Y449510D03*
X680928Y452659D03*
X684077D03*
X687227Y455809D03*
X684077D03*
X680928Y462108D03*
X696676Y449510D03*
Y452659D03*
X690376Y449510D03*
Y455809D03*
X687227Y452659D03*
X693526Y458959D03*
X696676D03*
Y462108D03*
X687227Y458959D03*
X684077D03*
Y468407D03*
X687227Y471557D03*
Y474707D03*
Y477856D03*
X684077Y471557D03*
X690376Y465258D03*
X684077D03*
X680928Y471557D03*
Y474707D03*
Y477856D03*
X693526Y465258D03*
Y471557D03*
X690376Y468407D03*
Y477856D03*
Y471557D03*
X687227Y465258D03*
X690376Y474707D03*
X687227Y468407D03*
X693526D03*
X684077Y474707D03*
X696676Y465258D03*
Y474707D03*
Y468407D03*
X693526Y474707D03*
X696676Y471557D03*
X693526Y477856D03*
X696441Y770144D03*
Y776837D03*
Y786877D03*
Y783530D03*
Y800263D03*
Y793570D03*
Y880577D03*
Y887270D03*
Y897310D03*
Y893963D03*
Y910696D03*
Y904003D03*
Y957546D03*
Y954200D03*
Y994357D03*
Y1108136D03*
Y1101444D03*
Y1124869D03*
Y1118176D03*
Y1114829D03*
Y1131562D03*
Y1175066D03*
Y1181758D03*
Y1191798D03*
Y1188451D03*
Y1205184D03*
Y1198491D03*
Y1255381D03*
X694100Y1261562D03*
X696441Y1248688D03*
X692233Y1252480D03*
X696046Y1263764D03*
X698598Y115178D03*
X705685D03*
X702141D03*
X698598Y112678D03*
X705685D03*
X702141D03*
X706125Y418013D03*
X712424Y424313D03*
X699825Y427462D03*
X699826Y414864D03*
X699825Y424313D03*
X712424Y430612D03*
X709274Y440061D03*
Y443210D03*
X706125D03*
X699825D03*
X709274Y433761D03*
X712424D03*
X699825D03*
X706125D03*
X699825Y430612D03*
X706125Y462108D03*
X709274D03*
X712424D03*
X709274Y449510D03*
X699825D03*
X706125D03*
X709274Y452659D03*
X699825Y458959D03*
X706125D03*
X709274D03*
X712424D03*
X699825Y462108D03*
X709274Y474707D03*
Y471557D03*
Y465258D03*
Y468407D03*
X712424Y474707D03*
Y468407D03*
Y465258D03*
X706125Y471557D03*
Y468407D03*
X699825Y471557D03*
Y474707D03*
X706125Y477856D03*
X699825Y465258D03*
X712424Y471557D03*
X706125Y481006D03*
X709899Y766798D03*
Y960892D03*
Y957546D03*
X709999Y1258727D03*
X708090Y1262074D03*
X705037Y1252034D03*
X706493Y1256563D03*
X705167Y1262074D03*
X709977Y1264985D03*
X721873Y427462D03*
X725022D03*
X728172Y418013D03*
X718723D03*
X715574Y427462D03*
X728172Y421163D03*
X718723Y414864D03*
X725022Y424313D03*
X721873D03*
X725022Y421163D03*
X728172Y427462D03*
X731322Y421163D03*
X725022Y418013D03*
X718723Y427462D03*
Y424313D03*
Y421163D03*
X715574Y424313D03*
Y421163D03*
Y418013D03*
X728172Y424313D03*
X718723Y436911D03*
X721873Y433761D03*
Y436911D03*
Y440061D03*
Y430612D03*
X718723Y433761D03*
Y440061D03*
X725022Y436911D03*
Y433761D03*
X728172D03*
X718723Y430612D03*
X715574D03*
X725022D03*
X728172Y436911D03*
X715574D03*
Y440061D03*
Y443210D03*
X728172D03*
Y430612D03*
X725022Y440061D03*
X718723Y443210D03*
X721873D03*
X725022D03*
X728172Y440061D03*
X731322D03*
X728172Y455809D03*
Y458959D03*
X718723Y455809D03*
X721873Y458959D03*
Y452659D03*
X725022D03*
X728172D03*
X715574Y462108D03*
X725022Y458959D03*
X721873Y455809D03*
X725022Y462108D03*
X718723Y452659D03*
X715574Y449510D03*
Y452659D03*
Y455809D03*
X728172Y462108D03*
X718723Y449510D03*
X721873D03*
X725022D03*
X718723Y458959D03*
X721873Y462108D03*
X718723D03*
X725022Y468407D03*
X721873Y465258D03*
Y477856D03*
X718723Y468407D03*
X715574Y474707D03*
Y471557D03*
Y468407D03*
Y465258D03*
X718723Y474707D03*
Y471557D03*
X728172Y477856D03*
X721873Y471557D03*
X725022D03*
X718723Y465258D03*
X728172D03*
X725022Y474707D03*
X728172Y468407D03*
X721873Y474707D03*
Y468407D03*
X728172Y474707D03*
Y471557D03*
X725022Y465258D03*
X718723Y477856D03*
X725132Y481116D03*
X728272Y481006D03*
X726041Y957546D03*
Y954200D03*
Y994357D03*
X726141Y1057940D03*
Y1255381D03*
X723700Y1258727D03*
X726141Y1248688D03*
Y1262074D03*
X726107Y1265420D03*
X734471Y418013D03*
X731322Y427462D03*
Y418013D03*
X734471Y421163D03*
X731322Y424313D03*
X734471D03*
X737621D03*
X731322Y414864D03*
Y433761D03*
X734471Y436911D03*
X731322D03*
X734471Y443210D03*
X737621D03*
X731322D03*
Y455809D03*
X737621Y458959D03*
X731322D03*
X734471Y452659D03*
X731322D03*
Y449510D03*
X734471Y458959D03*
X731322Y465258D03*
Y477856D03*
X737621Y471557D03*
X734471Y468407D03*
X731322D03*
X731321Y474707D03*
X731322Y471557D03*
X734471Y481006D03*
X739699Y766798D03*
Y780184D03*
Y773491D03*
Y786877D03*
Y803609D03*
Y796916D03*
Y790223D03*
Y816995D03*
Y810302D03*
Y833727D03*
Y823688D03*
Y827034D03*
Y847113D03*
Y840420D03*
Y853806D03*
Y860499D03*
Y863845D03*
Y883924D03*
Y877231D03*
Y870538D03*
Y890617D03*
Y897310D03*
Y900656D03*
Y914042D03*
Y907349D03*
Y927428D03*
Y920735D03*
Y934121D03*
Y944160D03*
Y937467D03*
Y960892D03*
Y950853D03*
Y957546D03*
Y980971D03*
Y974278D03*
Y967585D03*
Y994357D03*
Y987664D03*
Y1027822D03*
Y1021129D03*
Y1047900D03*
Y1041207D03*
Y1034514D03*
Y1061286D03*
Y1054593D03*
Y1074672D03*
Y1067979D03*
Y1091404D03*
Y1081365D03*
Y1084711D03*
Y1098097D03*
Y1111483D03*
Y1104790D03*
Y1128215D03*
Y1118176D03*
Y1121522D03*
Y1141601D03*
Y1134908D03*
Y1148294D03*
Y1154987D03*
Y1158333D03*
Y1171719D03*
Y1165026D03*
Y1185105D03*
Y1178412D03*
Y1191798D03*
Y1208530D03*
Y1201837D03*
Y1195144D03*
Y1221916D03*
Y1215223D03*
Y1238648D03*
Y1228609D03*
Y1231955D03*
Y1245341D03*
Y1258727D03*
X734967Y1252034D03*
X737580Y1262074D03*
X739697Y1265420D03*
X755841Y770144D03*
Y776837D03*
Y786877D03*
Y783530D03*
Y800263D03*
Y793570D03*
Y813648D03*
Y806955D03*
Y820341D03*
Y830381D03*
Y823688D03*
Y850459D03*
Y843766D03*
Y837074D03*
Y867192D03*
Y860499D03*
Y857152D03*
Y873885D03*
Y880577D03*
Y887270D03*
Y897310D03*
Y893963D03*
Y917389D03*
Y910696D03*
Y904003D03*
Y924081D03*
Y934121D03*
Y930774D03*
Y947507D03*
Y940814D03*
Y964239D03*
Y957546D03*
Y954200D03*
Y977625D03*
X755741Y970932D03*
X755841Y991011D03*
Y984318D03*
Y994357D03*
Y1021129D03*
Y1024475D03*
Y1031168D03*
X755541Y1044554D03*
Y1037861D03*
X755841Y1051247D03*
X755541Y1057940D03*
X755676Y1071326D03*
X755741Y1064633D03*
X755841Y1078018D03*
Y1094751D03*
Y1088058D03*
Y1081365D03*
X755676Y1108137D03*
X755841Y1101444D03*
Y1124869D03*
Y1118176D03*
Y1114829D03*
Y1144947D03*
Y1138255D03*
Y1131562D03*
Y1161680D03*
Y1154987D03*
Y1151640D03*
Y1175066D03*
Y1168373D03*
X755676Y1181759D03*
X755841Y1191798D03*
X755676Y1188452D03*
X755841Y1205184D03*
Y1198491D03*
Y1218569D03*
Y1211877D03*
Y1225262D03*
Y1241995D03*
Y1235302D03*
Y1228609D03*
X750890Y1248500D03*
X755890Y1255381D03*
X753000Y1261352D03*
X755841Y1252034D03*
Y1248688D03*
X750040Y1254179D03*
X755841Y1262074D03*
X755797Y1265420D03*
X769399Y766798D03*
Y960892D03*
Y957546D03*
Y967585D03*
Y1054593D03*
Y1258727D03*
X767080Y1262074D03*
X766148Y1255882D03*
X769399Y1265420D03*
X785541Y964239D03*
Y957546D03*
Y954200D03*
Y994357D03*
Y1021129D03*
Y1024475D03*
Y1051247D03*
Y1255381D03*
X783130Y1259372D03*
X794157Y1252034D03*
X785541Y1248688D03*
X796880Y1262074D03*
X796280Y1254402D03*
X785541Y1265420D03*
Y1262074D03*
X797417Y767345D03*
X799099Y780184D03*
Y773491D03*
Y786877D03*
Y803609D03*
Y796916D03*
Y790223D03*
Y816995D03*
Y810302D03*
Y833727D03*
Y823688D03*
Y827034D03*
Y847113D03*
Y840420D03*
Y853806D03*
Y860499D03*
Y863845D03*
Y883924D03*
Y877231D03*
Y870538D03*
Y890617D03*
Y897310D03*
Y900656D03*
Y914042D03*
Y907349D03*
Y927428D03*
Y920735D03*
Y934121D03*
Y944160D03*
Y937467D03*
Y960892D03*
Y950853D03*
Y957546D03*
Y980971D03*
Y974278D03*
Y967585D03*
Y994357D03*
Y987664D03*
Y1027822D03*
Y1021129D03*
Y1047900D03*
Y1041207D03*
Y1034515D03*
Y1061286D03*
Y1054593D03*
Y1074672D03*
Y1067979D03*
Y1091404D03*
Y1081365D03*
Y1084711D03*
Y1098097D03*
Y1111483D03*
Y1104790D03*
Y1128215D03*
Y1118176D03*
Y1121522D03*
Y1141601D03*
Y1134908D03*
Y1148294D03*
Y1154987D03*
Y1158333D03*
Y1171719D03*
Y1165026D03*
Y1185105D03*
Y1178412D03*
Y1191798D03*
Y1208530D03*
Y1201837D03*
Y1195144D03*
Y1221916D03*
Y1215223D03*
Y1238648D03*
Y1228609D03*
Y1231955D03*
Y1245341D03*
Y1258727D03*
X812440D03*
X799099Y1265420D03*
X815241Y770144D03*
Y776837D03*
Y786877D03*
Y783530D03*
Y800263D03*
Y793570D03*
Y813648D03*
Y806955D03*
Y820341D03*
Y830381D03*
Y823688D03*
Y850459D03*
Y843766D03*
Y837074D03*
Y867192D03*
Y860499D03*
Y857152D03*
Y873885D03*
Y880577D03*
Y887270D03*
Y897310D03*
Y893963D03*
Y917389D03*
Y910696D03*
Y904003D03*
Y924081D03*
Y934121D03*
Y930774D03*
Y947507D03*
Y940814D03*
Y964239D03*
Y957546D03*
Y954200D03*
Y977625D03*
Y970932D03*
Y991011D03*
Y984318D03*
Y994357D03*
Y1021129D03*
Y1024475D03*
Y1031168D03*
Y1044554D03*
Y1037861D03*
X814941Y1051247D03*
X815241Y1071325D03*
Y1064633D03*
Y1078018D03*
Y1094751D03*
Y1088058D03*
Y1081365D03*
Y1108136D03*
Y1101444D03*
Y1124869D03*
Y1118176D03*
Y1114829D03*
Y1144947D03*
Y1138255D03*
Y1131562D03*
Y1161680D03*
Y1154987D03*
Y1151640D03*
Y1175066D03*
Y1168373D03*
Y1181758D03*
Y1191798D03*
Y1188451D03*
Y1205184D03*
Y1198491D03*
Y1218570D03*
Y1211877D03*
Y1225263D03*
Y1241995D03*
Y1235302D03*
Y1228609D03*
Y1255381D03*
X826750Y1262074D03*
X823877Y1252034D03*
X815241Y1248688D03*
X826501Y1254553D03*
X815241Y1265420D03*
Y1262074D03*
X828699Y766798D03*
X828799Y960892D03*
Y957546D03*
Y967585D03*
Y1054593D03*
Y1258727D03*
X842630Y1256912D03*
X828799Y1265420D03*
X844941Y964239D03*
X844841Y957546D03*
Y954200D03*
Y994357D03*
X844941Y1021129D03*
Y1024475D03*
Y1051247D03*
Y1258727D03*
Y1252034D03*
X844997Y1248155D03*
X844941Y1265420D03*
Y1262074D03*
X998205Y195735D03*
Y192191D03*
X1000705Y195735D03*
Y192191D03*
X998205Y199278D03*
X1000705D03*
X998205Y202821D03*
X1000705D03*
X1001970Y1251522D03*
X1003831Y1259077D03*
X1002070Y1256942D03*
X1003841Y1265420D03*
Y1262074D03*
X1012769Y766798D03*
X1012541Y960892D03*
Y957546D03*
Y967585D03*
X1019983Y994357D03*
X1012541Y1054593D03*
X1017900Y1247632D03*
X1019983Y1255381D03*
Y1252034D03*
Y1248688D03*
Y1262074D03*
Y1265420D03*
X1033441Y766798D03*
X1028683Y964239D03*
Y957546D03*
Y954200D03*
Y1021129D03*
Y1024475D03*
Y1051247D03*
X1033541Y1258727D03*
X1030830Y1261302D03*
X1030270Y1256042D03*
X1033541Y1265420D03*
X1042241Y780184D03*
Y773491D03*
Y786877D03*
Y803609D03*
Y796916D03*
Y790223D03*
Y816995D03*
Y810302D03*
Y833727D03*
Y823688D03*
Y827034D03*
Y847113D03*
Y840420D03*
Y853806D03*
Y860499D03*
Y863845D03*
Y883924D03*
Y877231D03*
Y870538D03*
Y890617D03*
Y897310D03*
Y900656D03*
Y914042D03*
Y907349D03*
Y927428D03*
Y920735D03*
Y934121D03*
Y944160D03*
Y937467D03*
Y960892D03*
Y950853D03*
Y957546D03*
Y980971D03*
Y974278D03*
Y967585D03*
Y994357D03*
Y987664D03*
Y1027822D03*
Y1021129D03*
Y1047900D03*
Y1041207D03*
Y1034515D03*
Y1061286D03*
Y1054593D03*
Y1074672D03*
Y1067979D03*
Y1091404D03*
Y1081365D03*
Y1084711D03*
Y1098097D03*
Y1111483D03*
Y1104790D03*
Y1128215D03*
Y1118176D03*
Y1121522D03*
Y1141601D03*
Y1134908D03*
Y1148294D03*
Y1154987D03*
Y1158333D03*
Y1171719D03*
Y1165026D03*
Y1185105D03*
Y1178412D03*
Y1191798D03*
Y1208530D03*
Y1201837D03*
Y1195144D03*
Y1221916D03*
Y1215223D03*
Y1238648D03*
Y1228609D03*
Y1231955D03*
Y1245341D03*
X1047010Y1259222D03*
X1049683Y1258727D03*
Y1265420D03*
Y1262074D03*
X1044930Y1263492D03*
X1058383Y770144D03*
X1063141Y766798D03*
X1058383Y776837D03*
Y786877D03*
Y783530D03*
Y800263D03*
Y793570D03*
Y813648D03*
Y806955D03*
Y820341D03*
Y830381D03*
Y823688D03*
Y850459D03*
Y843766D03*
Y837074D03*
Y867192D03*
Y860499D03*
Y857152D03*
Y873885D03*
Y880577D03*
Y887270D03*
Y897310D03*
Y893963D03*
Y917389D03*
Y910696D03*
Y904003D03*
Y924081D03*
Y934121D03*
Y930774D03*
Y947507D03*
Y940814D03*
Y964239D03*
Y957546D03*
Y954200D03*
Y977625D03*
Y970932D03*
Y991011D03*
Y984318D03*
Y994357D03*
Y1021129D03*
Y1024475D03*
Y1031168D03*
Y1044554D03*
Y1037861D03*
Y1051247D03*
Y1071326D03*
Y1064633D03*
Y1078018D03*
Y1094751D03*
Y1088058D03*
Y1081365D03*
Y1108137D03*
Y1101444D03*
Y1124869D03*
Y1118176D03*
Y1114829D03*
Y1144948D03*
Y1138255D03*
Y1131562D03*
Y1161680D03*
Y1154987D03*
Y1151641D03*
Y1175066D03*
Y1168373D03*
Y1181759D03*
Y1191798D03*
Y1188452D03*
Y1205184D03*
Y1198491D03*
Y1218570D03*
Y1211877D03*
Y1225263D03*
Y1241995D03*
Y1235302D03*
Y1228609D03*
X1063241Y1258727D03*
X1061330Y1262074D03*
X1058383Y1248688D03*
X1059410Y1252272D03*
X1063241Y1265420D03*
X1071941Y960892D03*
Y957546D03*
Y967585D03*
X1079383Y994357D03*
X1071941Y1054593D03*
X1076520Y1259072D03*
X1079383Y1258727D03*
X1088262Y1252293D03*
X1079383Y1265420D03*
Y1262074D03*
X1092709Y766775D03*
X1101641Y780184D03*
Y773491D03*
Y786877D03*
Y803609D03*
Y796916D03*
Y790223D03*
Y816995D03*
Y810302D03*
Y833727D03*
Y823688D03*
Y827034D03*
Y847113D03*
Y840420D03*
Y853806D03*
Y860499D03*
Y863845D03*
Y883924D03*
Y877231D03*
Y870538D03*
Y890617D03*
Y897310D03*
Y900656D03*
Y914042D03*
Y907349D03*
Y927428D03*
Y920735D03*
Y934121D03*
Y944160D03*
Y937467D03*
Y960892D03*
Y950853D03*
X1088083Y964239D03*
X1101641Y957546D03*
X1088083D03*
Y954200D03*
X1101641Y980971D03*
Y974278D03*
Y967585D03*
Y994357D03*
Y987664D03*
X1088083Y1021129D03*
Y1024475D03*
X1101641Y1027822D03*
Y1021129D03*
Y1047900D03*
Y1041207D03*
Y1034515D03*
Y1061286D03*
X1088083Y1051247D03*
X1101641Y1054593D03*
Y1074672D03*
Y1067979D03*
Y1091404D03*
Y1081365D03*
Y1084711D03*
Y1098097D03*
Y1111483D03*
Y1104790D03*
Y1128215D03*
Y1118176D03*
Y1121522D03*
Y1141601D03*
Y1134908D03*
Y1148294D03*
Y1154987D03*
Y1158333D03*
Y1171719D03*
Y1165026D03*
Y1185105D03*
Y1178412D03*
Y1191798D03*
Y1208530D03*
Y1201837D03*
Y1195144D03*
Y1221916D03*
Y1215223D03*
Y1238648D03*
Y1228609D03*
Y1231955D03*
X1090273Y1246800D03*
X1101641Y1245341D03*
X1092941Y1258727D03*
X1088083Y1248688D03*
X1091000Y1262074D03*
X1106200Y1250162D03*
X1092941Y1265420D03*
X1103530Y1263602D03*
X1117783Y770144D03*
Y776837D03*
Y786877D03*
Y783530D03*
Y800263D03*
Y793570D03*
Y813648D03*
Y806955D03*
Y820341D03*
Y830381D03*
Y823688D03*
Y850459D03*
Y843766D03*
Y837074D03*
Y867192D03*
Y860499D03*
Y857152D03*
Y873885D03*
Y880577D03*
Y887270D03*
Y897310D03*
Y893963D03*
Y917389D03*
Y910696D03*
Y904003D03*
Y924081D03*
Y934121D03*
Y930774D03*
Y947507D03*
Y940814D03*
Y964239D03*
Y957546D03*
Y954200D03*
Y977625D03*
Y970932D03*
Y991011D03*
Y984318D03*
Y994357D03*
Y1021129D03*
Y1024475D03*
Y1031168D03*
Y1044554D03*
Y1037861D03*
Y1051247D03*
Y1057940D03*
Y1071326D03*
Y1064633D03*
Y1078018D03*
Y1094751D03*
Y1088058D03*
Y1081365D03*
Y1108137D03*
Y1101444D03*
Y1124869D03*
Y1118176D03*
Y1114829D03*
Y1144948D03*
Y1138255D03*
Y1131562D03*
Y1161680D03*
Y1154987D03*
Y1151641D03*
Y1175066D03*
Y1168373D03*
Y1181759D03*
Y1191798D03*
Y1188452D03*
Y1205184D03*
Y1198491D03*
Y1218570D03*
Y1211877D03*
Y1225263D03*
Y1241995D03*
Y1235302D03*
Y1228609D03*
X1120800Y1262074D03*
X1117783Y1248688D03*
X1109083Y1265420D03*
X1109050Y1262972D03*
X1106740Y1267902D03*
X1122541Y766798D03*
X1131341Y960892D03*
Y957546D03*
X1122641Y1258727D03*
X1133200Y1255702D03*
X1122620Y1264622D03*
X1152241Y766798D03*
X1147483Y957546D03*
Y954200D03*
X1138783Y994357D03*
X1152341Y1258727D03*
X1138783Y1255381D03*
Y1258727D03*
Y1252034D03*
X1147483Y1248688D03*
X1150400Y1262074D03*
X1148563Y1257097D03*
X1152341Y1265420D03*
X1138783Y1262027D03*
X1137980Y1264212D03*
X1161041Y780184D03*
Y773491D03*
Y786877D03*
Y803609D03*
Y796916D03*
Y790223D03*
Y883924D03*
Y890617D03*
Y897310D03*
Y900656D03*
Y914042D03*
Y907349D03*
Y960892D03*
Y957546D03*
Y1061286D03*
Y1111483D03*
Y1104790D03*
Y1128215D03*
Y1118176D03*
Y1121522D03*
Y1134908D03*
Y1185105D03*
Y1178412D03*
Y1191798D03*
Y1208530D03*
Y1201837D03*
Y1195144D03*
X1168483Y1255381D03*
Y1258727D03*
Y1252034D03*
Y1265420D03*
Y1262074D03*
X1177183Y770144D03*
Y776837D03*
Y786877D03*
Y783530D03*
Y800263D03*
Y793570D03*
Y880577D03*
Y887270D03*
Y897310D03*
Y893963D03*
Y910696D03*
Y904003D03*
Y957546D03*
Y954200D03*
Y994357D03*
X1177283Y1108137D03*
Y1101444D03*
X1177183Y1124869D03*
X1177283Y1118177D03*
Y1114830D03*
X1177183Y1131562D03*
X1177283Y1175066D03*
Y1181759D03*
Y1191799D03*
Y1188452D03*
Y1205184D03*
Y1198491D03*
X1177120Y1248688D03*
X1177222Y1255567D03*
X1182041Y1265420D03*
X1181850Y1260192D03*
X1179180Y1265872D03*
X1190741Y960892D03*
Y957546D03*
X1198183D03*
Y954200D03*
Y994357D03*
Y1252034D03*
X1198180Y1262112D03*
X1196470Y1265382D03*
X1193590Y1267912D03*
X1195470Y1262802D03*
X1196772Y1590094D03*
X1200172D03*
X1211641Y766798D03*
X1213983Y1000437D03*
X1216663Y1000395D03*
X1212533Y1002557D03*
X1205033D03*
X1207533D03*
X1210033D03*
X1208830Y1256692D03*
X1206883Y1248688D03*
X1207048Y1255174D03*
X1211240Y1265502D03*
X1208750Y1266546D03*
X1212232Y1590094D03*
X1208832D03*
X1214132Y1614292D03*
X1202072D03*
X1217532D03*
X1205472D03*
X1214132Y1602380D03*
X1202072D03*
X1217532D03*
X1205472D03*
X1220441Y960892D03*
Y957546D03*
X1227883D03*
Y954200D03*
Y994357D03*
X1233703Y999608D03*
X1231023Y999650D03*
X1220441Y1061286D03*
X1224189Y1259155D03*
X1226899Y1257968D03*
X1227847Y1251715D03*
X1227670Y1265162D03*
X1225540Y1266402D03*
X1220892Y1590094D03*
X1232952D03*
X1224292D03*
X1226192Y1614292D03*
X1229592D03*
X1226192Y1602380D03*
X1229592D03*
X1236583Y1057940D03*
Y1248688D03*
X1245012Y1590094D03*
X1236352D03*
X1248412D03*
X1238252Y1614292D03*
X1241652D03*
X1238252Y1602380D03*
X1241652D03*
X1257072Y1590094D03*
X1260472D03*
X1262372Y1614292D03*
X1250312D03*
X1265772D03*
X1253712D03*
X1262372Y1602380D03*
X1250312D03*
X1265772D03*
X1253712D03*
X1269132Y1590094D03*
X1281192D03*
X1272532D03*
X1274432Y1614292D03*
X1277832D03*
X1274432Y1602380D03*
X1277832D03*
X1293252Y1590094D03*
X1284592D03*
X1296652D03*
X1298552Y1614292D03*
X1286492D03*
X1289892D03*
X1298552Y1602380D03*
X1286492D03*
X1289892D03*
X1305312Y1590094D03*
X1308712D03*
X1310612Y1614292D03*
X1314012D03*
X1301952D03*
X1310612Y1602380D03*
X1314012D03*
X1301952D03*
X1317372Y1590094D03*
X1320772D03*
X1329432D03*
X1322672Y1614292D03*
X1326072D03*
X1322672Y1602380D03*
X1326072D03*
X1332832Y1590094D03*
X1341492D03*
X1344892D03*
X1346792Y1614292D03*
X1334732D03*
X1338132D03*
X1346792Y1602380D03*
X1334732D03*
X1338132D03*
X1353552Y1590094D03*
X1356952D03*
X1358852Y1614292D03*
X1362252D03*
X1350192D03*
X1358852Y1602380D03*
X1362252D03*
X1350192D03*
X1365612Y1590094D03*
X1377672D03*
X1369012D03*
X1370912Y1614292D03*
X1374312D03*
X1370912Y1602380D03*
X1374312D03*
X1381072Y1590094D03*
X1382972Y1614292D03*
X1386372D03*
X1382972Y1602380D03*
X1386372D03*
X1477755Y1578182D03*
X1462295D03*
X1474355D03*
X1465695D03*
X1477755Y1590094D03*
X1462295D03*
X1474355D03*
X1465695D03*
X1467595Y1614292D03*
X1470995D03*
X1489815Y1578182D03*
X1486415D03*
X1489815Y1590094D03*
X1486415D03*
X1491715Y1614292D03*
X1479655D03*
X1483055D03*
X1501875Y1578182D03*
X1498475D03*
X1501875Y1590094D03*
X1498475D03*
X1503775Y1614292D03*
X1507175D03*
X1495115D03*
X1525995Y1578182D03*
X1513935D03*
X1522595D03*
X1510535D03*
X1525995Y1590094D03*
X1513935D03*
X1522595D03*
X1510535D03*
X1515835Y1614292D03*
X1519235D03*
X1538055Y1578182D03*
X1534655D03*
X1538055Y1590094D03*
X1534655D03*
X1527895Y1614292D03*
X1539955D03*
X1531295D03*
X1550115Y1578182D03*
X1558775D03*
X1546715D03*
X1550115Y1590094D03*
X1558775D03*
X1546715D03*
X1552015Y1614292D03*
X1555415D03*
X1543355D03*
X1574235Y1578182D03*
X1562175D03*
X1570835D03*
X1574235Y1590094D03*
X1562175D03*
X1570835D03*
X1564075Y1614292D03*
X1567475D03*
X1586295Y1578182D03*
X1582895D03*
X1586295Y1590094D03*
X1582895D03*
X1588195Y1614292D03*
X1576135D03*
X1591595D03*
X1579535D03*
X1605800Y766478D03*
X1596941Y960892D03*
Y957546D03*
X1601922Y1000198D03*
X1599489Y999665D03*
X1597041Y1061286D03*
X1606481Y1258649D03*
X1608000Y1261662D03*
X1607897Y1264445D03*
X1598355Y1578182D03*
X1607015D03*
X1594955D03*
X1598355Y1590094D03*
X1607015D03*
X1594955D03*
X1600255Y1614292D03*
X1603655D03*
X1613083Y957546D03*
Y954200D03*
X1616609Y1000735D03*
X1616469Y1003135D03*
X1623539Y1000135D03*
X1620489Y1003135D03*
X1623589Y1002865D03*
X1620399Y1000325D03*
X1621983Y1258727D03*
X1624600Y1262074D03*
X1613183Y1252034D03*
X1613027Y1248805D03*
X1609056Y1250602D03*
X1623930Y1252242D03*
X1613019Y1261235D03*
X1622475Y1578182D03*
X1610415D03*
X1619075D03*
X1622475Y1590094D03*
X1610415D03*
X1619075D03*
X1612315Y1614292D03*
X1615715D03*
X1626741Y766798D03*
X1626641Y960892D03*
Y957546D03*
X1626249Y1002825D03*
X1626741Y1258727D03*
X1634535Y1578182D03*
X1631135D03*
X1634535Y1590094D03*
X1631135D03*
X1636435Y1614292D03*
X1624375D03*
X1639835D03*
X1627775D03*
X1656441Y766798D03*
Y780184D03*
Y773491D03*
Y786877D03*
Y803609D03*
Y796916D03*
Y790223D03*
Y883924D03*
Y890617D03*
Y897310D03*
Y900656D03*
Y914042D03*
Y907349D03*
Y960892D03*
Y957546D03*
X1642783D03*
Y954200D03*
X1648205Y998632D03*
X1656441Y1061286D03*
Y1111483D03*
Y1104790D03*
Y1128215D03*
Y1118176D03*
Y1121522D03*
Y1134908D03*
Y1185105D03*
Y1178412D03*
Y1191798D03*
Y1208530D03*
Y1201837D03*
Y1195144D03*
X1642883Y1255381D03*
Y1258727D03*
Y1252034D03*
X1651679Y1248885D03*
X1653140Y1257862D03*
X1656188Y1264964D03*
X1642788Y1264464D03*
X1642883Y1262074D03*
X1656170Y1260352D03*
X1654600Y1262742D03*
X1646595Y1578182D03*
X1643195D03*
X1646595Y1590094D03*
X1643195D03*
X1651895Y1614292D03*
X1648495D03*
X1672583Y770144D03*
Y776837D03*
Y786877D03*
Y783530D03*
Y800263D03*
Y793570D03*
Y880577D03*
Y887270D03*
Y897310D03*
Y893963D03*
Y910696D03*
Y904003D03*
Y957546D03*
Y954200D03*
Y994357D03*
Y1108136D03*
Y1101444D03*
Y1124869D03*
Y1118176D03*
Y1114829D03*
Y1131562D03*
Y1175066D03*
Y1181758D03*
Y1191798D03*
Y1188451D03*
Y1205184D03*
Y1198491D03*
Y1255381D03*
Y1258727D03*
Y1248688D03*
X1672188Y1263764D03*
X1686041Y766798D03*
Y960892D03*
Y957546D03*
X1686141Y1258727D03*
X1681179Y1252034D03*
X1683578Y1253780D03*
X1686119Y1264985D03*
X1681309Y1262074D03*
X1683500Y1264312D03*
X1702183Y957546D03*
Y954200D03*
Y994357D03*
X1702283Y1057940D03*
X1699852Y1245418D03*
X1699089Y1258842D03*
X1702283Y1248688D03*
X1702249Y1265420D03*
X1702283Y1262074D03*
X1699030Y1263912D03*
X1715841Y766798D03*
Y780184D03*
Y773491D03*
Y786877D03*
Y803609D03*
Y796916D03*
Y790223D03*
Y816995D03*
Y810302D03*
Y833727D03*
Y823688D03*
Y827034D03*
Y847113D03*
Y840420D03*
Y853806D03*
Y860499D03*
Y863845D03*
Y883924D03*
Y877231D03*
Y870538D03*
Y890617D03*
Y897310D03*
Y900656D03*
Y914042D03*
Y907349D03*
Y927428D03*
Y920735D03*
Y934121D03*
Y944160D03*
Y937467D03*
Y960892D03*
Y950853D03*
Y957546D03*
Y980971D03*
Y974278D03*
Y967585D03*
Y994357D03*
Y987664D03*
Y1027822D03*
Y1021129D03*
Y1047900D03*
Y1041207D03*
Y1034514D03*
Y1061286D03*
Y1054593D03*
Y1074672D03*
Y1067979D03*
Y1091404D03*
Y1081365D03*
Y1084711D03*
Y1098097D03*
Y1111483D03*
Y1104790D03*
Y1128215D03*
Y1118176D03*
Y1121522D03*
Y1141601D03*
Y1134908D03*
Y1148294D03*
Y1154987D03*
Y1158333D03*
Y1171719D03*
Y1165026D03*
Y1185105D03*
Y1178412D03*
Y1191798D03*
Y1208530D03*
Y1201837D03*
Y1195144D03*
Y1221916D03*
Y1215223D03*
Y1238648D03*
Y1228609D03*
Y1231955D03*
Y1245341D03*
X1713620Y1258512D03*
X1711109Y1252034D03*
X1713930Y1262074D03*
X1715839Y1265420D03*
X1737020Y112177D03*
Y109677D03*
X1731983Y770144D03*
Y776837D03*
Y786877D03*
Y783530D03*
Y800263D03*
Y793570D03*
Y813648D03*
Y806955D03*
Y820341D03*
Y830381D03*
Y823688D03*
Y850459D03*
Y843766D03*
Y837074D03*
Y867192D03*
Y860499D03*
Y857152D03*
Y873885D03*
Y880577D03*
Y887270D03*
Y897310D03*
Y893963D03*
Y917389D03*
Y910696D03*
Y904003D03*
Y924081D03*
Y934121D03*
Y930774D03*
Y947507D03*
Y940814D03*
Y964239D03*
Y957546D03*
Y954200D03*
Y977625D03*
X1731883Y970932D03*
X1731983Y991011D03*
Y984318D03*
Y994357D03*
Y1021129D03*
Y1024475D03*
Y1031168D03*
X1731683Y1044554D03*
Y1037861D03*
X1731983Y1051247D03*
X1731683Y1057940D03*
X1731818Y1071326D03*
X1731883Y1064633D03*
X1731983Y1078018D03*
Y1094751D03*
Y1088058D03*
Y1081365D03*
X1731818Y1108137D03*
X1731983Y1101444D03*
Y1124869D03*
Y1118176D03*
Y1114829D03*
Y1144947D03*
Y1138255D03*
Y1131562D03*
Y1161680D03*
Y1154987D03*
Y1151640D03*
Y1175066D03*
Y1168373D03*
X1731818Y1181759D03*
X1731983Y1191798D03*
X1731818Y1188452D03*
X1731983Y1205184D03*
Y1198491D03*
Y1218569D03*
Y1211877D03*
Y1225262D03*
Y1241995D03*
Y1235302D03*
Y1228609D03*
X1727041Y1248688D03*
X1731983Y1255381D03*
Y1258727D03*
Y1252034D03*
Y1248688D03*
X1731939Y1265420D03*
X1731983Y1262074D03*
X1747650Y109677D03*
Y112177D03*
X1744106Y109677D03*
Y112177D03*
X1740563Y109677D03*
Y112177D03*
X1745541Y766798D03*
Y960892D03*
Y957546D03*
Y967585D03*
Y1054593D03*
Y1258727D03*
X1743710Y1262074D03*
X1742337Y1252300D03*
X1745541Y1265420D03*
X1761683Y964239D03*
Y957546D03*
Y954200D03*
Y994357D03*
Y1021129D03*
Y1024475D03*
Y1051247D03*
X1756922Y1247632D03*
X1761683Y1255381D03*
Y1258727D03*
X1770299Y1252034D03*
X1761683Y1248688D03*
Y1262074D03*
Y1265420D03*
X1773559Y767345D03*
X1775241Y780184D03*
Y773491D03*
Y786877D03*
Y803609D03*
Y796916D03*
Y790223D03*
Y816995D03*
Y810302D03*
Y833727D03*
Y823688D03*
Y827034D03*
Y847113D03*
Y840420D03*
Y853806D03*
Y860499D03*
Y863845D03*
Y883924D03*
Y877231D03*
Y870538D03*
Y890617D03*
Y897310D03*
Y900656D03*
Y914042D03*
Y907349D03*
Y927428D03*
Y920735D03*
Y934121D03*
Y944160D03*
Y937467D03*
Y960892D03*
Y950853D03*
Y957546D03*
Y980971D03*
Y974278D03*
Y967585D03*
Y994357D03*
Y987664D03*
Y1027822D03*
Y1021129D03*
Y1047900D03*
Y1041207D03*
Y1034515D03*
Y1061286D03*
Y1054593D03*
Y1074672D03*
Y1067979D03*
Y1091404D03*
Y1081365D03*
Y1084711D03*
Y1098097D03*
Y1111483D03*
Y1104790D03*
Y1128215D03*
Y1118176D03*
Y1121522D03*
Y1141601D03*
Y1134908D03*
Y1148294D03*
Y1154987D03*
Y1158333D03*
Y1171719D03*
Y1165026D03*
Y1185105D03*
Y1178412D03*
Y1191798D03*
Y1208530D03*
Y1201837D03*
Y1195144D03*
Y1221916D03*
Y1215223D03*
Y1238648D03*
Y1228609D03*
Y1231955D03*
Y1245341D03*
Y1258727D03*
X1788219Y1259312D03*
X1773390Y1262074D03*
X1773480Y1253692D03*
X1775241Y1265420D03*
X1788360Y1264522D03*
X1791383Y770144D03*
Y776837D03*
Y786877D03*
Y783530D03*
Y800263D03*
Y793570D03*
Y813648D03*
Y806955D03*
Y820341D03*
Y830381D03*
Y823688D03*
Y850459D03*
Y843766D03*
Y837074D03*
Y867192D03*
Y860499D03*
Y857152D03*
Y873885D03*
Y880577D03*
Y887270D03*
Y897310D03*
Y893963D03*
Y917389D03*
Y910696D03*
Y904003D03*
Y924081D03*
Y934121D03*
Y930774D03*
Y947507D03*
Y940814D03*
Y964239D03*
Y957546D03*
Y954200D03*
Y977625D03*
Y970932D03*
Y991011D03*
Y984318D03*
Y994357D03*
Y1021129D03*
Y1024475D03*
Y1031168D03*
Y1044554D03*
Y1037861D03*
X1791083Y1051247D03*
X1791383Y1071325D03*
Y1064633D03*
Y1078018D03*
Y1094751D03*
Y1088058D03*
Y1081365D03*
Y1108136D03*
Y1101444D03*
Y1124869D03*
Y1118176D03*
Y1114829D03*
Y1144947D03*
Y1138255D03*
Y1131562D03*
Y1161680D03*
Y1154987D03*
Y1151640D03*
Y1175066D03*
Y1168373D03*
Y1181758D03*
Y1191798D03*
Y1188451D03*
Y1205184D03*
Y1198491D03*
Y1218570D03*
Y1211877D03*
Y1225263D03*
X1788373Y1241769D03*
X1791383Y1241995D03*
Y1235302D03*
Y1228609D03*
X1800427Y1248125D03*
X1803100Y1262074D03*
X1800019Y1252034D03*
X1791383Y1248688D03*
Y1265420D03*
Y1262074D03*
X1804841Y766798D03*
X1804941Y960892D03*
Y957546D03*
Y967585D03*
Y1054593D03*
X1815063Y1233103D03*
X1804941Y1258727D03*
X1813814Y1254693D03*
X1804941Y1265420D03*
X1821083Y964239D03*
X1820983Y957546D03*
Y954200D03*
Y994357D03*
X1821083Y1021129D03*
Y1024475D03*
Y1051247D03*
X1830379Y1250358D03*
X1829920Y1258322D03*
X1821139Y1248155D03*
X1821083Y1262074D03*
Y1265420D03*
X1829940Y1263662D03*
G54D29*
X159474Y1328627D03*
X183847Y1328652D03*
X208247D03*
X275289Y583576D03*
Y607735D03*
Y631889D03*
Y656043D03*
X270252Y676260D03*
Y700414D03*
X387897Y1242785D03*
X412297D03*
X436619D03*
X461019D03*
X485419D03*
X673093Y1328652D03*
X697466Y1328677D03*
X721866D03*
X1100800Y259362D03*
X1100700Y283662D03*
X1131100Y1364962D03*
X1155500D03*
X1179900D03*
X1364038Y1242785D03*
X1388438D03*
X1412760D03*
X1437160D03*
X1461560D03*
X1577000Y599762D03*
Y624262D03*
Y648762D03*
Y673162D03*
Y697662D03*
Y722162D03*
X1634259Y1362248D03*
X1658632Y1362273D03*
X1683032D03*
G54D51*
X705760Y-26500D03*
Y-16500D03*
D03*
Y-6500D03*
X730760Y-26500D03*
Y-16500D03*
D03*
Y-6500D03*
X822720Y3500D03*
Y13500D03*
D03*
Y23500D03*
X847720Y3500D03*
Y13500D03*
D03*
Y23500D03*
X973180Y-26500D03*
Y-16500D03*
D03*
Y-6500D03*
Y3500D03*
Y13500D03*
Y23500D03*
Y13500D03*
X998180Y-26500D03*
Y-16500D03*
D03*
Y-6500D03*
Y3500D03*
Y13500D03*
Y23500D03*
Y13500D03*
X1015152Y-26511D03*
Y-36511D03*
Y-26511D03*
Y-16511D03*
D03*
Y-6511D03*
D03*
Y3489D03*
D03*
Y13489D03*
D03*
Y23489D03*
X1040152Y-26511D03*
Y-36511D03*
Y-26511D03*
Y-16511D03*
D03*
Y-6511D03*
D03*
Y3489D03*
D03*
Y13489D03*
D03*
Y23489D03*
X1282572Y-36511D03*
Y-26511D03*
D03*
Y-16511D03*
D03*
Y-6511D03*
Y3489D03*
Y-6511D03*
Y3489D03*
Y13489D03*
Y23489D03*
Y13489D03*
X1307572Y-36511D03*
Y-26511D03*
D03*
Y-16511D03*
D03*
Y-6511D03*
Y3489D03*
Y-6511D03*
Y3489D03*
Y13489D03*
Y23489D03*
Y13489D03*
X1324471Y-26511D03*
Y-36511D03*
Y-26511D03*
Y-16511D03*
D03*
Y-6511D03*
D03*
Y3489D03*
D03*
Y13489D03*
D03*
Y23489D03*
X1349471Y-26511D03*
Y-36511D03*
Y-26511D03*
Y-16511D03*
D03*
Y-6511D03*
D03*
Y3489D03*
D03*
Y13489D03*
D03*
Y23489D03*
X1474931Y-36511D03*
Y-26511D03*
D03*
Y-16511D03*
D03*
Y-6511D03*
Y3489D03*
Y-6511D03*
Y3489D03*
Y13489D03*
Y23489D03*
Y13489D03*
X1499931Y-36511D03*
Y-26511D03*
D03*
Y-16511D03*
D03*
Y-6511D03*
Y3489D03*
Y-6511D03*
Y3489D03*
Y13489D03*
Y23489D03*
Y13489D03*
X1565236Y184783D03*
Y264035D03*
G54D54*
X793879Y194881D03*
X789942Y204724D03*
X793879Y214567D03*
X805690Y188976D03*
Y220472D03*
X817501Y194881D03*
Y214567D03*
X821438Y204724D03*
X841240Y1407480D03*
X832154Y1411244D03*
X828390Y1420330D03*
X832154Y1429416D03*
X841240Y1433180D03*
X850326Y1411244D03*
X854090Y1420330D03*
X850326Y1429416D03*
X1003390Y1420330D03*
X1016240Y1407480D03*
X1007154Y1411244D03*
Y1429416D03*
X1016240Y1433180D03*
X1025326Y1411244D03*
X1029090Y1420330D03*
X1025326Y1429416D03*
X1045847Y194881D03*
X1041910Y204724D03*
X1045847Y214567D03*
X1069469Y194881D03*
X1057658Y188976D03*
X1069469Y214567D03*
X1057658Y220472D03*
X1073406Y204724D03*
G54D11*
X3010Y63308D03*
Y123308D03*
Y163308D03*
Y183308D03*
Y203308D03*
Y223308D03*
Y243308D03*
Y263308D03*
Y283308D03*
Y303308D03*
X10884Y321693D03*
Y341693D03*
Y361693D03*
Y381693D03*
Y401693D03*
Y421693D03*
Y441693D03*
Y461693D03*
Y481693D03*
Y501693D03*
Y521693D03*
Y661693D03*
Y681693D03*
Y701693D03*
Y721693D03*
Y741693D03*
Y781693D03*
Y801693D03*
Y821693D03*
Y841693D03*
Y861693D03*
Y881693D03*
Y901693D03*
Y921693D03*
Y941693D03*
Y961693D03*
Y981693D03*
Y1001693D03*
Y1021693D03*
Y1041693D03*
Y1061693D03*
Y1081693D03*
Y1101693D03*
Y1121693D03*
Y1141693D03*
Y1161693D03*
Y1181693D03*
Y1201693D03*
Y1221693D03*
Y1241693D03*
Y1401693D03*
Y1421693D03*
Y1441693D03*
Y1461693D03*
Y1481693D03*
Y1501693D03*
Y1521693D03*
Y1541693D03*
Y1561693D03*
Y1581693D03*
X26615Y670036D03*
X28601Y1617541D03*
Y1637541D03*
Y1657541D03*
Y1677541D03*
X38220Y595862D03*
X54593Y19183D03*
X87565Y670441D03*
X94473Y698926D03*
X127313Y649765D03*
X114021Y669409D03*
X118021D03*
X127738Y659226D03*
X117220Y1680287D03*
X130067Y650213D03*
X134205Y643603D03*
X128193Y662015D03*
X128275Y665515D03*
X190800Y675662D03*
X219752Y1405499D03*
Y1401999D03*
Y1398599D03*
X259845Y461117D03*
X282640Y214102D03*
X301751Y127466D03*
Y124466D03*
Y121466D03*
X311758Y124469D03*
Y121469D03*
Y127469D03*
X313995Y237724D03*
X335285Y210609D03*
X332285D03*
X325755Y230719D03*
X338985Y229509D03*
X325855Y227619D03*
X325055Y237219D03*
X328965Y237214D03*
X332465D03*
X381068Y1674824D03*
X373320Y1688202D03*
X388220Y1631404D03*
X445944Y359053D03*
X446730Y382432D03*
X443744Y429553D03*
X451421D03*
X443744Y452462D03*
X437520Y484837D03*
X447520D03*
X442520D03*
X451520D03*
X448079Y1562177D03*
X443910Y1555602D03*
X450020Y1570412D03*
X453621Y359053D03*
X462720Y404762D03*
X465421Y424928D03*
X466520Y475812D03*
X456520Y484837D03*
X461520D03*
X456961Y1559697D03*
X456020Y1580412D03*
X464020D03*
X462079Y1572177D03*
X454661Y1596755D03*
X459779Y1609235D03*
X480393Y429412D03*
X479169Y484696D03*
X474169D03*
X484169D03*
X478308Y1439986D03*
X502070Y424787D03*
X488070Y429412D03*
X498169Y484696D03*
X493169D03*
X488169D03*
X513444Y473281D03*
X503169Y475671D03*
X550024Y369123D03*
Y401023D03*
X557701Y369123D03*
X649218Y504277D03*
X641386Y1687283D03*
X661534Y41748D03*
X656877Y514716D03*
X661743Y521166D03*
X657734Y528255D03*
X656725Y1657619D03*
X669004Y41698D03*
X694720Y491962D03*
X690720D03*
X702462Y1673258D03*
X725537Y-23978D03*
Y-19022D03*
Y-13978D03*
Y-9022D03*
X719194Y172909D03*
X714202D03*
X719194Y177865D03*
X714202D03*
X719194Y184909D03*
X714202D03*
X719194Y189865D03*
X714202D03*
X719194Y196409D03*
X714202D03*
X719194Y201365D03*
X714202D03*
X719194Y208243D03*
X714202D03*
X719194Y213199D03*
X714202D03*
X714203Y1639776D03*
X745685Y265322D03*
Y269322D03*
X742655Y1682362D03*
Y1678362D03*
X761720Y283262D03*
X748085Y278942D03*
X758360Y276122D03*
X755859Y1686090D03*
X755183Y1709850D03*
X764850Y249792D03*
X763359Y1729520D03*
X785135Y281822D03*
Y267822D03*
X842497Y6022D03*
Y16022D03*
Y20978D03*
Y10978D03*
X908675Y455386D03*
X913913Y455396D03*
X957420Y153699D03*
X960420D03*
X968022Y1620730D03*
X965022D03*
X971022D03*
X965022Y1632730D03*
X968022Y1629730D03*
X965022D03*
X968022Y1626730D03*
X965022D03*
Y1623730D03*
X968022D03*
X971022Y1626730D03*
Y1623730D03*
Y1629730D03*
Y1632730D03*
X968022D03*
X981445Y181058D03*
X1002735Y153943D03*
X999735D03*
X999915Y180548D03*
X996415D03*
X992505Y180553D03*
X993205Y174053D03*
X993305Y170953D03*
X990495Y212923D03*
X1001065Y304622D03*
Y307122D03*
Y309622D03*
X996662Y1620870D03*
X999662D03*
X1002662D03*
Y1626870D03*
Y1623870D03*
X996662Y1629870D03*
X999662Y1626870D03*
X996662D03*
Y1623870D03*
X999662D03*
X996662Y1632870D03*
X1021908Y60392D03*
Y120392D03*
X1015300Y148736D03*
X1012187Y148749D03*
X1006435Y172843D03*
X1009895Y192359D03*
X1008067Y194356D03*
X1019935Y206463D03*
Y203333D03*
X1010828Y304822D03*
Y307322D03*
Y309822D03*
X1034929Y-33989D03*
Y-29033D03*
Y-13989D03*
Y-9033D03*
Y-23989D03*
Y-19033D03*
Y-3989D03*
Y967D03*
X1036915Y290969D03*
X1035920Y428962D03*
X1034252Y1623870D03*
Y1626870D03*
X1031252Y1623870D03*
Y1626870D03*
X1028252Y1623870D03*
Y1626870D03*
X1031252Y1620870D03*
X1034252D03*
X1028252D03*
X1065721Y1633043D03*
X1068721D03*
Y1624043D03*
Y1627043D03*
Y1630043D03*
X1065721Y1624043D03*
Y1627043D03*
Y1630043D03*
X1062721Y1633043D03*
Y1624043D03*
Y1627043D03*
Y1630043D03*
X1059721Y1633043D03*
Y1624043D03*
Y1627043D03*
Y1630043D03*
X1068721Y1621043D03*
X1065721D03*
X1062721D03*
X1059721D03*
X1099901Y1633203D03*
Y1624203D03*
Y1627203D03*
Y1630203D03*
Y1621203D03*
X1093901Y1633203D03*
X1096901D03*
Y1624203D03*
Y1627203D03*
Y1630203D03*
X1093901Y1624203D03*
Y1627203D03*
Y1630203D03*
X1090901Y1633203D03*
X1087901D03*
X1090901Y1624203D03*
X1087901D03*
Y1627203D03*
X1090901D03*
X1087901Y1630203D03*
X1090901D03*
X1096901Y1621203D03*
X1093901D03*
X1087901D03*
X1090901D03*
X1132142Y1555301D03*
X1120472Y1615010D03*
X1127377Y1628485D03*
X1131632Y1625969D03*
X1148220Y501362D03*
X1139392Y1620851D03*
X1172720Y527862D03*
X1202600Y759662D03*
X1245574Y234042D03*
X1245593Y241462D03*
Y237462D03*
X1280223Y256841D03*
X1279841Y253052D03*
X1344248Y-33989D03*
Y-29033D03*
Y-13989D03*
Y-9033D03*
Y-23989D03*
Y-19033D03*
Y-3989D03*
Y967D03*
X1412954Y138742D03*
X1404402D03*
X1409716Y171696D03*
X1418268D03*
X1454829Y1439732D03*
X1465179Y213102D03*
X1477700Y236522D03*
X1466292Y631634D03*
X1473228D03*
X1486884Y374338D03*
X1479207D03*
X1478203Y406207D03*
X1493384Y419263D03*
X1481384Y419392D03*
X1505378Y225502D03*
X1509571Y239053D03*
X1507860Y249792D03*
X1513110Y247412D03*
X1522883Y305187D03*
X1526216Y306909D03*
X1529002Y32290D03*
X1528716Y306909D03*
X1533716D03*
X1536216D03*
X1534899Y310447D03*
X1559387Y589340D03*
X1564690Y663302D03*
X1619980Y590685D03*
X1615800Y584062D03*
X1620170Y623762D03*
X1622770D03*
X1612980D03*
X1620170Y626362D03*
X1622770D03*
X1612980D03*
X1615580Y650092D03*
Y657762D03*
X1620170D03*
X1622770D03*
X1622109Y652469D03*
X1619509D03*
X1612980Y657762D03*
Y650092D03*
X1615580Y660362D03*
X1620170D03*
X1622770D03*
X1612980D03*
X1622109Y686469D03*
X1619509D03*
X1615580Y684092D03*
X1612980D03*
X1622770Y691762D03*
Y694362D03*
X1620170Y691762D03*
Y694362D03*
X1615580D03*
X1612980D03*
X1615580Y691762D03*
X1612980D03*
X1619509Y720469D03*
X1622109D03*
X1612980Y718092D03*
X1615580D03*
X1610100Y725152D03*
X1637667Y587844D03*
Y590444D03*
X1629867D03*
Y587844D03*
X1632467Y590444D03*
Y587844D03*
X1635067Y590444D03*
Y587844D03*
X1626606Y616576D03*
X1629206D03*
X1631806D03*
X1634406D03*
X1637006D03*
X1639606D03*
X1630570Y623762D03*
X1627970D03*
X1625370D03*
X1636412Y638451D03*
X1636417Y630007D03*
X1640061Y639497D03*
X1636412Y641051D03*
X1630570Y626362D03*
X1627970D03*
X1625370D03*
X1630198Y638651D03*
Y636051D03*
Y641251D03*
X1633305Y638651D03*
Y641251D03*
X1630198Y632851D03*
X1630214Y629907D03*
X1633321D03*
X1640061Y644457D03*
Y641977D03*
X1630570Y657762D03*
X1627970D03*
X1625370D03*
X1629909Y652469D03*
X1632509D03*
X1624709D03*
X1627309D03*
X1630198Y643851D03*
X1633305Y646451D03*
Y643851D03*
X1630198Y646451D03*
X1636412Y672451D03*
X1636417Y664007D03*
X1640061Y673497D03*
X1630570Y660362D03*
X1627970D03*
X1625370D03*
X1630198Y672651D03*
Y670051D03*
X1633305Y672651D03*
X1630198Y666851D03*
X1630214Y663907D03*
X1633321D03*
X1629909Y686469D03*
X1632509D03*
X1624709D03*
X1627309D03*
X1640061Y678457D03*
Y675977D03*
X1636412Y675051D03*
X1630198Y677851D03*
Y675251D03*
X1633305Y680451D03*
Y675251D03*
Y677851D03*
X1630198Y680451D03*
X1636417Y698007D03*
X1636412Y706451D03*
X1630214Y697907D03*
X1633321D03*
X1630198Y704051D03*
Y706651D03*
X1633305D03*
X1630198Y700851D03*
X1625370Y691762D03*
Y694362D03*
X1630570D03*
Y691762D03*
X1627970D03*
Y694362D03*
X1640061Y707497D03*
Y712457D03*
Y709977D03*
X1636412Y709051D03*
X1632509Y720469D03*
X1627309D03*
X1629909D03*
X1624709D03*
X1633305Y711851D03*
Y709251D03*
X1630198D03*
Y711851D03*
X1633305Y714451D03*
X1630198D03*
X1642873Y604206D03*
Y607206D03*
X1645625Y600495D03*
Y603295D03*
X1642873Y601206D03*
Y598206D03*
X1645625Y597795D03*
Y594995D03*
X1642873Y595006D03*
X1642340Y618546D03*
X1642873Y610206D03*
X1645661Y639497D03*
X1656550Y653086D03*
X1645661Y644457D03*
Y641977D03*
Y673497D03*
X1656550Y687086D03*
X1645661Y678457D03*
Y675977D03*
Y707497D03*
Y709977D03*
Y712457D03*
X1665700Y583462D03*
X1661510Y583442D03*
X1672770Y580512D03*
X1669770D03*
X1663720Y620434D03*
X1659914Y649681D03*
Y683681D03*
Y717681D03*
X1686154Y434160D03*
X1704444Y407045D03*
X1697914Y427155D03*
X1698014Y424055D03*
X1701124Y433650D03*
X1697214Y433655D03*
X1704624Y433650D03*
X1717280Y174970D03*
X1707444Y407045D03*
X1711144Y425945D03*
X1765870Y179392D03*
X1780320Y177602D03*
G54D14*
X26054Y195148D03*
X25752Y203274D03*
X24754Y220220D03*
X24814Y236472D03*
X35600Y227380D03*
X45182Y426310D03*
X45034Y449106D03*
X62833Y410047D03*
X62808Y418425D03*
X50138Y426310D03*
X60393D03*
X49990Y449106D03*
X73020Y28406D03*
Y40020D03*
X65349Y426310D03*
X75516Y436519D03*
X73865Y763164D03*
X94279Y28406D03*
X87193D03*
X80106D03*
X94279Y40020D03*
X87193D03*
X80106D03*
X85826Y424319D03*
Y420319D03*
X82661Y449604D03*
X79451Y699517D03*
X92895Y1737108D03*
X108453Y28406D03*
X101366D03*
X108453Y40020D03*
X101366D03*
X104220Y400862D03*
X101720D03*
X113597Y488434D03*
X102152Y509374D03*
X102334Y500628D03*
X102359Y497374D03*
X102152Y513374D03*
X108909Y654926D03*
X102909Y648926D03*
Y642926D03*
Y655102D03*
X108909Y642926D03*
X122626Y28406D03*
X115539D03*
X122626Y40020D03*
X115539D03*
X125007Y392071D03*
Y388071D03*
Y384071D03*
Y396071D03*
X114507Y404571D03*
X117597Y488434D03*
X114909Y654926D03*
Y648926D03*
Y642926D03*
X116798Y1617262D03*
X112895Y1737108D03*
X129713Y28406D03*
Y40020D03*
X136301Y179095D03*
X143340Y204622D03*
X140974Y396885D03*
Y401885D03*
Y399385D03*
X142166Y490835D03*
X144263Y1412275D03*
X138492Y1717592D03*
X132895Y1737108D03*
X158492Y28406D03*
X151405D03*
X158492Y40020D03*
X151405D03*
X147901Y188852D03*
X159125Y448664D03*
X152171Y490615D03*
X149472Y502810D03*
X149486Y498810D03*
X149518Y522810D03*
X159898Y1360790D03*
X152895Y1737108D03*
X172665Y28406D03*
X165579D03*
X172665Y40020D03*
X165579D03*
X175640Y453779D03*
X162398Y1360790D03*
X164898D03*
X172895Y1737108D03*
X166761Y1732967D03*
X179752Y28406D03*
Y40020D03*
X184490Y402203D03*
X191305Y430216D03*
X188221Y454048D03*
X184147Y447078D03*
X192895Y1737108D03*
X202626Y28406D03*
X195539D03*
X202626Y40020D03*
X195539D03*
X199047Y428626D03*
X199139Y422882D03*
X196215Y447565D03*
X194858Y684348D03*
X203441Y1360790D03*
X198041D03*
X200941D03*
X223886Y28406D03*
X216799D03*
X209713D03*
X223886Y40020D03*
X216799D03*
X209713D03*
X223330Y426467D03*
X220843Y430004D03*
X220874Y442079D03*
X224137Y1414345D03*
X224077Y1416975D03*
X224350Y1432032D03*
X212895Y1737108D03*
X230972Y28406D03*
Y40020D03*
X242215Y151788D03*
X253000Y28362D03*
X256500D03*
X249500D03*
X252195Y144320D03*
X257434Y415896D03*
X252895Y1737108D03*
X260000Y28362D03*
X258746Y407842D03*
X260807Y424403D03*
X270322Y740207D03*
X272895Y1737108D03*
X286071Y28406D03*
X278984D03*
X279277Y99183D03*
X289557Y121803D03*
X280687Y140746D03*
X284482Y569548D03*
X286582Y630757D03*
X305025Y144202D03*
X302891Y141811D03*
X292895Y1737108D03*
X324733Y148598D03*
X321119Y1313108D03*
X317119D03*
X313119D03*
X330417Y380482D03*
X336370Y406302D03*
X325119Y1313108D03*
X328915Y1326704D03*
X331515D03*
X332895Y1737108D03*
X344776Y148462D03*
X343411Y363143D03*
Y375364D03*
X343354Y387988D03*
X343720Y400628D03*
X339769Y1299868D03*
X342769D03*
X352895Y1737108D03*
X366675Y158702D03*
X364179Y394596D03*
X371066Y400628D03*
X369690Y431812D03*
X365970Y444662D03*
X361769Y1300008D03*
X364769D03*
X383140Y119822D03*
X375330Y121182D03*
X374981Y131433D03*
X376770Y387272D03*
X385520Y429262D03*
X373190Y438342D03*
X384510Y438662D03*
X385730Y460922D03*
X382860Y471122D03*
X383239Y1286578D03*
X378069Y1286568D03*
X375069D03*
X386239Y1286578D03*
X372895Y1737108D03*
X403700Y402422D03*
X390892Y406863D03*
X403260Y439352D03*
X391150Y445302D03*
X396570Y472602D03*
X391360Y495712D03*
X402780Y499372D03*
X394860Y518812D03*
X403200Y572622D03*
X396139Y1286708D03*
X399139D03*
X400926Y1402207D03*
X391249Y1401048D03*
X396921Y1549810D03*
X396946Y1560810D03*
X419012Y368762D03*
X418602Y394722D03*
X417010Y439352D03*
X415130Y480202D03*
X410532Y1153341D03*
X407948Y1153370D03*
Y1161570D03*
X410532Y1161541D03*
X407948Y1169597D03*
X410532D03*
X429050Y117491D03*
X430980Y132672D03*
X432006Y363644D03*
X431596Y389604D03*
X424980Y439462D03*
X427790Y500862D03*
X427880Y506442D03*
X428510Y515842D03*
X436822Y1161570D03*
Y1153370D03*
X431722D03*
Y1161570D03*
X434272Y1153370D03*
Y1161570D03*
X436822Y1170070D03*
X431722D03*
X434272D03*
X430999Y1286758D03*
X423229D03*
X426229D03*
X433999D03*
X436920Y1541562D03*
X422566Y1550046D03*
X432996Y1558322D03*
X436840Y1632682D03*
X436880Y1622442D03*
X432895Y1737108D03*
X447100Y1622562D03*
X447020Y1632632D03*
X452895Y1737108D03*
X465236Y293823D03*
X467736Y312938D03*
X455326Y520389D03*
X457196Y1161570D03*
X459696D03*
X462196D03*
X459696Y1153370D03*
X457196D03*
X462196D03*
X459696Y1170070D03*
X462196D03*
X457196D03*
X460049Y1286978D03*
X463049D03*
X469019Y1286718D03*
X465749Y1401238D03*
X455602Y1412334D03*
X473870Y506622D03*
X474220Y572782D03*
X471940Y597532D03*
X483030Y1153370D03*
Y1161570D03*
Y1170070D03*
X474509Y1286848D03*
X481509D03*
X477509D03*
X484509D03*
X475285Y1395402D03*
X477835Y1673462D03*
Y1685462D03*
X472895Y1737108D03*
X498636Y293123D03*
X501136Y312238D03*
X486861Y309398D03*
X490759Y1291978D03*
X495309Y1300058D03*
X498309D03*
X492895Y1737108D03*
X517914Y42257D03*
X517902Y49194D03*
X510815D03*
X517989Y1300108D03*
X514989D03*
X508881Y1404880D03*
X506181D03*
X503559Y1405025D03*
X508775Y1409889D03*
X508828Y1407385D03*
X508802Y1412420D03*
X506075Y1409889D03*
X506128Y1407385D03*
X503572Y1407539D03*
Y1415039D03*
Y1412539D03*
X506102Y1412420D03*
X503572Y1410039D03*
X512895Y1737108D03*
X525000Y42257D03*
X524988Y49194D03*
X532533Y299500D03*
X529533D03*
X526941Y447802D03*
X521561Y550819D03*
X526280Y569122D03*
X520710Y592552D03*
X532895Y1737108D03*
X549610Y120682D03*
X535290Y572932D03*
X543450Y590262D03*
X562780Y32842D03*
X564430Y45132D03*
X565849Y1346968D03*
X552895Y1737108D03*
X578620Y45112D03*
X573849Y1346968D03*
X569849D03*
X572895Y1737108D03*
X596840Y45152D03*
X593925Y49193D03*
X590350Y294402D03*
X607890Y34389D03*
X615420Y42342D03*
X605060Y42402D03*
X615185Y49193D03*
X611310Y266272D03*
X612895Y1737108D03*
X621740Y265952D03*
X632895Y1737108D03*
X661681Y49193D03*
X654595D03*
X652895Y1737108D03*
X675854Y49193D03*
X668768D03*
X673517Y1360815D03*
X676017D03*
X678517D03*
X671112Y1639962D03*
X672895Y1737108D03*
X697122Y1632667D03*
X683592Y1634844D03*
X697197Y1644667D03*
X712433Y103308D03*
X712060Y1360815D03*
X722580Y49182D03*
X724133Y141288D03*
X713820Y488762D03*
Y484662D03*
X714560Y1360815D03*
X717060D03*
X744800Y1664840D03*
X732895Y1737108D03*
X762198Y129684D03*
Y126684D03*
X758110Y172636D03*
X752895Y1737108D03*
X777283Y320892D03*
X772208Y1731911D03*
X792208D03*
X810781Y372615D03*
X821164Y372312D03*
X812208Y1731911D03*
X836502Y161553D03*
X837975Y210064D03*
X832208Y1731911D03*
X856776Y129268D03*
X846846Y127064D03*
X851895Y160262D03*
X849710Y212062D03*
X845220Y216532D03*
X854706Y229878D03*
X852206D03*
X856842Y410760D03*
X852208Y1731911D03*
X874295Y163862D03*
X863488Y176332D03*
X872208Y1731911D03*
X886280Y174085D03*
X887671Y487831D03*
Y494767D03*
X878931Y509051D03*
X878941Y503813D03*
X892208Y1731911D03*
X899625Y473856D03*
X893321Y480293D03*
X893311Y485531D03*
X893572Y503050D03*
Y496114D03*
X920246Y184138D03*
X914550Y239924D03*
X923403Y983327D03*
X923322Y990227D03*
X921880Y1525110D03*
X924380D03*
X921880Y1527610D03*
X924380D03*
X912208Y1731911D03*
X935496Y195925D03*
Y203012D03*
Y210098D03*
Y217185D03*
Y224272D03*
Y231358D03*
X940596Y498648D03*
X939097Y527257D03*
X939282Y534020D03*
X930233Y983298D03*
X930274Y990237D03*
X939380Y1525110D03*
X926880D03*
X929380D03*
X931880D03*
X934380D03*
X936880D03*
X926880Y1527610D03*
X929380D03*
X931880D03*
X934380D03*
X936880D03*
X939380D03*
X932208Y1731911D03*
X947190Y527330D03*
X952208Y1731911D03*
X972208D03*
X989910Y-27961D03*
X989925Y-25446D03*
X983632Y-26655D03*
X989925Y-21572D03*
X983632Y-16626D03*
X989910Y-17932D03*
X989925Y-15417D03*
Y-11543D03*
X989910Y-7903D03*
X989925Y-5388D03*
X983632Y-6597D03*
X989925Y4641D03*
X989910Y2126D03*
X983632Y3432D03*
X989925Y14670D03*
X989910Y12155D03*
X989925Y8515D03*
X983632Y13461D03*
X989925Y19044D03*
X983632Y23990D03*
X987259Y276094D03*
X998500Y269862D03*
X1002500D03*
X992208Y1731911D03*
X1014500Y269862D03*
X1018000D03*
X1006500D03*
X1010500D03*
X1021419Y305704D03*
X1012208Y1731911D03*
X1032208D03*
X1053028Y246518D03*
X1053428Y261118D03*
X1052208Y1731911D03*
X1058028Y246518D03*
X1055528D03*
X1068093Y265503D03*
X1058428Y261118D03*
X1055928D03*
X1067618Y273800D03*
X1070718Y273700D03*
X1067718Y285600D03*
X1070618D03*
X1072208Y1731911D03*
X1102561Y78461D03*
X1117574Y1448604D03*
X1111866Y1737108D03*
X1135709Y1397119D03*
X1133209D03*
X1127008Y1524203D03*
X1135748Y1524187D03*
X1131866Y1737108D03*
X1138209Y1397119D03*
X1170337Y607327D03*
X1171752Y1397119D03*
X1176752D03*
X1174252D03*
X1179922Y1524203D03*
X1201110Y1681767D03*
X1191866Y1737108D03*
X1211866D03*
X1231866D03*
X1253586Y1334649D03*
X1257586D03*
X1251866Y1737108D03*
X1276745Y125850D03*
X1275807Y132922D03*
X1281600Y137962D03*
X1282568Y212722D03*
X1272707Y1334865D03*
X1271866Y1737108D03*
X1293024Y-36695D03*
Y-26666D03*
Y-16637D03*
Y-6608D03*
Y3421D03*
Y13450D03*
Y23979D03*
X1291280Y58262D03*
X1293860Y58312D03*
X1284930Y124922D03*
X1285793Y141562D03*
X1288258Y145501D03*
X1283781Y149115D03*
Y155788D03*
X1283425Y179272D03*
X1283397Y202085D03*
X1295150Y1323217D03*
X1298150D03*
X1291010Y1323307D03*
X1288010D03*
X1291866Y1737108D03*
X1299317Y-35486D03*
Y-31612D03*
X1299302Y-38001D03*
Y-27972D03*
X1299317Y-25457D03*
Y-21583D03*
X1299302Y-17943D03*
X1299317Y-15428D03*
Y-11554D03*
X1299302Y-7914D03*
X1299317Y-5399D03*
Y4630D03*
X1299302Y2115D03*
X1299317Y-1525D03*
Y14659D03*
X1299302Y12144D03*
X1299317Y8504D03*
Y19033D03*
X1304066Y1323578D03*
X1307656Y1326704D03*
X1305056D03*
X1311866Y1737108D03*
X1323958Y146227D03*
X1333811Y235348D03*
X1338652Y536654D03*
Y543590D03*
X1337663Y1301001D03*
X1340663D03*
X1331866Y1737108D03*
X1349704Y145385D03*
X1357888Y145893D03*
X1361111Y236448D03*
X1353982Y1287048D03*
X1362382D03*
X1359382D03*
X1350982D03*
X1351866Y1737108D03*
X1366868Y147341D03*
X1369593Y147462D03*
X1369916Y154132D03*
X1379969Y176330D03*
X1370586Y176366D03*
X1370405Y186938D03*
X1369479Y208384D03*
X1370636Y227292D03*
X1369410Y224504D03*
X1375463Y1287048D03*
X1372463D03*
X1376666Y1402778D03*
X1376686Y1399758D03*
X1371866Y1737108D03*
X1384173Y1161549D03*
X1384089Y1153369D03*
X1386673Y1161520D03*
Y1153340D03*
X1384173Y1169599D03*
X1386673Y1169570D03*
X1391866Y1737108D03*
X1407613Y177159D03*
X1398770D03*
X1402258Y184263D03*
X1411101D03*
X1407913Y1161569D03*
X1410413Y1153369D03*
X1407913D03*
X1410613Y1161569D03*
X1407913Y1170069D03*
X1410613D03*
X1410819Y1287198D03*
X1407819D03*
X1399419D03*
X1402419D03*
X1411866Y1737108D03*
X1420222Y184263D03*
X1429250Y1623391D03*
X1419270Y1631000D03*
X1429382Y184263D03*
X1430000Y220018D03*
X1435387Y1161569D03*
X1435837Y1153369D03*
X1432887Y1161569D03*
X1433337Y1153369D03*
X1435387Y1170069D03*
X1432887D03*
X1437258Y1287198D03*
X1445106Y1287158D03*
X1440258Y1287198D03*
X1431829Y1412370D03*
X1443325Y1410068D03*
X1431717Y1424125D03*
X1441800Y1620300D03*
Y1632900D03*
X1431866Y1737108D03*
X1458911Y1161569D03*
Y1170069D03*
X1453366Y1287198D03*
X1458766D03*
X1461766D03*
X1450366D03*
X1474180Y1300407D03*
X1471180D03*
X1491661Y-27972D03*
X1491676Y-25457D03*
X1485383Y-26666D03*
X1491661Y-38001D03*
X1491676Y-35486D03*
Y-31612D03*
X1485383Y-36695D03*
X1491661Y-17943D03*
X1491676Y-15428D03*
Y-11554D03*
X1485383Y-16637D03*
X1491676Y-21583D03*
X1485383Y3421D03*
X1491661Y2115D03*
X1491676Y4630D03*
X1491661Y-7914D03*
X1491676Y-5399D03*
Y-1525D03*
X1485383Y-6608D03*
X1491676Y14659D03*
X1491661Y12144D03*
X1485383Y13450D03*
X1491676Y8504D03*
Y19033D03*
X1485383Y23979D03*
X1487058Y281456D03*
X1484958Y289656D03*
X1487658D03*
X1484758Y312356D03*
X1487458D03*
X1484858Y305956D03*
X1487558D03*
X1491840Y1300447D03*
X1479658Y1405397D03*
X1485301Y1409442D03*
X1485274Y1406911D03*
X1485380Y1412202D03*
X1479671Y1410411D03*
Y1412911D03*
Y1407911D03*
X1482201Y1409442D03*
X1482174Y1406911D03*
X1482280Y1412202D03*
X1491866Y1737108D03*
X1504602Y312867D03*
X1494840Y1300447D03*
X1511866Y1737108D03*
X1540937Y576522D03*
X1536527Y589012D03*
X1531866Y1737108D03*
X1547429Y28406D03*
X1554515D03*
Y40020D03*
X1547429D03*
X1547312Y579080D03*
X1551866Y1737108D03*
X1561602Y28406D03*
X1568688D03*
Y40020D03*
X1561602D03*
X1575775Y28406D03*
X1582862D03*
X1589948D03*
Y40020D03*
X1582862D03*
X1575775D03*
X1591866Y1737108D03*
X1597035Y28406D03*
X1604122D03*
Y40020D03*
X1597035D03*
X1623881Y117627D03*
X1619980Y615201D03*
X1614116Y1411169D03*
X1611866Y1737108D03*
X1625814Y28406D03*
X1632901D03*
X1639988D03*
X1625814Y40020D03*
X1632901D03*
X1639988D03*
X1637183Y1394411D03*
X1639683D03*
X1634683D03*
X1631866Y1737108D03*
X1654161Y28406D03*
X1647074D03*
Y40020D03*
X1654161D03*
X1652113Y527325D03*
X1652138Y524071D03*
X1651931Y540071D03*
Y536071D03*
X1649291Y556057D03*
X1649149Y607022D03*
X1653929Y604546D03*
X1649139Y604576D03*
X1653736Y607033D03*
X1649117Y602139D03*
X1653930Y602099D03*
X1651866Y1737108D03*
X1669948Y28406D03*
Y40020D03*
X1663376Y515531D03*
X1667376D03*
X1664997Y604762D03*
X1659458Y637149D03*
X1658085Y639511D03*
X1659458Y671149D03*
X1658085Y673511D03*
X1659458Y705149D03*
X1658085Y707511D03*
X1673226Y1394411D03*
X1671866Y1737108D03*
X1677035Y28406D03*
X1684122D03*
X1677035Y40020D03*
X1684122D03*
X1681612Y499290D03*
X1675926Y1394411D03*
X1678426D03*
X1691208Y28406D03*
X1698295D03*
X1705381D03*
X1697824Y39974D03*
X1691208Y40020D03*
X1693987Y230174D03*
Y233174D03*
X1703487Y232174D03*
X1699265Y525507D03*
X1699291Y537507D03*
X1699251Y529507D03*
X1699297Y549507D03*
X1705723Y1583821D03*
X1691866Y1737108D03*
X1711866D03*
X1738200Y193862D03*
X1731866Y1737108D03*
X1753388Y28360D03*
X1754398Y100307D03*
X1752200Y197762D03*
X1748500Y193862D03*
X1745500D03*
X1741200D03*
X1740831Y489362D03*
X1740886Y493960D03*
X1751866Y1737108D03*
X1760475Y28360D03*
X1764678Y122927D03*
X1766880Y234842D03*
Y231842D03*
X1758500Y231822D03*
Y234822D03*
X1755378Y233528D03*
X1782000Y128455D03*
X1771915Y128393D03*
X1782000Y125955D03*
Y123455D03*
X1771915Y125893D03*
Y123393D03*
X1783800Y231762D03*
Y234762D03*
X1775140Y234792D03*
Y231792D03*
X1779226Y275604D03*
X1783563Y273471D03*
X1786089D03*
X1771866Y1737108D03*
X1797663Y269571D03*
X1800189D03*
X1790563Y273471D03*
X1793089D03*
X1802763Y308671D03*
X1795763D03*
X1798289D03*
X1788763D03*
X1791289D03*
X1814349Y269634D03*
X1811823D03*
X1807249D03*
X1804723D03*
X1812349Y308734D03*
X1809823D03*
X1805289Y308671D03*
X1828777Y156520D03*
X1841257Y151402D03*
G54D19*
X20188Y1599396D03*
G54D66*
X1156378Y133866D03*
G54D70*
X1850331Y311946D03*
G54D25*
X60303Y20354D03*
X312921Y24291D03*
X505185Y41142D03*
X757803Y45079D03*
X922441Y237697D03*
X929331Y160413D03*
X1534712Y20354D03*
X1787330Y24291D03*
G54D41*
X337778Y854584D03*
X335924Y857789D03*
X334079Y880219D03*
X332228Y877014D03*
X335928D03*
X334078Y893036D03*
X335928Y896240D03*
X332229Y902649D03*
X332228Y915466D03*
X335928D03*
X332229Y921875D03*
Y941100D03*
X332228Y934692D03*
X335928D03*
X334079Y957122D03*
X335928Y953917D03*
X332228D03*
X332229Y973143D03*
X334079Y976347D03*
X338210Y996480D03*
X332661Y1006093D03*
X338211Y1002888D03*
X332661Y1025318D03*
Y1018910D03*
X338211Y1015705D03*
Y1022114D03*
X332661Y1044544D03*
X338211Y1041340D03*
X334511D03*
X338211Y1060565D03*
X336360Y1082995D03*
X338211Y1111834D03*
Y1105426D03*
Y1124651D03*
X336361Y1115039D03*
Y1127856D03*
X347028Y844971D03*
X345178Y848176D03*
X350727Y844971D03*
X347027Y851380D03*
X343327D03*
X354429D03*
X341478Y854584D03*
X339628Y857789D03*
X347029Y864197D03*
Y857789D03*
X348878Y854584D03*
X345179Y860993D03*
X343327Y857789D03*
X354429Y864197D03*
X350729D03*
X341479Y867401D03*
X348879D03*
X352579D03*
X354429Y877014D03*
X339629D03*
X341479Y873810D03*
X345179Y880219D03*
Y873810D03*
X343329Y877014D03*
X352579Y880219D03*
X350729Y877014D03*
X339629Y883423D03*
X347029D03*
X350729D03*
X352578Y899445D03*
X339629Y896240D03*
Y889832D03*
X348879Y886627D03*
X345179Y893036D03*
X343328Y896240D03*
X352578Y893036D03*
Y886627D03*
X345179Y899445D03*
X348878Y905853D03*
X352578D03*
X341479Y912262D03*
X341478Y905853D03*
X347029Y909057D03*
Y902649D03*
X345179Y912262D03*
X352578D03*
X339629Y915466D03*
X343329D03*
X348878Y925079D03*
X352578D03*
Y918670D03*
X341478Y925079D03*
X347029Y928283D03*
Y921875D03*
X345179Y918670D03*
X341479Y931488D03*
X345179D03*
X352578D03*
X341478Y944304D03*
X352578D03*
X347029Y941100D03*
X348878Y944304D03*
X347029Y947509D03*
X352578Y937896D03*
X339629Y934692D03*
X345179Y937896D03*
X343328Y934692D03*
X348878Y963530D03*
X347029Y960326D03*
X343328D03*
X343329Y966735D03*
X339629D03*
Y953917D03*
X343328D03*
X345179Y957122D03*
X352578D03*
X347029Y966735D03*
X352578Y963530D03*
X341479Y950713D03*
X345179D03*
X352578D03*
X354428Y973143D03*
X339629D03*
X345179Y976347D03*
Y969939D03*
X350729Y973143D03*
X347029Y979552D03*
X352579Y976347D03*
X352578Y969939D03*
X348878Y982756D03*
X352578D03*
X339629Y979552D03*
X343329Y973143D03*
X341911Y1009297D03*
Y1002888D03*
X347461Y999684D03*
X345611Y1009297D03*
X343761Y1006093D03*
X345611Y1002888D03*
X351162Y1006093D03*
X354861D03*
X353011Y1009297D03*
Y1002888D03*
X347461Y1012501D03*
X353011Y1028523D03*
Y1015705D03*
X341911Y1022114D03*
Y1015705D03*
X349311D03*
X347461Y1018910D03*
X345611Y1028523D03*
X343761Y1018910D03*
X345611Y1022114D03*
Y1015705D03*
X353011Y1022114D03*
X343761Y1031727D03*
X347461D03*
X353011Y1034931D03*
Y1047749D03*
X341911Y1041340D03*
X343761Y1038136D03*
X349311Y1034931D03*
X347461Y1038136D03*
X345611Y1041340D03*
X343761Y1044544D03*
X353011Y1041340D03*
X345611Y1047749D03*
X349311Y1054157D03*
X353011Y1060565D03*
Y1054157D03*
X343761Y1057361D03*
Y1050952D03*
X347461D03*
Y1057361D03*
X345611Y1060565D03*
X343761Y1063770D03*
X353011Y1073383D03*
X343761Y1076587D03*
Y1070178D03*
X340062Y1076587D03*
X347461D03*
Y1070178D03*
X349312Y1073383D03*
X345611Y1066974D03*
X353011D03*
X345611Y1079791D03*
X341911D03*
X353011D03*
Y1086200D03*
X349310Y1092609D03*
X347461Y1089404D03*
X345610Y1086200D03*
X343760Y1082995D03*
X340060D03*
X353011Y1092608D03*
X340061Y1095813D03*
X347461Y1108630D03*
X354861D03*
X353011Y1099017D03*
X340061Y1108630D03*
Y1102221D03*
X349311Y1099017D03*
X347461Y1102221D03*
X343761D03*
X340061Y1115039D03*
X349311Y1124651D03*
X349312Y1118243D03*
X345611D03*
X343761Y1115039D03*
X341911Y1124651D03*
X354861Y1115039D03*
X351161Y1121447D03*
Y1115039D03*
X345611Y1137469D03*
Y1131060D03*
X349311D03*
X343761Y1134264D03*
X353011Y1137469D03*
Y1131060D03*
X361829Y851380D03*
X358129D03*
X365529Y864197D03*
X361829D03*
X359979Y854584D03*
X358129Y864197D03*
X369229D03*
X367379Y854584D03*
X359979Y867401D03*
X367379D03*
X365529Y877014D03*
X361829D03*
X358129D03*
X369229D03*
X367379Y880219D03*
X356278Y886627D03*
X365529Y896240D03*
Y889832D03*
X361828Y896240D03*
X361829Y889832D03*
X359979Y893036D03*
X358128Y889832D03*
X369229Y896240D03*
Y889832D03*
X356278Y905853D03*
X365529Y909057D03*
Y902649D03*
X359978Y912262D03*
X358128Y909057D03*
X358129Y902649D03*
X371079Y912262D03*
X365529Y915466D03*
X361828D03*
X369229D03*
X356279Y925079D03*
X365529Y928283D03*
Y921875D03*
X358128Y928283D03*
X358129Y921875D03*
X371078Y918670D03*
X359978Y931488D03*
X371079D03*
X358128Y947509D03*
X358129Y941100D03*
X356279Y944304D03*
X365529Y947509D03*
Y934691D03*
X361828D03*
X369229D03*
X356279Y963530D03*
X358129Y960326D03*
X359979Y957122D03*
X358128Y966735D03*
X361829Y953917D03*
X359978Y950713D03*
X371078Y957122D03*
X371079Y950713D03*
X365529Y953917D03*
X367378Y963530D03*
X363679D03*
X365529Y960326D03*
X365528Y966735D03*
X369229Y953917D03*
X359979Y976347D03*
X358129Y979552D03*
X359978Y969939D03*
X361828Y973143D03*
X356279Y982756D03*
X371078Y976347D03*
X371079Y969939D03*
X369229Y973143D03*
X365529Y979552D03*
Y973143D03*
X365962Y999684D03*
Y1006093D03*
X362261D03*
X360411Y1009297D03*
X360412Y1002888D03*
X358562Y999684D03*
X371512Y1009297D03*
X365961Y1012501D03*
X358561D03*
X356712Y1015705D03*
X365962Y1025318D03*
Y1018910D03*
X364112Y1015705D03*
X360411Y1028523D03*
X362261Y1025318D03*
X360412Y1022114D03*
X358562Y1018910D03*
X369662Y1025318D03*
X367811Y1015705D03*
X371511Y1028523D03*
Y1022114D03*
X365962Y1031727D03*
X358561D03*
X356712Y1034931D03*
X365962Y1044544D03*
Y1038136D03*
X362261Y1044544D03*
X360412Y1041340D03*
X358562Y1038136D03*
X369662Y1044544D03*
X371511Y1041340D03*
X360411Y1047749D03*
X371511D03*
X356712Y1054157D03*
X365962Y1057361D03*
Y1050952D03*
X360412Y1060565D03*
X358562Y1057361D03*
X358561Y1050952D03*
X371511Y1060565D03*
X365962Y1063770D03*
X362261D03*
X369662D03*
X356712Y1073383D03*
X365962Y1070178D03*
X360411Y1066974D03*
X358561Y1070178D03*
X358562Y1076587D03*
X371512Y1066974D03*
X360412Y1079791D03*
X371511D03*
X365962Y1089404D03*
Y1082995D03*
X362261D03*
X360411Y1086200D03*
X358561Y1089404D03*
X356712Y1092608D03*
X369662Y1082995D03*
X371512Y1086200D03*
X365962Y1095813D03*
X358561D03*
X365962Y1102221D03*
X362262D03*
X360411Y1099017D03*
X356711Y1105426D03*
Y1099017D03*
X371512Y1105426D03*
Y1099017D03*
X364112Y1111834D03*
X356712D03*
X371512D03*
X364111Y1118243D03*
X362261Y1115039D03*
X360411Y1118243D03*
X356711D03*
X367811D03*
X371511D03*
X365962Y1127856D03*
X358561D03*
X365961Y1140973D03*
X364112Y1131060D03*
X360412D03*
X358561Y1140973D03*
X356712Y1131060D03*
X367811D03*
X371511D03*
X382179Y854584D03*
X380329Y864197D03*
X376629D03*
X374779Y854584D03*
X372929Y864197D03*
X384029D03*
X387729D03*
X382179Y867401D03*
X374779D03*
X382179Y880219D03*
X380329Y877014D03*
X376629D03*
X374779Y880219D03*
X372929Y877014D03*
X384029D03*
X387729D03*
X380329Y889832D03*
X378479Y893036D03*
X376629Y889832D03*
X372929D03*
X384029D03*
X387729Y896240D03*
Y889832D03*
X378478Y899445D03*
X385879D03*
X382179Y905853D03*
X378478Y912262D03*
Y905853D03*
X374778D03*
X372929Y909057D03*
X372928Y902649D03*
X385878Y912262D03*
X384028Y909057D03*
X384029Y902649D03*
X387728Y915466D03*
X382179Y925079D03*
X378478D03*
Y918670D03*
X374778Y925079D03*
X372929Y928283D03*
X372928Y921875D03*
X385879Y918670D03*
X384028Y928283D03*
X384029Y921875D03*
X385878Y931488D03*
X384029Y941100D03*
X384028Y947509D03*
X374778Y944304D03*
X372929Y947509D03*
X372928Y941100D03*
X382179Y944304D03*
X378478D03*
Y937896D03*
X385879D03*
X387728Y934691D03*
X387729Y953917D03*
X372928Y960326D03*
X374778Y963530D03*
X372929Y966735D03*
X382179Y963530D03*
X378478D03*
Y957122D03*
X384029Y960326D03*
X385879Y957122D03*
X384028Y966735D03*
X385878Y950713D03*
X378478D03*
X387728Y973143D03*
X376629D03*
X380328D03*
X378479Y976347D03*
X378478Y969939D03*
X385879Y976347D03*
X384029Y979552D03*
X385878Y969939D03*
X374778Y982756D03*
X382179D03*
X378478D03*
X372928Y979552D03*
X375210Y996480D03*
X373361Y999684D03*
X378911Y1009297D03*
Y1002888D03*
X386311Y1009297D03*
X386312Y1002888D03*
X384462Y999684D03*
X373362Y1012501D03*
X384461D03*
X382612Y1015705D03*
X378911Y1028523D03*
Y1022114D03*
Y1015705D03*
X375211D03*
X373361Y1018910D03*
X386311Y1028523D03*
X386312Y1022114D03*
X384462Y1018910D03*
X373362Y1031727D03*
X384461D03*
X382612Y1034931D03*
X378911Y1041340D03*
Y1034931D03*
X375211D03*
X373361Y1038136D03*
X386312Y1041340D03*
X384462Y1038136D03*
X378911Y1047749D03*
X386311D03*
X382612Y1054157D03*
X378911D03*
X375211D03*
X373361Y1057361D03*
X373362Y1050952D03*
X386312Y1060565D03*
X384462Y1057361D03*
X384461Y1050952D03*
X382612Y1073383D03*
X378911D03*
Y1066974D03*
X375211Y1073383D03*
X373361Y1076587D03*
X373362Y1070178D03*
X386311Y1066974D03*
X384462Y1076587D03*
X384461Y1070178D03*
X378911Y1079791D03*
X386311D03*
X382611Y1092608D03*
X378911D03*
Y1086200D03*
X375211Y1092608D03*
X373362Y1089404D03*
X386311Y1086200D03*
X384461Y1089404D03*
X373362Y1095813D03*
X384462D03*
X380762Y1108630D03*
X378911Y1099017D03*
X377062Y1102221D03*
X373361Y1108630D03*
Y1102221D03*
X386312Y1099017D03*
X384462Y1102221D03*
X382611Y1118243D03*
X378911D03*
X377061Y1115039D03*
X375211Y1118243D03*
X373361Y1115039D03*
X386311Y1118243D03*
X384461Y1115039D03*
X380761Y1127856D03*
X373361D03*
X382611Y1131060D03*
X380761Y1140973D03*
X378911Y1131060D03*
X375211D03*
X373361Y1140973D03*
X386311Y1131060D03*
X396979Y841467D03*
X398829Y851380D03*
X395129D03*
X391429D03*
X402529D03*
X398829Y864197D03*
X396979Y854584D03*
X395129Y864197D03*
X391429D03*
X389579Y854584D03*
X402529Y864197D03*
X396979Y867401D03*
X389579D03*
X398829Y877014D03*
X396979Y880219D03*
X395129Y877014D03*
X391429D03*
X389579Y880219D03*
X402529Y877014D03*
X398829Y889832D03*
X395129Y896240D03*
Y889832D03*
X391428Y896240D03*
X391429Y889832D03*
X389579Y893036D03*
X402529Y889832D03*
X398829Y909057D03*
X398828Y902649D03*
X396979Y912262D03*
X391429Y909057D03*
Y902649D03*
X395129Y915466D03*
X391429D03*
X398829Y928283D03*
X398828Y921875D03*
X396978Y918670D03*
X391429Y928283D03*
Y921875D03*
X400678Y925079D03*
X396979Y931488D03*
X398828Y941100D03*
X395129Y934691D03*
X391429Y941100D03*
Y934691D03*
X400678Y937896D03*
X398829Y947509D03*
X391429D03*
X398828Y960326D03*
X396978Y957122D03*
X396979Y950713D03*
X395129Y953917D03*
X391429Y960326D03*
Y953917D03*
X400678Y957122D03*
X398829Y966735D03*
X391429D03*
X400678Y963530D03*
X398828Y979552D03*
X396978Y976347D03*
X396979Y969939D03*
X395129Y973143D03*
X391429Y979552D03*
Y973143D03*
X400678Y982756D03*
Y969939D03*
X397412Y1009297D03*
X397411Y1002888D03*
X395562Y1006093D03*
X391862D03*
Y999684D03*
X388161Y1006093D03*
X401111Y1002888D03*
X399262Y1012501D03*
X391861D03*
X399261Y1018910D03*
X397411Y1028523D03*
Y1022114D03*
X395562Y1025318D03*
X393711Y1015705D03*
X391862Y1025318D03*
Y1018910D03*
X390012Y1015705D03*
X388161Y1025318D03*
X399262Y1031727D03*
X391862D03*
X399261Y1038136D03*
X397411Y1041340D03*
X395562Y1044544D03*
X391862D03*
Y1038136D03*
X388161Y1044544D03*
X397411Y1047749D03*
X399261Y1057361D03*
X399262Y1050952D03*
X397411Y1060565D03*
X391862Y1057361D03*
Y1050952D03*
X395562Y1063770D03*
X391862D03*
X388161D03*
X399261Y1076587D03*
X399262Y1070178D03*
X397412Y1066974D03*
X391862Y1076587D03*
Y1070178D03*
X401111Y1073383D03*
X397411Y1079791D03*
X401111D03*
X399262Y1089404D03*
X397412Y1086200D03*
X395562Y1082995D03*
X391862Y1089404D03*
Y1082995D03*
X388161D03*
X401112Y1092608D03*
X401111Y1086200D03*
X399261Y1095813D03*
X391862D03*
X402962D03*
X399262Y1102221D03*
X397412Y1099017D03*
X395562Y1102221D03*
X390011Y1105426D03*
X388162Y1108630D03*
Y1102221D03*
X401111Y1105426D03*
X397411Y1111834D03*
X390011D03*
X397411Y1118243D03*
X395561Y1115039D03*
X393711Y1118243D03*
X390011D03*
X388161Y1115039D03*
X401111Y1118243D03*
X395561Y1127856D03*
X388161D03*
X402961D03*
X397411Y1131060D03*
X395561Y1140973D03*
X393711Y1131060D03*
X390011D03*
X388161Y1140973D03*
X402961D03*
X401111Y1131060D03*
X419179Y841467D03*
X404379D03*
X411779D03*
X413629Y851380D03*
X409929D03*
X406229D03*
X417329D03*
X404379Y854584D03*
X413629Y864197D03*
X411779Y854584D03*
X409929Y864197D03*
X406229D03*
X419179Y854584D03*
X417329Y864197D03*
X404379Y867401D03*
X411779D03*
X419179D03*
X404379Y880219D03*
X413629Y877014D03*
X411779Y880219D03*
X409929Y877014D03*
Y870606D03*
X406229Y877014D03*
X419179Y880219D03*
X417329Y877014D03*
X413629Y889832D03*
X411779Y893036D03*
X409929Y889832D03*
X408079Y893036D03*
X406229Y889832D03*
X419179Y893036D03*
X417329Y889832D03*
X413629Y902649D03*
X409929Y909057D03*
Y902649D03*
X404378Y912262D03*
Y905853D03*
X419178Y912262D03*
X419179Y905853D03*
X417329Y902649D03*
X409929Y915466D03*
Y921875D03*
X404378Y918670D03*
X418229Y926896D03*
X419178Y918670D03*
X405048Y930812D03*
X405145Y946239D03*
Y948539D03*
X414093Y942098D03*
X405048Y938046D03*
Y935746D03*
X416393Y942098D03*
X418693D03*
X405122Y965896D03*
Y963596D03*
X414365Y971140D03*
X416755D03*
X404861Y981269D03*
Y978969D03*
Y986421D03*
X405101Y992971D03*
Y995271D03*
X404861Y988721D03*
X405227Y1007156D03*
X405231Y1004848D03*
X417575Y1000060D03*
X415185D03*
X404986Y1022427D03*
X404998Y1026821D03*
X408325Y1031971D03*
Y1034271D03*
X408511Y1041340D03*
X417762Y1044544D03*
X412211Y1047749D03*
X404811D03*
X415911Y1060565D03*
Y1054157D03*
X412211Y1060565D03*
X410361Y1050952D03*
X408511Y1054157D03*
X404811Y1060565D03*
X417761Y1050952D03*
X415911Y1066974D03*
X410362Y1076587D03*
Y1070178D03*
X406661Y1076587D03*
X404811Y1066974D03*
X419611Y1073383D03*
X412211Y1079791D03*
X404811D03*
X415911Y1092608D03*
X415912Y1086200D03*
X412211Y1092608D03*
X408511Y1086200D03*
X417761Y1089404D03*
Y1082995D03*
X410362Y1095813D03*
X406662D03*
X415912Y1099017D03*
X414062Y1108630D03*
X412211Y1099017D03*
X410362Y1102221D03*
X406661Y1108630D03*
Y1102221D03*
X404812Y1105426D03*
X417762Y1102221D03*
X404812Y1111834D03*
X415911Y1118243D03*
X414061Y1121447D03*
X412211Y1124651D03*
Y1118243D03*
X410361Y1115039D03*
X408511Y1118243D03*
X406661Y1115039D03*
X404811Y1118243D03*
X417761Y1115039D03*
X410361Y1127856D03*
X414062Y1134264D03*
X412212Y1131060D03*
X410361Y1140973D03*
X408511Y1131060D03*
X404811D03*
X432128Y844671D03*
X426579Y841467D03*
X432129Y851380D03*
X428429D03*
X424729D03*
X421029D03*
X432129Y864197D03*
X428429D03*
X426579Y854584D03*
X424729Y864197D03*
X421029D03*
X433979Y854584D03*
X426579Y867401D03*
X433979D03*
X432129Y877014D03*
X428429D03*
X426579Y880219D03*
X424729Y877014D03*
X421029D03*
X433979Y880219D03*
X432129Y889832D03*
X428429D03*
X426579Y893036D03*
X424729Y889832D03*
X421029D03*
X433979Y893036D03*
X424729Y902649D03*
X432129D03*
X428429Y909057D03*
Y902649D03*
X421029D03*
X428429Y915466D03*
X433980Y925079D03*
Y931487D03*
X426875Y947199D03*
Y949499D03*
X427875Y936470D03*
X426905Y965935D03*
Y963635D03*
Y980336D03*
Y978036D03*
Y994722D03*
Y992422D03*
Y1006875D03*
Y1009175D03*
Y1021963D03*
Y1019663D03*
X428862Y1044544D03*
X430712Y1047749D03*
X423311D03*
X425162Y1057361D03*
X432561Y1050952D03*
X434411Y1060565D03*
Y1054157D03*
X421462Y1063770D03*
X430711Y1073383D03*
X427011D03*
Y1066974D03*
X425162Y1076587D03*
X423311Y1066974D03*
X432561Y1076587D03*
X434411Y1073383D03*
Y1066974D03*
X427012Y1079791D03*
X434411D03*
X428861Y1082995D03*
X425162Y1089404D03*
X421462Y1082995D03*
X432561Y1089404D03*
Y1082995D03*
X434411Y1086200D03*
X428861Y1095813D03*
X421462D03*
X432561D03*
X427011Y1099017D03*
X425161Y1102221D03*
X423311Y1105426D03*
X421462Y1108630D03*
X434411Y1105426D03*
X423311Y1111834D03*
X434411D03*
X423311Y1124651D03*
Y1118243D03*
X421462Y1115039D03*
X434411Y1124651D03*
Y1118243D03*
X423312Y1137469D03*
X423311Y1131060D03*
X434412Y1137769D03*
X434411Y1131060D03*
X452478Y848176D03*
X445078D03*
X441378D03*
X439529Y844671D03*
X446929Y851380D03*
X443228D03*
X439529D03*
X448779Y854584D03*
X446929Y864197D03*
X443229D03*
X441379Y854584D03*
X439529Y864197D03*
X439528Y857789D03*
X437680Y860992D03*
X450629Y864197D03*
X448779Y867401D03*
X441379D03*
X448779Y880219D03*
X446929Y877014D03*
X443229D03*
X441379Y880219D03*
X439529Y877014D03*
X448779Y893036D03*
X446929Y889832D03*
X443229D03*
X441379Y893036D03*
X439529Y896240D03*
Y889832D03*
X437678Y886627D03*
X450629Y889832D03*
X437679Y899445D03*
X446929Y909057D03*
Y902649D03*
X443229D03*
X439528D03*
X437679Y905853D03*
X450629Y902649D03*
X446929Y915466D03*
X446930Y928283D03*
X441379Y925079D03*
Y931487D03*
X446929Y921875D03*
X437678Y918670D03*
X448779Y937897D03*
X447360Y1038136D03*
X452911Y1041340D03*
X451061Y1044544D03*
X449211Y1047749D03*
X447361Y1057361D03*
Y1050952D03*
X452911Y1060565D03*
X447361Y1063770D03*
Y1076587D03*
Y1070178D03*
X449211Y1073383D03*
X452911Y1079791D03*
X449211D03*
X447361Y1082995D03*
X452911Y1092608D03*
X451062Y1089404D03*
X449212Y1086200D03*
X451062Y1095813D03*
X447361Y1108630D03*
Y1102221D03*
X452911Y1099017D03*
X447361Y1121447D03*
Y1115039D03*
Y1127856D03*
Y1134264D03*
X461729Y851380D03*
X458029D03*
X454328D03*
X456179Y841467D03*
X463579D03*
X469129Y851380D03*
X465429D03*
X456179Y854584D03*
X463579D03*
X461729Y864197D03*
X458029D03*
X454329D03*
X469129D03*
X465429D03*
X456179Y867401D03*
X463579D03*
X461729Y877014D03*
X458029D03*
X456179Y880219D03*
X454329Y877014D03*
X463579Y880219D03*
X469129Y877014D03*
X465429D03*
X461729Y889832D03*
X458029D03*
X456179Y893036D03*
X454329Y889832D03*
X463579Y893036D03*
X469129Y896240D03*
Y889832D03*
X465429D03*
X461729Y902649D03*
X458029D03*
X456178Y905853D03*
X454329Y902649D03*
X465429D03*
Y909057D03*
Y915466D03*
X454103Y931359D03*
Y933659D03*
X456178Y918670D03*
X454434Y1022186D03*
Y1019886D03*
X460311Y1041340D03*
X467372Y1036874D03*
X465861Y1044544D03*
X456611Y1047749D03*
X464011D03*
X456611Y1054157D03*
X462162Y1050952D03*
X454761Y1076587D03*
X462162Y1070178D03*
X456612Y1079791D03*
X467711D03*
X458461Y1082995D03*
X456611Y1086200D03*
X460311Y1092608D03*
X464011Y1086200D03*
X467712D03*
Y1092608D03*
X460312Y1105426D03*
X458462Y1102221D03*
X456611Y1099017D03*
X464012Y1105426D03*
Y1099017D03*
X462162Y1108630D03*
X465861D03*
Y1102221D03*
X464012Y1111834D03*
X467711Y1105426D03*
Y1111834D03*
X458462Y1121447D03*
Y1115039D03*
X467712Y1124651D03*
X467711Y1118243D03*
X465862Y1121447D03*
Y1115039D03*
X458462Y1127856D03*
Y1134264D03*
X478379Y841467D03*
X470979D03*
X476529Y851380D03*
X480229D03*
X472829D03*
X483929D03*
X480229Y864197D03*
X478379Y854584D03*
X476529Y864197D03*
X470979Y854584D03*
X472829Y864197D03*
X483929D03*
X478379Y867401D03*
X470979D03*
X480229Y877014D03*
X478379Y880219D03*
X476529Y877014D03*
X472829D03*
X472828Y870606D03*
X470979Y880219D03*
Y873810D03*
X483929Y877014D03*
X480228Y896240D03*
X480229Y889832D03*
X478379Y893036D03*
X470979D03*
X476529Y889832D03*
X472829D03*
X483929D03*
X482078Y899445D03*
X474678Y905853D03*
X483929Y909057D03*
X482079Y912262D03*
X483928Y902649D03*
X476285Y930126D03*
X476528Y921875D03*
X474678Y918670D03*
X483929Y928283D03*
X482078Y918670D03*
X483928Y921875D03*
X482079Y931488D03*
X476285Y934726D03*
X476180Y945355D03*
Y947655D03*
X478378Y944304D03*
X480229Y934691D03*
X483928Y941100D03*
X482079Y944304D03*
X482078Y937896D03*
X483928Y947509D03*
X476285Y962326D03*
Y960026D03*
Y964626D03*
X483928Y960326D03*
X482078Y957122D03*
X482079Y950713D03*
X483929Y966735D03*
X476285Y966926D03*
X476192Y977670D03*
X476335Y980737D03*
X482079Y969939D03*
X483928Y979552D03*
X482078Y976347D03*
X476285Y996826D03*
Y994526D03*
Y989926D03*
Y987626D03*
X476295Y1010500D03*
X476285Y1012926D03*
Y1006026D03*
Y1003726D03*
X484361Y999684D03*
X482512Y1009297D03*
X482511Y1002888D03*
X484362Y1012501D03*
X476275Y1022636D03*
X476285Y1017526D03*
X482511Y1028523D03*
Y1022114D03*
X484361Y1018910D03*
Y1031727D03*
X471282Y1036526D03*
X473507Y1035928D03*
X475111Y1041340D03*
X482511D03*
X482512Y1034931D03*
X484361Y1038136D03*
X471411Y1047749D03*
X482511D03*
X480662Y1050952D03*
X471411Y1054157D03*
X482511Y1060565D03*
X484362Y1050952D03*
Y1070178D03*
X482511Y1079791D03*
X480662Y1082995D03*
X476962Y1089404D03*
X473262Y1082995D03*
X469561Y1089404D03*
X482512Y1086200D03*
X484362Y1089404D03*
X480661Y1095813D03*
X469562D03*
X484362D03*
X480662Y1108630D03*
X478811Y1099017D03*
X473262Y1108630D03*
X476962Y1102221D03*
X475112Y1099017D03*
X471411D03*
X469562Y1102221D03*
X482511Y1105426D03*
Y1111834D03*
X484362Y1108630D03*
X475111Y1111834D03*
X471411D03*
X478811Y1105426D03*
X469562Y1108630D03*
X473262Y1102221D03*
X482511Y1099017D03*
X478811Y1111834D03*
X476962Y1108630D03*
X471411Y1105426D03*
X475111D03*
X484362Y1102221D03*
X480661Y1115039D03*
X478811Y1118243D03*
X476961Y1115039D03*
X475111Y1118243D03*
X471411D03*
X469561Y1115039D03*
X482511Y1118243D03*
X476961Y1127856D03*
X469562D03*
X484361D03*
X484362Y1115039D03*
X473262D03*
X478811Y1131060D03*
X476961Y1140973D03*
X475111Y1131060D03*
X471412Y1137469D03*
Y1131060D03*
X469561Y1140973D03*
X473261Y1134264D03*
X482511Y1131060D03*
X484361Y1140973D03*
X493179Y841467D03*
X485779D03*
X500579D03*
X495029Y851380D03*
X491329D03*
X487629D03*
X498729D03*
X495029Y864197D03*
X493179Y854584D03*
X491329Y864197D03*
X487629D03*
X485779Y854584D03*
X498729Y864197D03*
X500579Y854584D03*
X493179Y867401D03*
X485779D03*
X500579D03*
X495029Y877014D03*
X493179Y880219D03*
X491329Y877014D03*
X487629D03*
X485779Y880219D03*
X500579D03*
X498729Y877014D03*
X489479Y893036D03*
X495029Y889832D03*
X491329D03*
X487629D03*
X498729D03*
X500579Y893036D03*
X498729Y896240D03*
X496879Y899445D03*
X489478D03*
X496878Y912262D03*
X495029Y909057D03*
X489478Y905853D03*
X495029Y902649D03*
X493179Y905853D03*
X485778D03*
X498728Y915466D03*
X495028Y928283D03*
X493179Y925079D03*
X489478D03*
Y918670D03*
X485778Y925079D03*
X496879Y918670D03*
X495029Y921875D03*
X496878Y931488D03*
X489478D03*
X496879Y937896D03*
X495029Y941100D03*
X493179Y944304D03*
X489478D03*
Y937896D03*
X485778Y944304D03*
X498729Y934691D03*
X495028Y947509D03*
X496879Y957122D03*
X495029Y960326D03*
X489478Y957122D03*
Y950713D03*
X496878D03*
X498729Y953917D03*
X495028Y966735D03*
X493179Y963530D03*
X485778D03*
X489478D03*
X500579D03*
X496879Y976347D03*
X496878Y969939D03*
X489478Y976347D03*
Y969939D03*
X495029Y979552D03*
X498728Y973143D03*
X493179Y982756D03*
X489478D03*
X485778D03*
X497311Y1009297D03*
X497312Y1002888D03*
X495462Y999684D03*
X489911Y1009297D03*
X489912Y1002888D03*
X491761Y1006093D03*
X488062D03*
X499161D03*
X495461Y1012501D03*
X497311Y1028523D03*
X489911D03*
Y1022114D03*
Y1015705D03*
X497311Y1022114D03*
X495462Y1018910D03*
X493612Y1015705D03*
X486211D03*
X501012D03*
X499161Y1025318D03*
X495461Y1031727D03*
X497312Y1041340D03*
X489911D03*
Y1034931D03*
X495462Y1038136D03*
X493612Y1034931D03*
X486211D03*
X499161Y1044544D03*
X489911Y1047749D03*
X497311D03*
Y1060565D03*
X489911D03*
Y1054157D03*
X495461Y1050952D03*
X493611Y1054157D03*
X486211D03*
X489911Y1066974D03*
X495461Y1070178D03*
X489911Y1073383D03*
X497312Y1079791D03*
X489911D03*
X497311Y1086200D03*
X493612Y1092608D03*
X489911D03*
Y1086200D03*
X486211Y1092608D03*
X495461Y1089404D03*
X499161Y1082995D03*
X495462Y1095813D03*
X499162D03*
X491762D03*
X497312Y1105426D03*
X493611D03*
X491762Y1102221D03*
X488061D03*
X486211Y1105426D03*
X486212Y1099017D03*
X499161Y1108630D03*
Y1102221D03*
X497312Y1111834D03*
X489911D03*
Y1099017D03*
X495462Y1102221D03*
X501011Y1099017D03*
X493611D03*
X497311D03*
X489911Y1105426D03*
X486211Y1111834D03*
X491762Y1108630D03*
X488062D03*
X497311Y1118243D03*
X495462Y1121447D03*
X493612Y1118243D03*
X489911D03*
X486211D03*
X501011D03*
X499161Y1115039D03*
X491761Y1127856D03*
X499161D03*
X491762Y1115039D03*
X495462D03*
X497311Y1131060D03*
X493611D03*
X489911D03*
X486211D03*
X491761Y1140973D03*
X501011Y1131060D03*
X499161Y1140973D03*
X507979Y841467D03*
X515379D03*
X506129Y851380D03*
X502429D03*
X513529D03*
X509829D03*
X517229D03*
X513529Y864197D03*
X509829D03*
X506129D03*
X502429D03*
X507979Y854584D03*
X515379D03*
X517229Y864197D03*
X507979Y867401D03*
X515379D03*
X509829Y877014D03*
X507979Y880219D03*
X502429Y877014D03*
X513529D03*
X506129D03*
X515379Y880219D03*
X517229Y877014D03*
X506129Y889832D03*
X502428Y896240D03*
X502429Y889832D03*
X513529D03*
X509829D03*
X506128Y896240D03*
X504279Y893036D03*
X515379D03*
X517229Y889832D03*
X507978Y899445D03*
X515378D03*
X511678Y905853D03*
X509829Y909057D03*
X507979Y912262D03*
X502429Y909057D03*
Y902649D03*
X509828D03*
X515378Y912262D03*
Y905853D03*
X502429Y915466D03*
X506129D03*
X511678Y925079D03*
X509829Y928283D03*
X502429D03*
Y921875D03*
X509828D03*
X507978Y918670D03*
X515378Y925079D03*
Y918670D03*
X507979Y931488D03*
X515378D03*
X511678Y944304D03*
X509828Y941100D03*
X506129Y934691D03*
X502429Y941100D03*
Y934691D03*
X515378Y944304D03*
Y937896D03*
X502429Y947509D03*
X509828Y960326D03*
X507978Y957122D03*
X506129Y953917D03*
X502429Y960326D03*
Y953917D03*
X507979Y950713D03*
X515378Y957122D03*
Y950713D03*
X509829Y966735D03*
X502428D03*
X511678Y963530D03*
X504278D03*
X515378D03*
X507978Y976347D03*
X507979Y969939D03*
X502429Y979552D03*
Y973143D03*
X513529D03*
X509828Y979552D03*
X506129Y973143D03*
X515379Y976347D03*
X515378Y969939D03*
X517228Y973143D03*
X511678Y982756D03*
X515378D03*
X510261Y999684D03*
X508411Y1002888D03*
X506562Y1006093D03*
X502862Y999684D03*
X502861Y1012501D03*
X508412Y1009297D03*
X510262Y1012501D03*
X515811Y1009297D03*
Y1002888D03*
X508411Y1028523D03*
X502862Y1025318D03*
Y1018910D03*
X510261D03*
X508411Y1022114D03*
X506562Y1025318D03*
X504711Y1015705D03*
X515811Y1028523D03*
Y1022114D03*
X510262Y1031727D03*
X502862D03*
X515811Y1015705D03*
X512111D03*
X502862Y1044544D03*
Y1038136D03*
X512111Y1034931D03*
X510261Y1038136D03*
X508411Y1041340D03*
X506562Y1044544D03*
X515811Y1034931D03*
Y1041340D03*
X508411Y1047749D03*
X515811D03*
X508411Y1060565D03*
X502862Y1057361D03*
Y1050952D03*
X512111Y1054157D03*
X510262Y1050952D03*
X515811Y1054157D03*
Y1060565D03*
X502862Y1063770D03*
X510262Y1070178D03*
X502862Y1076587D03*
Y1070178D03*
X515811Y1073383D03*
Y1079791D03*
X512112Y1092608D03*
X510262Y1089404D03*
X508412Y1086200D03*
X506562Y1082995D03*
X502862Y1089404D03*
Y1082995D03*
X515812Y1092608D03*
X513961Y1095813D03*
X502862D03*
X517662D03*
X513962Y1108630D03*
Y1102221D03*
X512112Y1099017D03*
X508411D03*
X506562Y1108630D03*
X504711Y1099017D03*
X502862Y1102221D03*
X515811Y1105426D03*
Y1111834D03*
X517662Y1108630D03*
X513961Y1115039D03*
X512111Y1118243D03*
X508411D03*
X504711D03*
X510261Y1115039D03*
X515811Y1118243D03*
X513961Y1127856D03*
X506561D03*
X517662Y1115039D03*
X513961Y1140973D03*
X512111Y1131060D03*
X508411D03*
X504711D03*
X506561Y1140973D03*
X515811Y1131060D03*
X528329Y844671D03*
X522779Y841467D03*
X528329Y851380D03*
X524629D03*
X520929D03*
X532029D03*
X528329Y864197D03*
X524629D03*
X520929D03*
X530179Y860993D03*
Y854584D03*
X522779D03*
X532028Y857789D03*
X533879Y860993D03*
X530178Y867401D03*
X522779D03*
X533879D03*
X528329Y877014D03*
X522779Y880219D03*
X520929Y877014D03*
X530179Y880219D03*
X524629Y877014D03*
X532029D03*
X533879Y880219D03*
Y873810D03*
X532028Y883423D03*
X528329Y896240D03*
Y889832D03*
X524629D03*
X526479Y893036D03*
X524629Y896240D03*
X520929Y889832D03*
X532029D03*
Y896240D03*
X533879Y893036D03*
X522779Y899445D03*
X533879D03*
X528329Y902649D03*
X522778Y912262D03*
X520928Y909057D03*
X519079Y905853D03*
X520929Y902649D03*
X528329Y915466D03*
X524628D03*
X532029D03*
X528329Y909057D03*
X533879Y912262D03*
X528329Y921875D03*
X520928Y928283D03*
X519079Y925079D03*
X522779Y918670D03*
X520929Y921875D03*
X522778Y931488D03*
X528329Y928283D03*
X533879Y918670D03*
X533878Y931488D03*
X528329Y941100D03*
Y934691D03*
X524628D03*
X522779Y937896D03*
X520929Y941100D03*
X519079Y944304D03*
X520928Y947509D03*
X532029Y934691D03*
X533879Y937896D03*
X528329Y947509D03*
Y960326D03*
Y953917D03*
X524629D03*
X522779Y957122D03*
X520929Y960326D03*
X522778Y950713D03*
X520928Y966735D03*
X526479Y963530D03*
X519079D03*
X533879Y957122D03*
X532029Y953917D03*
X533879Y950713D03*
X530178Y963530D03*
X528329Y966735D03*
Y979552D03*
Y973143D03*
X522779Y976347D03*
X522778Y969939D03*
X524628Y973143D03*
X520929Y979552D03*
X533879Y976347D03*
X519079Y982756D03*
X533901Y980606D03*
X533879Y969939D03*
X532029Y973143D03*
X521361Y1012501D03*
Y999684D03*
X528762Y1006093D03*
Y999684D03*
X525061Y1006093D03*
X523211Y1009297D03*
X523212Y1002888D03*
X534311Y1009297D03*
Y1002888D03*
X532461Y1006093D03*
X528761Y1012501D03*
X528762Y1025318D03*
X523211Y1028523D03*
X525061Y1025318D03*
X528762Y1031727D03*
X521361D03*
X519512Y1015705D03*
X521362Y1018910D03*
X523211Y1022114D03*
X526912Y1015705D03*
X528762Y1018910D03*
X530611Y1015705D03*
X534311Y1028523D03*
X534310Y1022114D03*
X532461Y1025318D03*
X528762Y1044544D03*
X525061D03*
X523212Y1041340D03*
X521362Y1038136D03*
X519512Y1034931D03*
X532462Y1044544D03*
X523211Y1047749D03*
X528762Y1038136D03*
X534311Y1041340D03*
Y1047749D03*
X528762Y1057361D03*
Y1050952D03*
X523212Y1060565D03*
X521361Y1050952D03*
X519512Y1054157D03*
X528762Y1063770D03*
X534311Y1060565D03*
X528762Y1076587D03*
Y1070178D03*
X521361D03*
X523212Y1079791D03*
X534311D03*
X523211Y1086200D03*
X521361Y1089404D03*
X519511Y1092608D03*
X528762Y1089404D03*
Y1082995D03*
X525061D03*
X532462Y1082996D03*
X534311Y1086200D03*
X528761Y1095813D03*
X526911Y1105426D03*
X521361Y1102221D03*
X519511Y1105426D03*
X519512Y1099017D03*
X532461Y1108630D03*
X530612Y1111834D03*
X523211D03*
X526911Y1099017D03*
X534311D03*
X532460Y1102221D03*
X521362Y1108630D03*
X525062D03*
X534311Y1111834D03*
X523211Y1105426D03*
X534311D03*
X528762Y1108630D03*
X519511Y1111834D03*
X526911D03*
X530611Y1124651D03*
Y1118243D03*
X528762Y1121447D03*
X523211Y1118243D03*
X521361Y1115039D03*
X519511Y1118243D03*
X532461Y1115039D03*
X528761Y1127856D03*
X521361D03*
X525062Y1115039D03*
X528762D03*
X530612Y1137469D03*
Y1131060D03*
X526912D03*
X523211D03*
X519511D03*
X528761Y1134264D03*
X521361Y1140973D03*
X534311Y1131060D03*
X537580Y848176D03*
X535729Y844671D03*
Y851380D03*
X544979Y860993D03*
Y854584D03*
X539428Y864197D03*
X537579Y854584D03*
Y860993D03*
X544979Y867401D03*
X541279D03*
X537579D03*
X546829Y870606D03*
X541279Y873810D03*
X535729Y870606D03*
Y883423D03*
X541279Y880219D03*
X546829Y883423D03*
X537579Y893036D03*
X541279Y886627D03*
X544979D03*
X537579D03*
X535729Y889832D03*
X550529D03*
X537579Y899445D03*
X548679Y912262D03*
X537579D03*
X539429Y909057D03*
X537579Y905853D03*
X535729Y909057D03*
X543129D03*
X535729Y902649D03*
X548679Y905853D03*
X537579Y918670D03*
X535729Y921875D03*
X537578Y931488D03*
X548678D03*
X537579Y937896D03*
X535729Y941100D03*
X539429Y947509D03*
X535729D03*
X537579Y957122D03*
Y950713D03*
X535729Y960326D03*
Y966735D03*
X537579Y963530D03*
X539429Y979552D03*
X537579Y982756D03*
X541279Y969939D03*
X539429Y973143D03*
X535729D03*
X539862Y1006092D03*
X539861Y999684D03*
X536161D03*
Y1006093D03*
X543563Y1006092D03*
X549254Y1000648D03*
X536161Y1012501D03*
Y1025318D03*
X539861Y1018910D03*
X541712Y1015705D03*
X545412D03*
X538012D03*
X536161Y1018910D03*
X549112Y1015705D03*
X536161Y1031727D03*
X545412Y1034931D03*
X539862Y1044544D03*
X539861Y1038136D03*
X541711Y1034931D03*
X538011D03*
X536161Y1038136D03*
X549112Y1034931D03*
X541711Y1054157D03*
X538011D03*
X545411D03*
X538011Y1060565D03*
X536161Y1050952D03*
X538011Y1066974D03*
X539861Y1076587D03*
X536162Y1082996D03*
X538011Y1092608D03*
X536161Y1089404D03*
X545411Y1092608D03*
X547262Y1082996D03*
X543561Y1095813D03*
X536161D03*
X547261D03*
X545412Y1105426D03*
X541711D03*
X539861Y1108630D03*
Y1102221D03*
X536161D03*
X541711Y1111834D03*
X545411D03*
X538011Y1105426D03*
X536161Y1108630D03*
X538011Y1111834D03*
X543561Y1108630D03*
X545411Y1124651D03*
Y1118243D03*
X543562Y1115039D03*
X539862D03*
X538011Y1124651D03*
X536161Y1115039D03*
X541711Y1131060D03*
X536162Y1134264D03*
X551429Y979057D03*
X550701Y972608D03*
X550961Y1031727D03*
X560571Y1614292D03*
X580431Y1602380D03*
X688999Y1051247D03*
X748399D03*
X1293802Y162999D03*
X1297007Y161149D03*
X1297012Y168549D03*
X1297007Y164849D03*
X1293802Y183349D03*
Y187049D03*
Y190749D03*
Y198149D03*
Y194449D03*
Y201849D03*
X1296999Y209249D03*
X1300774Y155288D03*
X1309832Y161149D03*
X1303417D03*
X1309832Y168549D03*
X1303417D03*
X1303422Y172249D03*
X1313033Y174099D03*
X1306622D03*
X1300207Y185199D03*
X1306617Y181499D03*
X1300207Y192599D03*
X1309817Y187049D03*
X1306617Y192599D03*
X1313023Y199999D03*
X1306617D03*
X1300207D03*
X1303407Y201849D03*
X1303422Y209249D03*
X1313032Y214799D03*
X1306622Y218499D03*
X1303417Y212949D03*
Y216649D03*
X1300207Y214799D03*
X1301151Y225450D03*
X1309828Y224049D03*
X1306622Y222199D03*
X1309100Y236477D03*
X1313920Y854584D03*
X1312266Y857972D03*
X1312070Y877014D03*
X1310221Y880219D03*
X1308370Y877014D03*
X1312070Y896240D03*
X1310220Y893036D03*
X1308371Y902649D03*
X1312070Y915466D03*
X1308370D03*
X1308371Y921875D03*
X1312070Y934692D03*
X1308371Y941100D03*
X1308370Y934692D03*
X1312070Y953917D03*
X1308370D03*
X1310221Y957122D03*
X1308371Y973143D03*
X1310221Y976347D03*
X1314352Y996480D03*
X1314353Y1002888D03*
X1308803Y1006093D03*
X1314353Y1015705D03*
Y1022114D03*
X1308803Y1025318D03*
Y1018910D03*
X1314353Y1041340D03*
X1308803Y1044544D03*
X1310653Y1041340D03*
X1314353Y1060565D03*
X1312502Y1082995D03*
X1314353Y1111834D03*
Y1105426D03*
X1312503Y1115039D03*
Y1127856D03*
X1320469Y155288D03*
X1322652Y161149D03*
X1316242D03*
X1319452Y166699D03*
X1329062Y168549D03*
X1319442Y170399D03*
X1318502Y176574D03*
Y186024D03*
Y182874D03*
X1329062Y172249D03*
X1316237D03*
X1331102Y176574D03*
X1327952Y186024D03*
Y182874D03*
X1318502Y189174D03*
X1315352Y195474D03*
X1327952Y189174D03*
X1331102Y195474D03*
X1327952Y198624D03*
X1321652D03*
X1325852Y214799D03*
X1319442Y218499D03*
X1329062Y209249D03*
X1319442Y207399D03*
X1329062Y216649D03*
X1319442Y222199D03*
X1329061Y224049D03*
X1326377Y235784D03*
X1321986Y236726D03*
X1326869Y844971D03*
X1323170D03*
X1321320Y848176D03*
X1330571Y851380D03*
X1323170D03*
X1319469D03*
X1317620Y854584D03*
X1315770Y857789D03*
X1330571Y864197D03*
X1326871D03*
X1323171D03*
Y857789D03*
X1325020Y854584D03*
X1321321Y860993D03*
X1319469Y857789D03*
X1317621Y867401D03*
X1328721D03*
X1325021D03*
X1330571Y877014D03*
X1328722Y880219D03*
X1326871Y877014D03*
X1321321Y873810D03*
X1315771Y877014D03*
X1317621Y873810D03*
X1321321Y880219D03*
X1319471Y877014D03*
X1315771Y883423D03*
X1326871D03*
X1323171D03*
X1328720Y899445D03*
X1315771Y896240D03*
Y889832D03*
X1328720Y893036D03*
Y886627D03*
X1325021D03*
X1321321Y893036D03*
X1319470Y896240D03*
X1321321Y899445D03*
X1328720Y905853D03*
X1325020D03*
X1317621Y912262D03*
X1317620Y905853D03*
X1328720Y912262D03*
X1323171Y909057D03*
Y902649D03*
X1321321Y912262D03*
X1315771Y915466D03*
X1319471D03*
X1328720Y925079D03*
Y918670D03*
X1325020Y925079D03*
X1317620D03*
X1323171Y928283D03*
Y921875D03*
X1321321Y918670D03*
X1317621Y931488D03*
X1328720D03*
X1321321D03*
X1323171Y941100D03*
X1325020Y944304D03*
X1323171Y947509D03*
X1317620Y944304D03*
X1328720D03*
Y937896D03*
X1315771Y934692D03*
X1321321Y937896D03*
X1319470Y934692D03*
X1321321Y957122D03*
X1323171Y966735D03*
X1325020Y963530D03*
X1323171Y960326D03*
X1321321Y950713D03*
X1315771Y953917D03*
Y966735D03*
X1319470Y953917D03*
X1319471Y966735D03*
X1319470Y960326D03*
X1317621Y950713D03*
X1328720Y957122D03*
Y963530D03*
Y950713D03*
X1321321Y969939D03*
X1325020Y982756D03*
X1323171Y979552D03*
X1321321Y976347D03*
X1315771Y973143D03*
X1319471D03*
X1328720Y969939D03*
X1330570Y973143D03*
X1326871D03*
X1328720Y982756D03*
X1328721Y976347D03*
X1315771Y979552D03*
X1318053Y1009297D03*
Y1002888D03*
X1327304Y1006093D03*
X1331003D03*
X1329153Y1009297D03*
Y1002888D03*
X1323603Y999684D03*
X1321753Y1009297D03*
X1319903Y1006093D03*
X1321753Y1002888D03*
X1323603Y1012501D03*
X1329153Y1028523D03*
Y1015705D03*
X1318053Y1022114D03*
Y1015705D03*
X1329153Y1022114D03*
X1325453Y1015705D03*
X1323603Y1018910D03*
X1321753Y1028523D03*
X1319903Y1018910D03*
X1321753Y1022114D03*
Y1015705D03*
X1319903Y1031727D03*
X1323603D03*
X1329153Y1034931D03*
Y1047749D03*
X1318053Y1041340D03*
X1319903Y1038136D03*
X1329153Y1041340D03*
X1325453Y1034931D03*
X1323603Y1038136D03*
X1321753Y1041340D03*
X1319903Y1044544D03*
X1321753Y1047749D03*
X1329153Y1060565D03*
Y1054157D03*
X1325453D03*
X1319903Y1057361D03*
Y1050952D03*
X1323603D03*
Y1057361D03*
X1321753Y1060565D03*
X1319903Y1063770D03*
X1329153Y1073383D03*
X1319903Y1076587D03*
Y1070178D03*
X1316204Y1076587D03*
X1329153Y1066974D03*
X1323603Y1076587D03*
Y1070178D03*
X1325454Y1073383D03*
X1321753Y1066974D03*
X1329153Y1079791D03*
X1321753D03*
X1318053D03*
X1329153Y1086200D03*
Y1092608D03*
X1325452Y1092609D03*
X1323603Y1089404D03*
X1321752Y1086200D03*
X1319902Y1082995D03*
X1316202D03*
X1316203Y1095813D03*
X1331003Y1108630D03*
X1329153Y1099017D03*
X1323603Y1108630D03*
X1316203D03*
Y1102221D03*
X1325453Y1099017D03*
X1323603Y1102221D03*
X1319903D03*
X1316203Y1115039D03*
X1331003D03*
X1327303Y1121447D03*
Y1115039D03*
X1325453Y1124651D03*
X1325454Y1118243D03*
X1321753D03*
X1319903Y1115039D03*
X1329152Y1137469D03*
X1329153Y1131060D03*
X1321752Y1137469D03*
X1325453Y1131060D03*
X1319903Y1134264D03*
X1344103Y155288D03*
X1342936Y159301D03*
X1335472Y161149D03*
X1346137Y168549D03*
X1342907Y166699D03*
X1332268D03*
X1346137Y164849D03*
X1339727D03*
X1335472Y168549D03*
X1339568Y176028D03*
X1339727Y179649D03*
X1342937Y181499D03*
Y185199D03*
X1346137Y172249D03*
X1335472D03*
X1339727Y190749D03*
X1342937Y188899D03*
X1334252Y195474D03*
X1346137Y194449D03*
Y190749D03*
X1346147Y209248D03*
X1332262Y218499D03*
Y214799D03*
X1332285Y226210D03*
X1342937Y222199D03*
X1332267D03*
X1343521Y841467D03*
X1336121D03*
X1345371Y851380D03*
X1341671D03*
X1337971D03*
X1334271D03*
X1345371Y864197D03*
X1343521Y854584D03*
X1341671Y864197D03*
X1337971D03*
X1336121Y854584D03*
X1334271Y864197D03*
X1343521Y867401D03*
X1336121D03*
X1345371Y877014D03*
X1343521Y880219D03*
X1341671Y877014D03*
X1337971D03*
X1334271D03*
X1332420Y886627D03*
X1345371Y896240D03*
Y889832D03*
X1341671Y896240D03*
Y889832D03*
X1337970Y896240D03*
X1337971Y889832D03*
X1336121Y893036D03*
X1334270Y889832D03*
X1332420Y905853D03*
X1341671Y909057D03*
Y902649D03*
X1336120Y912262D03*
X1334270Y909057D03*
X1334271Y902649D03*
X1347221Y912262D03*
X1345371Y915466D03*
X1341671D03*
X1337970D03*
X1332421Y925079D03*
X1341671Y928283D03*
Y921875D03*
X1334270Y928283D03*
X1334271Y921875D03*
X1347220Y918670D03*
X1336120Y931488D03*
X1347221D03*
X1341671Y947509D03*
X1334270D03*
X1334271Y941100D03*
X1332421Y944304D03*
X1345371Y934691D03*
X1341671D03*
X1337970D03*
X1337971Y953917D03*
X1345371D03*
X1341671D03*
Y960326D03*
X1347220Y957122D03*
X1343520Y963530D03*
X1339821D03*
X1341670Y966735D03*
X1347221Y950713D03*
X1334271Y960326D03*
X1336121Y957122D03*
X1332421Y963530D03*
X1334270Y966735D03*
X1336120Y950713D03*
X1347221Y969939D03*
X1337970Y973143D03*
X1347220Y976347D03*
X1345371Y973143D03*
X1341671Y979552D03*
Y973143D03*
X1336120Y969939D03*
X1336121Y976347D03*
X1334271Y979552D03*
X1332421Y982756D03*
X1342104Y999684D03*
Y1006093D03*
X1338403D03*
X1336553Y1009297D03*
X1336554Y1002888D03*
X1334704Y999684D03*
X1347654Y1009297D03*
X1342103Y1012501D03*
X1334703D03*
X1332854Y1015705D03*
X1345804Y1025318D03*
X1343953Y1015705D03*
X1342104Y1025318D03*
Y1018910D03*
X1340254Y1015705D03*
X1336553Y1028523D03*
X1338403Y1025318D03*
X1336554Y1022114D03*
X1334704Y1018910D03*
X1347653Y1028523D03*
Y1022114D03*
X1342104Y1031727D03*
X1334703D03*
X1332854Y1034931D03*
X1345804Y1044544D03*
X1342104D03*
Y1038136D03*
X1338403Y1044544D03*
X1336554Y1041340D03*
X1334704Y1038136D03*
X1347653Y1041340D03*
X1336553Y1047749D03*
X1347653D03*
X1332854Y1054157D03*
X1342104Y1057361D03*
Y1050952D03*
X1336554Y1060565D03*
X1334704Y1057361D03*
X1334703Y1050952D03*
X1347653Y1060565D03*
X1345804Y1063770D03*
X1342104D03*
X1338403D03*
X1332854Y1073383D03*
X1342104Y1070178D03*
X1336553Y1066974D03*
X1334703Y1070178D03*
X1334704Y1076587D03*
X1347654Y1066974D03*
X1336554Y1079791D03*
X1347653D03*
X1345804Y1082995D03*
X1342104Y1089404D03*
Y1082995D03*
X1338403D03*
X1336553Y1086200D03*
X1334703Y1089404D03*
X1332854Y1092608D03*
X1347654Y1086200D03*
X1342104Y1095813D03*
X1334703D03*
X1342104Y1102221D03*
X1338404D03*
X1336553Y1099017D03*
X1332853Y1105426D03*
Y1099017D03*
X1347654Y1105426D03*
Y1099017D03*
X1340254Y1111834D03*
X1332854D03*
X1347654D03*
X1343953Y1118243D03*
X1340253D03*
X1338403Y1115039D03*
X1336553Y1118243D03*
X1332853D03*
X1347653D03*
X1342104Y1127856D03*
X1334703D03*
X1343953Y1131060D03*
X1342103Y1140973D03*
X1340254Y1131060D03*
X1336554D03*
X1334703Y1140973D03*
X1332854Y1131060D03*
X1347653D03*
X1349351Y159298D03*
X1355758D03*
X1355761Y162998D03*
X1358865Y166732D03*
Y158854D03*
Y162793D03*
X1349351Y166698D03*
X1352557Y164848D03*
X1358865Y170671D03*
Y174603D03*
Y182484D03*
Y178544D03*
X1355761Y170398D03*
X1352557Y179648D03*
X1358371Y188778D03*
X1358865Y195240D03*
Y199180D03*
X1349351Y196298D03*
X1352561Y194448D03*
X1352551Y190748D03*
X1349345Y188898D03*
X1355761Y192598D03*
X1358865Y207060D03*
Y203120D03*
Y213994D03*
Y217934D03*
X1352560Y205549D03*
X1355765Y207399D03*
X1349351Y214798D03*
X1352561Y212948D03*
X1349351Y211098D03*
Y222198D03*
X1358321Y841467D03*
X1350921D03*
X1360171Y851380D03*
X1356471D03*
X1352771D03*
X1349071D03*
X1363871D03*
X1360171Y864197D03*
X1358321Y854584D03*
X1356471Y864197D03*
X1352771D03*
X1350921Y854584D03*
X1349071Y864197D03*
X1363871D03*
X1358321Y867401D03*
X1350921D03*
X1360171Y877014D03*
X1358321Y880219D03*
X1356471Y877014D03*
X1352771D03*
X1350921Y880219D03*
X1349071Y877014D03*
X1363871D03*
X1360171Y889832D03*
X1356471D03*
X1354621Y893036D03*
X1352771Y889832D03*
X1349071D03*
X1363871Y896240D03*
Y889832D03*
X1362021Y899445D03*
X1354620D03*
X1362020Y912262D03*
X1360170Y909057D03*
X1360171Y902649D03*
X1358321Y905853D03*
X1354620Y912262D03*
Y905853D03*
X1350920D03*
X1349071Y909057D03*
X1349070Y902649D03*
X1363870Y915466D03*
X1362021Y918670D03*
X1360170Y928283D03*
X1360171Y921875D03*
X1358321Y925079D03*
X1354620D03*
Y918670D03*
X1350920Y925079D03*
X1349071Y928283D03*
X1349070Y921875D03*
X1362020Y931488D03*
X1360171Y941100D03*
X1358321Y944304D03*
X1354620D03*
X1360170Y947509D03*
X1350920Y944304D03*
X1349071Y947509D03*
X1349070Y941100D03*
X1362021Y937896D03*
X1354620D03*
X1363870Y934691D03*
X1363871Y953917D03*
X1360171Y960326D03*
X1362021Y957122D03*
X1354620D03*
X1358321Y963530D03*
X1354620D03*
X1360170Y966735D03*
X1354620Y950713D03*
X1362020D03*
X1349070Y960326D03*
X1350920Y963530D03*
X1349071Y966735D03*
X1362020Y969939D03*
X1354620D03*
X1363870Y973143D03*
X1362021Y976347D03*
X1360171Y979552D03*
X1358321Y982756D03*
X1356470Y973143D03*
X1354620Y982756D03*
X1354621Y976347D03*
X1350920Y982756D03*
X1349070Y979552D03*
X1352771Y973143D03*
X1351352Y996480D03*
X1349503Y999684D03*
X1362453Y1009297D03*
X1362454Y1002888D03*
X1360604Y999684D03*
X1355053Y1009297D03*
Y1002888D03*
X1360603Y1012501D03*
X1349504D03*
X1362453Y1028523D03*
X1362454Y1022114D03*
X1360604Y1018910D03*
X1358754Y1015705D03*
X1355053Y1028523D03*
Y1022114D03*
Y1015705D03*
X1351353D03*
X1349503Y1018910D03*
X1360603Y1031727D03*
X1349504D03*
X1362454Y1041340D03*
X1360604Y1038136D03*
X1358754Y1034931D03*
X1355053Y1041340D03*
Y1034931D03*
X1351353D03*
X1349503Y1038136D03*
X1362453Y1047749D03*
X1355053D03*
X1362454Y1060565D03*
X1360604Y1057361D03*
X1360603Y1050952D03*
X1358754Y1054157D03*
X1355053D03*
X1351353D03*
X1349503Y1057361D03*
X1349504Y1050952D03*
X1362453Y1066974D03*
X1360604Y1076587D03*
X1360603Y1070178D03*
X1358754Y1073383D03*
X1355053D03*
Y1066974D03*
X1351353Y1073383D03*
X1349503Y1076587D03*
X1349504Y1070178D03*
X1362453Y1079791D03*
X1355053D03*
X1362453Y1086200D03*
X1360603Y1089404D03*
X1358753Y1092608D03*
X1355053D03*
Y1086200D03*
X1351353Y1092608D03*
X1349504Y1089404D03*
X1360604Y1095813D03*
X1349504D03*
X1362454Y1099017D03*
X1360604Y1102221D03*
X1356904Y1108630D03*
X1355053Y1099017D03*
X1353204Y1102221D03*
X1349503Y1108630D03*
Y1102221D03*
X1362453Y1118243D03*
X1360603Y1115039D03*
X1358753Y1118243D03*
X1355053D03*
X1353203Y1115039D03*
X1351353Y1118243D03*
X1349503Y1115039D03*
X1356903Y1127856D03*
X1349503D03*
X1362453Y1131060D03*
X1358753D03*
X1356903Y1140973D03*
X1355053Y1131060D03*
X1351353D03*
X1349503Y1140973D03*
X1373121Y841467D03*
X1365721D03*
X1378671Y851380D03*
X1374971D03*
X1371271D03*
X1367571D03*
X1378671Y864197D03*
X1374971D03*
X1373121Y854584D03*
X1371271Y864197D03*
X1367571D03*
X1365721Y854584D03*
X1373121Y867401D03*
X1365721D03*
X1378671Y877014D03*
X1374971D03*
X1373121Y880219D03*
X1371271Y877014D03*
X1367571D03*
X1365721Y880219D03*
X1378671Y889832D03*
X1374971D03*
X1371271Y896240D03*
Y889832D03*
X1367570Y896240D03*
X1367571Y889832D03*
X1365721Y893036D03*
X1374971Y909057D03*
X1374970Y902649D03*
X1373121Y912262D03*
X1367571Y909057D03*
Y902649D03*
X1371271Y915466D03*
X1367571D03*
X1376820Y925079D03*
X1374971Y928283D03*
X1374970Y921875D03*
X1373120Y918670D03*
X1367571Y928283D03*
Y921875D03*
X1376820Y937896D03*
X1374970Y941100D03*
X1371271Y934691D03*
X1367571Y941100D03*
Y934691D03*
X1374971Y947509D03*
X1367571D03*
X1376820Y957122D03*
X1374970Y960326D03*
X1373120Y957122D03*
X1373121Y950713D03*
X1371271Y953917D03*
X1367571Y960326D03*
Y953917D03*
X1376820Y963530D03*
X1374971Y966735D03*
X1367571D03*
X1376820Y982756D03*
Y969939D03*
X1374970Y979552D03*
X1373120Y976347D03*
X1373121Y969939D03*
X1371271Y973143D03*
X1367571Y979552D03*
Y973143D03*
X1364303Y1006093D03*
X1377253Y1002888D03*
X1373554Y1009297D03*
X1373553Y1002888D03*
X1371704Y1006093D03*
X1368004D03*
Y999684D03*
X1375404Y1012501D03*
X1368003D03*
X1364303Y1025318D03*
X1375403Y1018910D03*
X1373553Y1028523D03*
Y1022114D03*
X1371704Y1025318D03*
X1369853Y1015705D03*
X1368004Y1025318D03*
Y1018910D03*
X1366154Y1015705D03*
X1375404Y1031727D03*
X1368004D03*
X1364303Y1044544D03*
X1375403Y1038136D03*
X1373553Y1041340D03*
X1371704Y1044544D03*
X1368004D03*
Y1038136D03*
X1373553Y1047749D03*
X1375403Y1057361D03*
X1375404Y1050952D03*
X1373553Y1060565D03*
X1368004Y1057361D03*
Y1050952D03*
X1364303Y1063770D03*
X1371704D03*
X1368004D03*
X1377253Y1073383D03*
X1375403Y1076587D03*
X1375404Y1070178D03*
X1373554Y1066974D03*
X1368004Y1076587D03*
Y1070178D03*
X1377253Y1079791D03*
X1373553D03*
X1364303Y1082995D03*
X1377254Y1092608D03*
X1377253Y1086200D03*
X1375404Y1089404D03*
X1373554Y1086200D03*
X1371704Y1082995D03*
X1368004Y1089404D03*
Y1082995D03*
X1379104Y1095813D03*
X1375403D03*
X1368004D03*
X1364304Y1108630D03*
Y1102221D03*
X1377253Y1105426D03*
X1375404Y1102221D03*
X1373554Y1099017D03*
X1371704Y1102221D03*
X1366153Y1105426D03*
X1373553Y1111834D03*
X1366153D03*
X1364303Y1115039D03*
X1377253Y1118243D03*
X1373553D03*
X1371703Y1115039D03*
X1369853Y1118243D03*
X1366153D03*
X1364303Y1127856D03*
X1379103D03*
X1371703D03*
X1364303Y1140973D03*
X1379103D03*
X1377253Y1131060D03*
X1373553D03*
X1371703Y1140973D03*
X1369853Y1131060D03*
X1366153D03*
X1380521Y841467D03*
X1395321D03*
X1387921D03*
X1393471Y851380D03*
X1389771D03*
X1386071D03*
X1382371D03*
X1380521Y854584D03*
X1395321D03*
X1393471Y864197D03*
X1389771D03*
X1387921Y854584D03*
X1386071Y864197D03*
X1382371D03*
X1380521Y867401D03*
X1395321D03*
X1387921D03*
X1380521Y880219D03*
X1395321D03*
X1393471Y877014D03*
X1389771D03*
X1387921Y880219D03*
X1386071Y877014D03*
Y870606D03*
X1382371Y877014D03*
X1395321Y893036D03*
X1393471Y889832D03*
X1389771D03*
X1387921Y893036D03*
X1386071Y889832D03*
X1384221Y893036D03*
X1382371Y889832D03*
X1386071Y902649D03*
X1380520Y912262D03*
Y905853D03*
X1395320Y912262D03*
X1395321Y905853D03*
X1393471Y902649D03*
X1389771D03*
X1386071Y909057D03*
Y915466D03*
X1380520Y918670D03*
X1395187Y926265D03*
X1395320Y918670D03*
X1386071Y921875D03*
X1381189Y930811D03*
Y938045D03*
X1381287Y946239D03*
Y948539D03*
X1381189Y935745D03*
X1390234Y942097D03*
X1381264Y965896D03*
Y963596D03*
X1390506Y971139D03*
X1392896D03*
X1381003Y981269D03*
Y978969D03*
Y986421D03*
X1381243Y992971D03*
Y995271D03*
X1381003Y988721D03*
X1381369Y1007156D03*
X1381373Y1004848D03*
X1393716Y1000059D03*
X1391326D03*
X1381128Y1022427D03*
X1381140Y1026821D03*
X1384466Y1034270D03*
Y1031970D03*
X1393904Y1044544D03*
X1384653Y1041340D03*
X1380953Y1047749D03*
X1388353D03*
X1380953Y1060565D03*
X1393904Y1050952D03*
X1392053Y1060565D03*
Y1054157D03*
X1388353Y1060565D03*
X1386504Y1050952D03*
X1384653Y1054157D03*
X1380953Y1066974D03*
X1395753Y1073383D03*
X1392053Y1066974D03*
X1386504Y1076587D03*
Y1070178D03*
X1382803Y1076587D03*
X1380953Y1079791D03*
X1388353D03*
X1393903Y1089404D03*
Y1082995D03*
X1392053Y1092608D03*
X1392054Y1086200D03*
X1388353Y1092608D03*
X1384653Y1086200D03*
X1386504Y1095813D03*
X1382804D03*
X1380954Y1105426D03*
X1393904Y1102221D03*
X1392054Y1099017D03*
X1390204Y1108630D03*
X1388353Y1099017D03*
X1386504Y1102221D03*
X1382803Y1108630D03*
Y1102221D03*
X1380954Y1111834D03*
X1380953Y1118243D03*
X1386503Y1115039D03*
X1384653Y1118243D03*
X1382803Y1115039D03*
X1386503Y1127856D03*
X1380953Y1131060D03*
X1386503Y1140973D03*
X1384653Y1131060D03*
X1408269Y844971D03*
X1402721Y841467D03*
X1397171Y851380D03*
X1408271D03*
X1404571D03*
X1400871D03*
X1397171Y864197D03*
X1408271D03*
X1404571D03*
X1402721Y854584D03*
X1400871Y864197D03*
X1410121Y854584D03*
Y867401D03*
X1402721D03*
X1397171Y877014D03*
X1410121Y880219D03*
X1408271Y877014D03*
X1404571D03*
X1402721Y880219D03*
X1400871Y877014D03*
X1397171Y889832D03*
X1410121Y893036D03*
X1408271Y889832D03*
X1404571D03*
X1402721Y893036D03*
X1400871Y889832D03*
Y902649D03*
X1397171D03*
X1408271D03*
X1404571Y909057D03*
Y902649D03*
Y915466D03*
X1410121Y925079D03*
Y931488D03*
X1403016Y949498D03*
Y947198D03*
X1406420Y937896D03*
X1404016Y936469D03*
X1410120Y937896D03*
X1403046Y963634D03*
Y965934D03*
Y978035D03*
Y980335D03*
Y992421D03*
Y994721D03*
Y1009174D03*
Y1006874D03*
Y1021962D03*
Y1019662D03*
X1397604Y1063770D03*
Y1082995D03*
Y1095813D03*
X1428620Y848176D03*
X1415669Y844971D03*
X1421220Y848176D03*
X1417520D03*
X1423070Y851380D03*
X1419370D03*
X1415671D03*
X1413822Y860993D03*
X1426771Y864197D03*
X1424921Y854584D03*
X1423071Y864197D03*
X1419371D03*
X1417521Y854584D03*
X1415671Y864197D03*
Y857789D03*
X1424921Y867401D03*
X1417521D03*
X1424921Y880219D03*
X1423071Y877014D03*
X1419371D03*
X1417521Y880219D03*
X1415671Y877014D03*
X1413820Y886627D03*
X1426771Y889832D03*
X1424921Y893036D03*
X1423071Y889832D03*
X1419371D03*
X1417521Y893036D03*
X1415671Y896240D03*
Y889832D03*
X1413821Y899445D03*
Y905853D03*
X1426771Y902649D03*
X1423071Y909057D03*
Y902649D03*
X1419371D03*
X1415670D03*
X1423071Y915466D03*
Y928283D03*
X1417520Y925079D03*
Y931488D03*
X1413820Y918670D03*
X1423071Y921875D03*
X1424920Y937896D03*
X1421220D03*
X1417520D03*
X1413820D03*
X1427203Y1044544D03*
X1425353Y1047749D03*
X1429053Y1060565D03*
X1423503Y1057361D03*
Y1050952D03*
Y1063770D03*
X1425353Y1073383D03*
X1423503Y1076587D03*
Y1070178D03*
X1429053Y1079791D03*
X1425353D03*
X1425354Y1086200D03*
X1423503Y1082995D03*
X1437871Y851380D03*
X1434171D03*
X1430470D03*
X1432321Y841467D03*
X1439721D03*
X1445271Y851380D03*
X1441571D03*
X1439721Y854584D03*
X1432321D03*
X1437871Y864197D03*
X1434171D03*
X1430471D03*
X1445271D03*
X1441571D03*
X1432321Y867401D03*
X1439721D03*
X1437871Y877014D03*
X1434171D03*
X1432321Y880219D03*
X1430471Y877014D03*
X1445271D03*
X1441571D03*
X1439721Y880219D03*
X1437871Y889832D03*
X1434171D03*
X1432321Y893036D03*
X1430471Y889832D03*
X1445271Y896240D03*
X1439721Y893036D03*
X1445271Y889832D03*
X1441571D03*
X1437871Y902649D03*
X1434171D03*
X1432320Y905853D03*
X1430471Y902649D03*
X1441571D03*
Y909057D03*
Y915466D03*
X1430244Y931358D03*
Y933658D03*
X1432320Y918670D03*
X1430575Y1022185D03*
Y1019885D03*
X1443541Y1036914D03*
X1436453Y1041340D03*
X1442003Y1044544D03*
X1432753Y1047749D03*
X1440153D03*
X1432753Y1054157D03*
X1442004Y1057361D03*
X1438304Y1050952D03*
X1434604Y1063770D03*
X1442004D03*
X1432753Y1073383D03*
X1430903Y1076587D03*
X1430904Y1070178D03*
X1443853Y1073383D03*
Y1066974D03*
X1438304Y1070178D03*
X1432754Y1079791D03*
X1443853D03*
X1434603Y1082995D03*
X1432753Y1086200D03*
X1436453Y1092608D03*
X1443854Y1086200D03*
X1440153D03*
X1443854Y1092608D03*
X1442003Y1108630D03*
Y1102221D03*
X1440154Y1099017D03*
X1443853Y1105426D03*
Y1111834D03*
X1454521Y841467D03*
X1447121D03*
X1460071Y851380D03*
X1452671D03*
X1456371D03*
X1448971D03*
X1460071Y864197D03*
X1456371D03*
X1454521Y854584D03*
X1452671Y864197D03*
X1447121Y854584D03*
X1448971Y864197D03*
X1454521Y867401D03*
X1447121D03*
X1460071Y877014D03*
X1456371D03*
X1454521Y880219D03*
X1452671Y877014D03*
X1448971D03*
X1448970Y870606D03*
X1447121Y880219D03*
Y873810D03*
X1456370Y896240D03*
X1456371Y889832D03*
X1454521Y893036D03*
X1447121D03*
X1460071Y889832D03*
X1452671D03*
X1448971D03*
X1458220Y899445D03*
X1460071Y909057D03*
X1458221Y912262D03*
X1450820Y905853D03*
X1460070Y902649D03*
X1452426Y930125D03*
X1460071Y928283D03*
X1458220Y918670D03*
X1456371Y921875D03*
X1460070D03*
X1452670D03*
X1450820Y918670D03*
X1458220Y931488D03*
X1452426Y934725D03*
X1454520Y944304D03*
X1452321Y945354D03*
Y947654D03*
X1460070Y941100D03*
X1458221Y944304D03*
X1458220Y937896D03*
X1456371Y934691D03*
X1460070Y947509D03*
X1452426Y962325D03*
Y960025D03*
Y964625D03*
X1460070Y960326D03*
X1458220Y957122D03*
X1458221Y950713D03*
X1460071Y966735D03*
X1452426Y966925D03*
X1452333Y977669D03*
X1452476Y980736D03*
X1458221Y969939D03*
X1460070Y979552D03*
X1458220Y976347D03*
X1452426Y996825D03*
Y994525D03*
Y989925D03*
Y987625D03*
X1452436Y1010499D03*
X1452426Y1006025D03*
Y1003725D03*
Y1012925D03*
X1460503Y999684D03*
X1458654Y1009297D03*
X1458653Y1002888D03*
X1460504Y1012501D03*
X1452416Y1022635D03*
X1452426Y1017525D03*
X1458653Y1028523D03*
Y1022114D03*
X1460503Y1018910D03*
Y1031727D03*
X1447424Y1036526D03*
X1449649Y1035928D03*
X1458653Y1041340D03*
X1458654Y1034931D03*
X1451253Y1041340D03*
X1460503Y1038136D03*
X1458653Y1047749D03*
X1447553D03*
X1460503Y1057361D03*
X1458653Y1060565D03*
X1456804Y1050952D03*
X1451253Y1060565D03*
X1447553Y1054157D03*
X1460504Y1050952D03*
X1460503Y1076587D03*
X1451253Y1066974D03*
X1449404Y1070178D03*
X1460504D03*
X1458654Y1066974D03*
X1454953Y1073383D03*
X1458653Y1079791D03*
X1454954D03*
X1451253D03*
X1445703Y1089404D03*
X1458654Y1086200D03*
X1456804Y1082995D03*
X1453104Y1089404D03*
X1449404Y1082995D03*
X1460504Y1089404D03*
X1445704Y1095813D03*
X1460504D03*
X1456803D03*
X1445704Y1102221D03*
X1458653Y1105426D03*
X1456804Y1108630D03*
X1454953Y1099017D03*
X1449404Y1108630D03*
X1453104Y1102221D03*
X1451254Y1099017D03*
X1447553D03*
X1458653Y1111834D03*
X1460504Y1108630D03*
X1451253Y1111834D03*
X1447553D03*
X1454953Y1105426D03*
X1445704Y1108630D03*
X1449404Y1102221D03*
X1458653Y1099017D03*
X1454953Y1111834D03*
X1453104Y1108630D03*
X1447553Y1105426D03*
X1451253D03*
X1460504Y1102221D03*
X1458653Y1118243D03*
X1456803Y1115039D03*
X1454953Y1118243D03*
X1453103Y1115039D03*
X1451253Y1118243D03*
X1460503Y1127856D03*
X1453103D03*
X1460504Y1115039D03*
X1449404D03*
X1458653Y1131060D03*
X1454953D03*
X1453103Y1140973D03*
X1451253Y1131060D03*
X1449403Y1134264D03*
X1460503Y1140973D03*
X1469321Y841467D03*
X1461921D03*
X1476721D03*
X1474871Y851380D03*
X1471171D03*
X1467471D03*
X1463771D03*
X1461921Y854584D03*
X1474871Y864197D03*
X1471171D03*
X1469321Y854584D03*
X1467471Y864197D03*
X1463771D03*
X1476721Y854584D03*
X1461921Y867401D03*
X1476721D03*
X1469321D03*
X1461921Y880219D03*
X1471171Y877014D03*
X1476721Y880219D03*
X1474871Y877014D03*
X1469321Y880219D03*
X1467471Y877014D03*
X1463771D03*
X1474871Y889832D03*
X1465621Y893036D03*
X1476721D03*
X1474871Y896240D03*
X1471171Y889832D03*
X1467471D03*
X1463771D03*
X1473021Y899445D03*
X1465620D03*
X1461920Y905853D03*
X1473020Y912262D03*
X1471171Y909057D03*
X1465620Y905853D03*
X1471171Y902649D03*
X1469321Y905853D03*
X1474870Y915466D03*
X1461920Y925079D03*
X1471170Y928283D03*
X1469321Y925079D03*
X1465620D03*
Y918670D03*
X1473021D03*
X1471171Y921875D03*
X1473020Y931488D03*
X1465620D03*
X1461920Y944304D03*
X1474871Y934691D03*
X1473021Y937896D03*
X1471171Y941100D03*
X1469321Y944304D03*
X1465620D03*
Y937896D03*
X1471170Y947509D03*
X1474871Y953917D03*
X1473021Y957122D03*
X1471171Y960326D03*
X1465620Y957122D03*
Y950713D03*
X1473020D03*
X1461920Y963530D03*
X1476721D03*
X1471170Y966735D03*
X1469321Y963530D03*
X1465620D03*
X1473021Y976347D03*
X1473020Y969939D03*
X1465620Y976347D03*
Y969939D03*
X1474870Y973143D03*
X1471171Y979552D03*
X1461920Y982756D03*
X1469321D03*
X1465620D03*
X1475303Y1006093D03*
X1473453Y1009297D03*
X1473454Y1002888D03*
X1471604Y999684D03*
X1466053Y1009297D03*
X1466054Y1002888D03*
X1467903Y1006093D03*
X1464204D03*
X1471603Y1012501D03*
X1462353Y1015705D03*
X1473453Y1028523D03*
X1466053D03*
Y1022114D03*
Y1015705D03*
X1477154D03*
X1475303Y1025318D03*
X1473453Y1022114D03*
X1471604Y1018910D03*
X1469754Y1015705D03*
X1471603Y1031727D03*
X1462353Y1034931D03*
X1473454Y1041340D03*
X1466053D03*
Y1034931D03*
X1475303Y1044544D03*
X1471604Y1038136D03*
X1469754Y1034931D03*
X1466053Y1047749D03*
X1473453D03*
X1462353Y1054157D03*
X1473453Y1060565D03*
X1471604Y1057361D03*
X1466053Y1060565D03*
Y1054157D03*
X1471603Y1050952D03*
X1469753Y1054157D03*
X1475304Y1063770D03*
X1462353Y1073383D03*
X1471604Y1076587D03*
X1469754Y1073383D03*
X1466053Y1066974D03*
X1473453D03*
X1471603Y1070178D03*
X1466053Y1073383D03*
X1473454Y1079791D03*
X1466053D03*
X1462353Y1092608D03*
X1475303Y1082995D03*
X1473453Y1086200D03*
X1469754Y1092608D03*
X1466053D03*
Y1086200D03*
X1471603Y1089404D03*
X1475304Y1095813D03*
X1471604D03*
X1467904D03*
X1462353Y1105426D03*
X1462354Y1099017D03*
X1475303Y1108630D03*
Y1102221D03*
X1473454Y1105426D03*
X1469753D03*
X1467904Y1102221D03*
X1464203D03*
X1473454Y1111834D03*
X1466053D03*
Y1099017D03*
X1471604Y1102221D03*
X1477153Y1099017D03*
X1469753D03*
X1473453D03*
X1466053Y1105426D03*
X1462353Y1111834D03*
X1467904Y1108630D03*
X1464204D03*
X1462353Y1118243D03*
X1477153D03*
X1475303Y1115039D03*
X1473453Y1118243D03*
X1471604Y1121447D03*
X1469754Y1118243D03*
X1466053D03*
X1475303Y1127856D03*
X1467903D03*
X1467904Y1115039D03*
X1471604D03*
X1462353Y1131060D03*
X1477153D03*
X1475303Y1140973D03*
X1473453Y1131060D03*
X1469753D03*
X1466053D03*
X1467903Y1140973D03*
X1491521Y841467D03*
X1484121D03*
X1478571Y851380D03*
X1482271D03*
X1489671D03*
X1485971D03*
X1493371D03*
X1478571Y864197D03*
X1491521Y854584D03*
X1489671Y864197D03*
X1485971D03*
X1482271D03*
X1493371D03*
X1491521Y867401D03*
X1484121D03*
Y854584D03*
X1478571Y877014D03*
X1491521Y880219D03*
X1485971Y877014D03*
X1484121Y880219D03*
X1489671Y877014D03*
X1482271D03*
X1493371D03*
X1478570Y896240D03*
X1478571Y889832D03*
X1491521Y893036D03*
X1482271Y889832D03*
X1489671D03*
X1485971D03*
X1482270Y896240D03*
X1480421Y893036D03*
X1493371Y889832D03*
X1491520Y899445D03*
X1484120D03*
X1478571Y909057D03*
Y902649D03*
X1491520Y912262D03*
X1487820Y905853D03*
X1485971Y909057D03*
X1484121Y912262D03*
X1491520Y905853D03*
X1485970Y902649D03*
X1478571Y915466D03*
X1482271D03*
X1478571Y928283D03*
Y921875D03*
X1491520Y925079D03*
Y918670D03*
X1487820Y925079D03*
X1485971Y928283D03*
X1485970Y921875D03*
X1484120Y918670D03*
X1491520Y931488D03*
X1484121D03*
X1478571Y941100D03*
Y934691D03*
X1491520Y944304D03*
Y937896D03*
X1487820Y944304D03*
X1485970Y941100D03*
X1482271Y934691D03*
X1478571Y947509D03*
Y960326D03*
Y953917D03*
X1491520Y957122D03*
Y950713D03*
X1485970Y960326D03*
X1484120Y957122D03*
X1482271Y953917D03*
X1484121Y950713D03*
X1478570Y966735D03*
X1491520Y963530D03*
X1485971Y966735D03*
X1487820Y963530D03*
X1480420D03*
X1478571Y979552D03*
Y973143D03*
X1491521Y976347D03*
X1491520Y969939D03*
X1484120Y976347D03*
X1484121Y969939D03*
X1489671Y973143D03*
X1485970Y979552D03*
X1482271Y973143D03*
X1493370D03*
X1491520Y982756D03*
X1487820D03*
X1479004Y999684D03*
X1486403D03*
X1484553Y1002888D03*
X1482704Y1006093D03*
X1479003Y1012501D03*
X1486404D03*
X1491953Y1009297D03*
Y1002888D03*
X1484554Y1009297D03*
X1479004Y1025318D03*
Y1018910D03*
X1491953Y1028523D03*
Y1022114D03*
X1484553Y1028523D03*
X1486403Y1018910D03*
X1484553Y1022114D03*
X1482704Y1025318D03*
X1480853Y1015705D03*
X1479004Y1031727D03*
X1486404D03*
X1488253Y1015705D03*
X1491953D03*
X1479004Y1044544D03*
Y1038136D03*
X1491953Y1034931D03*
Y1041340D03*
X1488253Y1034931D03*
X1486403Y1038136D03*
X1484553Y1041340D03*
X1482704Y1044544D03*
X1491953Y1047749D03*
X1484553D03*
X1479004Y1057361D03*
Y1050952D03*
X1491953Y1054157D03*
X1486404Y1057361D03*
X1484553Y1060565D03*
X1488253Y1054157D03*
X1486404Y1050952D03*
X1491953Y1060565D03*
X1479004Y1063770D03*
X1482704D03*
X1479004Y1076587D03*
Y1070178D03*
X1486404Y1076587D03*
Y1070178D03*
X1488253Y1073383D03*
X1484553Y1066974D03*
X1491953Y1073383D03*
Y1066974D03*
X1484553Y1079791D03*
X1491953D03*
X1479004Y1089404D03*
Y1082995D03*
X1488254Y1092608D03*
X1486404Y1089404D03*
X1484554Y1086200D03*
X1482704Y1082995D03*
X1491954Y1092608D03*
X1479004Y1095813D03*
X1490103D03*
X1493804D03*
X1479004Y1102221D03*
X1490104Y1108630D03*
Y1102221D03*
X1488254Y1099017D03*
X1484553D03*
X1482704Y1108630D03*
X1480853Y1099017D03*
X1491953Y1105426D03*
Y1111834D03*
X1493804Y1108630D03*
X1490103Y1115039D03*
X1488253Y1118243D03*
X1484553D03*
X1480853D03*
X1486403Y1115039D03*
X1491953Y1118243D03*
X1490103Y1127856D03*
X1482703D03*
X1493804Y1115039D03*
X1490103Y1140973D03*
X1488253Y1131060D03*
X1484553D03*
X1480853D03*
X1482703Y1140973D03*
X1491953Y1131060D03*
X1504471Y844671D03*
X1498921Y841467D03*
X1508171Y851380D03*
X1504471D03*
X1500771D03*
X1497071D03*
X1504471Y864197D03*
X1500771D03*
X1508170Y857789D03*
X1497071Y864197D03*
X1506321Y860993D03*
Y854584D03*
X1498921D03*
X1510021Y860993D03*
X1506320Y867401D03*
X1498921D03*
X1510021D03*
X1504471Y877014D03*
X1498921Y880219D03*
X1508171Y877014D03*
X1497071D03*
X1506321Y880219D03*
X1500771Y877014D03*
X1510021Y880219D03*
Y873810D03*
X1508170Y883423D03*
X1508171Y889832D03*
X1504471Y896240D03*
Y889832D03*
X1500771D03*
X1508171Y896240D03*
X1502621Y893036D03*
X1500771Y896240D03*
X1497071Y889832D03*
X1510021Y893036D03*
X1498921Y899445D03*
X1510021D03*
X1495221Y905853D03*
X1504471Y902649D03*
X1498920Y912262D03*
X1497070Y909057D03*
X1497071Y902649D03*
X1508171Y915466D03*
X1504471D03*
X1500770D03*
X1504471Y909057D03*
X1510021Y912262D03*
X1495221Y925079D03*
X1504471Y921875D03*
X1497070Y928283D03*
X1498921Y918670D03*
X1497071Y921875D03*
X1498920Y931488D03*
X1504471Y928283D03*
X1510021Y918670D03*
X1510020Y931488D03*
X1495221Y944304D03*
X1504471Y941100D03*
Y934691D03*
X1500770D03*
X1498921Y937896D03*
X1497071Y941100D03*
X1497070Y947509D03*
X1508171Y934691D03*
X1510021Y937896D03*
X1504471Y947509D03*
Y960326D03*
Y953917D03*
X1500771D03*
X1498921Y957122D03*
X1497071Y960326D03*
X1498920Y950713D03*
X1495221Y963530D03*
X1497070Y966735D03*
X1502621Y963530D03*
X1510021Y957122D03*
X1508171Y953917D03*
X1510021Y950713D03*
X1506320Y963530D03*
X1504471Y966735D03*
Y979552D03*
Y973143D03*
X1498921Y976347D03*
X1498920Y969939D03*
X1500770Y973143D03*
X1497071Y979552D03*
X1510021Y976347D03*
X1495221Y982756D03*
X1510043Y980606D03*
X1510021Y969939D03*
X1508171Y973143D03*
X1497503Y1012501D03*
Y999684D03*
X1504904Y1006093D03*
Y999684D03*
X1501203Y1006093D03*
X1499353Y1009297D03*
X1499354Y1002888D03*
X1510453Y1009297D03*
Y1002888D03*
X1508603Y1006093D03*
X1504903Y1012501D03*
X1504904Y1025318D03*
X1499353Y1028523D03*
X1501203Y1025318D03*
X1504904Y1031727D03*
X1497503D03*
X1495654Y1015705D03*
X1497504Y1018910D03*
X1499353Y1022114D03*
X1503054Y1015705D03*
X1504904Y1018910D03*
X1506753Y1015705D03*
X1510453Y1028523D03*
X1510452Y1022114D03*
X1508603Y1025318D03*
X1504904Y1044544D03*
X1501203D03*
X1499354Y1041340D03*
X1497504Y1038136D03*
X1495654Y1034931D03*
X1508604Y1044544D03*
X1499353Y1047749D03*
X1504904Y1038136D03*
X1510453Y1041340D03*
Y1047749D03*
X1504904Y1057361D03*
Y1050952D03*
X1499354Y1060565D03*
X1497504Y1057361D03*
X1497503Y1050952D03*
X1495654Y1054157D03*
X1504904Y1063770D03*
X1501203D03*
X1510453Y1060565D03*
X1508604Y1063770D03*
X1504904Y1076587D03*
Y1070178D03*
X1497504Y1076587D03*
X1497503Y1070178D03*
X1495654Y1073383D03*
X1499353Y1066974D03*
X1499354Y1079791D03*
X1510453Y1066974D03*
Y1079791D03*
X1499353Y1086200D03*
X1497503Y1089404D03*
X1495653Y1092608D03*
X1504904Y1089404D03*
Y1082995D03*
X1501203D03*
X1508604Y1082996D03*
X1510453Y1086200D03*
X1504903Y1095813D03*
X1503053Y1105426D03*
X1497503Y1102221D03*
X1495653Y1105426D03*
X1495654Y1099017D03*
X1508603Y1108630D03*
X1506754Y1111834D03*
X1499353D03*
X1503053Y1099017D03*
X1510453D03*
X1508602Y1102221D03*
X1497504Y1108630D03*
X1501204D03*
X1510453Y1111834D03*
X1499353Y1105426D03*
X1510453D03*
X1504904Y1108630D03*
X1495653Y1111834D03*
X1503053D03*
X1506753Y1124651D03*
Y1118243D03*
X1504904Y1121447D03*
X1499353Y1118243D03*
X1497503Y1115039D03*
X1495653Y1118243D03*
X1508603Y1115039D03*
X1504904Y1127856D03*
X1497503D03*
X1501204Y1115039D03*
X1504904D03*
X1506754Y1137469D03*
X1506753Y1131060D03*
X1503053D03*
X1499353D03*
X1495653D03*
X1504904Y1134264D03*
X1497503Y1140973D03*
X1510453Y1131060D03*
X1511871Y844671D03*
X1513722Y848176D03*
X1511871Y851380D03*
X1521121Y860993D03*
Y854584D03*
X1515570Y864197D03*
X1513721Y854584D03*
Y860993D03*
X1521121Y867401D03*
X1517421D03*
X1513721D03*
X1511871Y870606D03*
X1522971D03*
X1517421Y873810D03*
X1511871Y883423D03*
X1517421Y880219D03*
X1522971Y883423D03*
X1511871Y889832D03*
X1513721Y893036D03*
X1517421Y886627D03*
X1521121D03*
X1513721D03*
X1526671Y889832D03*
X1513721Y899445D03*
X1524821Y912262D03*
X1511871Y909057D03*
Y902649D03*
X1513721Y912262D03*
X1515571Y909057D03*
X1524821Y905853D03*
X1513721D03*
X1519271Y909057D03*
X1511871Y921875D03*
X1513721Y918670D03*
X1524820Y931488D03*
X1513720D03*
X1511871Y941100D03*
X1513721Y937896D03*
X1511871Y947509D03*
X1519271D03*
X1515571D03*
X1511871Y960326D03*
X1513721Y957122D03*
Y950713D03*
X1511871Y966735D03*
X1513721Y963530D03*
X1515571Y979552D03*
X1513721Y982756D03*
X1511871Y973143D03*
X1517421Y969939D03*
X1515571Y973143D03*
X1516004Y1006092D03*
X1516003Y999684D03*
X1512303D03*
Y1006093D03*
X1519705Y1006092D03*
X1525396Y1000648D03*
X1512303Y1012501D03*
Y1025318D03*
X1516003Y1018910D03*
X1517854Y1015705D03*
X1525254D03*
X1521554D03*
X1514154D03*
X1512303Y1018910D03*
Y1031727D03*
X1525254Y1034931D03*
X1521554D03*
X1516004Y1044544D03*
X1516003Y1038136D03*
X1517853Y1034931D03*
X1514153D03*
X1512303Y1038136D03*
X1517853Y1054157D03*
X1514153D03*
X1512303Y1057361D03*
X1521553Y1054157D03*
X1514153Y1060565D03*
X1512303Y1050952D03*
X1525564Y1064850D03*
X1523404Y1070178D03*
X1514153Y1066974D03*
X1517853Y1073383D03*
X1521553Y1066974D03*
X1516003Y1076587D03*
X1512303D03*
X1512304Y1070178D03*
X1514153Y1073383D03*
X1523404Y1082996D03*
X1512304D03*
X1514153Y1092608D03*
X1512303Y1089404D03*
X1521553Y1092608D03*
X1523403Y1095813D03*
X1519703D03*
X1512303D03*
X1521554Y1105426D03*
X1517853D03*
X1516003Y1108630D03*
Y1102221D03*
X1512303D03*
X1517853Y1111834D03*
X1521553D03*
X1514153Y1105426D03*
X1512303Y1108630D03*
X1514153Y1111834D03*
X1519703Y1108630D03*
X1521553Y1124651D03*
Y1118243D03*
X1519704Y1115039D03*
X1516004D03*
X1514153Y1124651D03*
X1512303Y1115039D03*
X1517854Y1131560D03*
X1512304Y1134264D03*
X1527571Y979057D03*
X1526843Y972608D03*
X1527103Y1031726D03*
X1665141Y1051247D03*
X1724541D03*
G54D43*
X333834Y1062790D03*
X329632Y1092168D03*
X335344Y1097289D03*
X549719Y962436D03*
X548146Y965640D03*
X543729Y984866D03*
X1309976Y1062790D03*
X1305774Y1092168D03*
X1311486Y1097289D03*
X1337102Y206675D03*
X1525861Y962436D03*
X1524288Y965640D03*
X1519871Y984866D03*
X1879155Y468898D03*
Y716798D03*
X1889155Y468898D03*
Y716798D03*
X1900275Y840758D03*
X1910275D03*
X1921395Y-19332D03*
X1931395D03*
X1942395Y593048D03*
X1952395D03*
X1963362Y-19190D03*
X1973362D03*
X1984482Y593020D03*
X1994482D03*
X2005452Y-19180D03*
X2015452D03*
X2026452Y593200D03*
X2047419Y-19038D03*
X2036452Y593200D03*
X2057419Y-19038D03*
X2068539Y593172D03*
X2078539D03*
G54D52*
X717313Y-27626D03*
Y-21471D03*
Y-17597D03*
X717298Y-15082D03*
X717313Y-11442D03*
X717298Y-25111D03*
X717313Y-7568D03*
X717298Y-5053D03*
X834273Y2374D03*
X834258Y4889D03*
X834273Y22432D03*
Y8529D03*
Y12403D03*
X834258Y14918D03*
X834273Y18558D03*
X834258Y24947D03*
X1026705Y-27695D03*
Y-38224D03*
X1023437Y-38210D03*
X1026690Y-35709D03*
X1023422Y-35695D03*
X1026705Y-32069D03*
Y-17666D03*
X1026690Y-15151D03*
X1026705Y-11511D03*
X1026690Y-25180D03*
X1026705Y-21540D03*
X1026690Y4907D03*
X1026705Y2392D03*
X1026690Y-5122D03*
X1026705Y-7637D03*
Y-1482D03*
Y22450D03*
Y18576D03*
Y8547D03*
X1026690Y14936D03*
X1026705Y12421D03*
X1026690Y24965D03*
X1336024Y-27695D03*
Y-32069D03*
X1332741Y-35695D03*
X1336009Y-35709D03*
X1332756Y-38210D03*
X1336024Y-38224D03*
Y-11511D03*
X1336009Y-15151D03*
X1336024Y-17666D03*
Y-21540D03*
X1336009Y-25180D03*
X1336024Y2392D03*
X1336009Y4907D03*
X1336024Y-1482D03*
Y-7637D03*
X1336009Y-5122D03*
X1336024Y18576D03*
Y22450D03*
Y12421D03*
X1336009Y14936D03*
X1336024Y8547D03*
X1336009Y24965D03*
G54D62*
X918780Y1684890D03*
Y1694890D03*
Y1714890D03*
X928780Y1684890D03*
X938780D03*
X928780Y1694890D03*
X938780D03*
X928780Y1704890D03*
X938780D03*
X928780Y1714890D03*
X938780D03*
G54D72*
X1879155Y354948D03*
Y458898D03*
Y478898D03*
Y582848D03*
Y602848D03*
Y706798D03*
Y726798D03*
Y830748D03*
X1900275Y-9342D03*
X1889155Y354948D03*
Y458898D03*
Y478898D03*
X1900275Y582858D03*
X1889155Y582848D03*
Y602848D03*
Y706798D03*
X1900275Y726808D03*
X1889155Y726798D03*
X1900275Y830758D03*
X1889155Y830748D03*
X1900275Y850758D03*
Y954708D03*
X1910275Y-9342D03*
Y582858D03*
Y726808D03*
Y830758D03*
Y850758D03*
Y954708D03*
X1921395Y-9332D03*
X1931395D03*
Y582868D03*
X1921395D03*
X1931395Y602868D03*
X1921395D03*
Y1195068D03*
X1931395D03*
X1942395Y-9152D03*
Y583048D03*
Y603048D03*
Y1195248D03*
X1963362Y-9190D03*
X1952395Y-9152D03*
X1963362Y583010D03*
X1952395Y583048D03*
X1963362Y603010D03*
X1952395Y603048D03*
X1963362Y1195210D03*
X1952395Y1195248D03*
X1973362Y-9190D03*
Y583010D03*
Y603010D03*
Y1195210D03*
X1994482Y-9180D03*
X1984482D03*
Y583020D03*
X1994482D03*
X1984482Y603020D03*
X1994482D03*
Y1195220D03*
X1984482D03*
X2005452Y-9180D03*
X2015452D03*
Y583020D03*
X2005452D03*
X2015452Y603020D03*
X2005452D03*
Y1195220D03*
X2015452D03*
X2026452Y-9000D03*
Y583200D03*
Y603200D03*
Y1195400D03*
X2047419Y-9038D03*
X2036452Y-9000D03*
X2047419Y583162D03*
X2036452Y583200D03*
X2047419Y603162D03*
X2036452Y603200D03*
X2047419Y1195362D03*
X2036452Y1195400D03*
X2057419Y-9038D03*
Y583162D03*
Y603162D03*
Y1195362D03*
X2068539Y603172D03*
X2078539D03*
Y1195372D03*
X2068539D03*
G54D73*
X1879155Y468898D03*
Y716798D03*
X1889155Y468898D03*
X1900275Y592858D03*
X1889155Y716798D03*
X1900275Y840758D03*
X1910275Y592858D03*
Y840758D03*
X1921395Y1205068D03*
X1931395D03*
X1942395Y593048D03*
X1952395D03*
X1963362Y1205210D03*
X1984482Y593020D03*
X1973362Y1205210D03*
X1994482Y593020D03*
X2005452Y1205220D03*
X2015452D03*
X2026452Y593200D03*
X2036452D03*
X2047419Y1205362D03*
X2057419D03*
G54D49*
X676508Y224606D03*
G54D27*
X155199Y967585D03*
Y1054593D03*
X171341Y964239D03*
Y1021129D03*
Y1024475D03*
Y1051247D03*
X184899Y816995D03*
Y810302D03*
Y833727D03*
Y823688D03*
Y827034D03*
Y847113D03*
Y840420D03*
Y853806D03*
Y860499D03*
Y863845D03*
Y877231D03*
Y870538D03*
Y927428D03*
Y920735D03*
Y934121D03*
Y944160D03*
Y937467D03*
Y950853D03*
Y980971D03*
Y974278D03*
Y967585D03*
Y994357D03*
Y987664D03*
Y1027822D03*
Y1021129D03*
Y1047900D03*
Y1041207D03*
Y1034515D03*
Y1054593D03*
Y1074672D03*
Y1067979D03*
Y1091404D03*
Y1081365D03*
Y1084711D03*
Y1098097D03*
Y1141601D03*
Y1148294D03*
Y1154987D03*
Y1158333D03*
Y1171719D03*
Y1165026D03*
Y1221916D03*
Y1215223D03*
Y1238648D03*
Y1228609D03*
Y1231955D03*
Y1245341D03*
X201041Y813648D03*
Y806955D03*
Y820341D03*
Y830381D03*
Y823688D03*
Y850459D03*
Y843766D03*
Y837074D03*
Y867192D03*
Y860499D03*
Y857152D03*
Y873885D03*
Y917389D03*
Y924081D03*
Y934121D03*
Y930774D03*
Y947507D03*
Y940814D03*
Y964239D03*
Y977625D03*
Y970932D03*
Y991011D03*
Y984318D03*
X201141Y1021129D03*
Y1024475D03*
Y1031168D03*
Y1044554D03*
Y1037861D03*
Y1051247D03*
Y1071326D03*
Y1064633D03*
Y1078018D03*
Y1094752D03*
Y1088059D03*
Y1081366D03*
Y1144948D03*
Y1138255D03*
Y1161680D03*
Y1154988D03*
Y1151641D03*
Y1168373D03*
Y1218570D03*
Y1211877D03*
Y1225263D03*
Y1241995D03*
Y1235302D03*
Y1228609D03*
X244299Y883924D03*
Y890617D03*
Y897310D03*
Y900656D03*
Y914042D03*
Y907349D03*
Y1185105D03*
Y1178412D03*
Y1191798D03*
Y1208530D03*
Y1201837D03*
Y1195144D03*
X260441Y880577D03*
Y887270D03*
Y897310D03*
Y893963D03*
Y910696D03*
Y904003D03*
Y1175066D03*
Y1181759D03*
Y1191798D03*
Y1188452D03*
Y1205184D03*
Y1198491D03*
X348878Y899445D03*
Y893036D03*
X350729Y889832D03*
X354429D03*
X347029Y896240D03*
X354429D03*
X350729D03*
X348878Y912262D03*
X350729Y909057D03*
X354429D03*
X350729Y902649D03*
X354429D03*
X347029Y915466D03*
X354429D03*
X350729D03*
X348879Y931488D03*
X350729Y928283D03*
X354429D03*
Y921875D03*
X350729D03*
X348878Y918670D03*
X350729Y941100D03*
X348878Y937896D03*
X354429Y941100D03*
X347029Y934691D03*
X354429D03*
X350729D03*
Y947509D03*
X354429D03*
X348878Y950713D03*
X350729Y960326D03*
X348878Y957122D03*
X354429Y960326D03*
X350729Y966735D03*
X354429D03*
X350729Y953917D03*
X354429D03*
X347030D03*
X350729Y979552D03*
X354429D03*
X348878Y976347D03*
X347029Y973143D03*
X348878Y969939D03*
X347461Y1006093D03*
X349311Y1002888D03*
X351161Y999684D03*
X354861D03*
X351161Y1012501D03*
X349311Y1009297D03*
X354861Y1012501D03*
X351162Y1031727D03*
X349311Y1028523D03*
X354861Y1031727D03*
X349311Y1022114D03*
X351161Y1018910D03*
X354861D03*
X347461Y1025318D03*
X354862D03*
X351162D03*
X349311Y1047749D03*
Y1041340D03*
X351161Y1038136D03*
X354861D03*
X347461Y1044544D03*
X354861D03*
X351161D03*
X349311Y1060565D03*
X351161Y1057361D03*
X354861D03*
X347461Y1063770D03*
X351161D03*
X354861D03*
X351161Y1050952D03*
X354861D03*
Y1070178D03*
X351162D03*
X349311Y1066974D03*
Y1079791D03*
X351161Y1076587D03*
X354861D03*
X351161Y1089404D03*
X349311Y1086200D03*
X354861Y1089404D03*
X347461Y1082995D03*
X354861D03*
X351161D03*
X353011Y1124651D03*
X354861Y1127856D03*
X356278Y899445D03*
Y893036D03*
X358129Y896240D03*
X356278Y912262D03*
X358129Y915466D03*
X356278Y931488D03*
Y918670D03*
Y937896D03*
X358129Y934691D03*
X356278Y950713D03*
Y957122D03*
X358129Y953917D03*
X359978Y982756D03*
X367378D03*
X363678D03*
X371078D03*
X369229Y979552D03*
X367378Y976347D03*
X361829Y979552D03*
X363678Y976347D03*
X356278D03*
Y969939D03*
X358129Y973143D03*
X358562Y1006093D03*
X356711Y1002888D03*
Y1009297D03*
Y1028523D03*
Y1022114D03*
X358562Y1025318D03*
X356711Y1047749D03*
Y1041340D03*
X358562Y1044544D03*
X356711Y1060565D03*
X358562Y1063770D03*
X356711Y1066974D03*
Y1079791D03*
Y1086200D03*
X358562Y1082995D03*
X358561Y1121447D03*
X360412Y1124651D03*
X364111D03*
X367811D03*
X371511D03*
X356712D03*
X362262Y1127856D03*
X365962Y1121447D03*
X369662Y1127856D03*
X375211Y1124651D03*
X378911D03*
X382611D03*
X386311D03*
X373362Y1121447D03*
X377062Y1127856D03*
X380762Y1121447D03*
X384462Y1127856D03*
X390011Y1124651D03*
X395562Y1121447D03*
X397411Y1124651D03*
X401111D03*
X391862Y1127856D03*
X393711Y1124651D03*
X399262Y1127856D03*
X402962Y1121447D03*
X388162D03*
X417329Y883423D03*
X415478Y880219D03*
X413629Y883423D03*
X419178Y886627D03*
X404811Y1124651D03*
X408511D03*
X406662Y1127856D03*
X410362Y1121447D03*
X432129Y883423D03*
X430278Y880219D03*
X424729Y883423D03*
X422878Y880219D03*
X428429Y883423D03*
X421029D03*
X435829D03*
X433978Y886627D03*
X426578D03*
X452479Y880219D03*
X446929Y883423D03*
X445078Y880219D03*
X439529Y883423D03*
X437678Y880219D03*
X450629Y883423D03*
X443229D03*
X448778Y886627D03*
X441378D03*
X469129Y883423D03*
X467278Y880219D03*
X461729Y883423D03*
X459878Y880219D03*
X454329Y883423D03*
X465429D03*
X458029D03*
X463578Y886627D03*
X456178D03*
X470978D03*
X484362Y1121447D03*
X480662Y1127856D03*
X476962Y1121447D03*
X473262Y1127856D03*
X469562Y1121447D03*
X482511Y1124651D03*
X478811D03*
X475111D03*
X471411D03*
X488062Y1127856D03*
X499162Y1121447D03*
X495462Y1127856D03*
X491762Y1121447D03*
X489911Y1124651D03*
X486211D03*
X501011D03*
X497311D03*
X493611D03*
X517662Y1006093D03*
X513962D03*
X510262D03*
X517662Y1012501D03*
X513962D03*
X512111Y1009297D03*
X517662Y1127856D03*
X513962Y1121447D03*
X510262Y1127856D03*
X506562Y1121447D03*
X502862Y1127856D03*
X515811Y1124651D03*
X512111D03*
X508411D03*
X504711D03*
X526479Y899445D03*
X530178D03*
X530179Y912262D03*
X532029Y909057D03*
X524629Y902649D03*
X532029D03*
X526479Y912262D03*
X524629Y909057D03*
X526479Y905853D03*
X533879D03*
X522778D03*
X530179D03*
X526479Y931488D03*
X524629Y928283D03*
X530179Y931488D03*
X532029Y928283D03*
X524629Y921875D03*
X526479Y918670D03*
X532029Y921875D03*
X530179Y918670D03*
X526479Y925079D03*
X533879D03*
X522778D03*
X530179D03*
X524629Y941100D03*
X526479Y937896D03*
X532029Y941100D03*
X530179Y937896D03*
X524629Y947509D03*
X532029D03*
X533879Y944304D03*
X526479D03*
X530178D03*
X522778D03*
X524629Y966735D03*
X532029D03*
X522778Y963530D03*
X526479Y950713D03*
X530178D03*
X532029Y960326D03*
X530178Y957122D03*
X524629Y960326D03*
X526479Y957122D03*
X533879Y963530D03*
X526479Y969939D03*
X530179D03*
X521362Y1006093D03*
X525062Y1012501D03*
X532461D03*
X526911Y1009297D03*
X530611D03*
X519511D03*
X523211Y1015705D03*
X534311D03*
X525062Y1031727D03*
X526911Y1028523D03*
X532461Y1031727D03*
X530611Y1028523D03*
Y1022114D03*
X532461Y1018910D03*
X526911Y1022114D03*
X525062Y1018910D03*
X526911Y1041340D03*
X525062Y1038136D03*
X530611Y1041340D03*
X532461Y1038136D03*
X526911Y1047749D03*
X530611D03*
X526911Y1034931D03*
X534311D03*
X523211D03*
X530611D03*
X526911Y1060565D03*
X525062Y1057361D03*
X530611Y1060565D03*
X532462Y1057361D03*
X525061Y1050952D03*
X532462Y1050953D03*
X523211Y1054157D03*
X534311D03*
X526911D03*
X530611D03*
Y1079791D03*
X532462Y1076587D03*
X525062Y1070178D03*
X526911Y1066974D03*
X532462Y1070178D03*
X530611Y1066974D03*
X526911Y1079791D03*
X525062Y1076587D03*
X523211Y1073383D03*
X534311D03*
X526911D03*
X530611D03*
X521362Y1095813D03*
X532461D03*
X525062D03*
Y1089404D03*
X526911Y1086200D03*
X532462Y1089404D03*
X530611Y1086200D03*
X526911Y1092608D03*
X534310D03*
X523211D03*
X530611D03*
Y1099017D03*
X526911Y1124651D03*
X521362Y1121447D03*
X525062Y1127856D03*
X523211Y1124651D03*
X519511D03*
X539429Y883423D03*
X537578Y880219D03*
X543129Y883423D03*
X544979Y880219D03*
X537578Y873810D03*
X539429Y870606D03*
X544979Y873810D03*
X543129Y870606D03*
X539428Y877014D03*
X546828D03*
X535729D03*
X543129D03*
X620799Y883924D03*
Y890617D03*
Y897310D03*
Y900656D03*
Y914042D03*
Y907349D03*
Y1185105D03*
Y1178412D03*
Y1191798D03*
Y1208530D03*
Y1201837D03*
Y1195144D03*
X636941Y880577D03*
Y887270D03*
Y897310D03*
Y893963D03*
Y910696D03*
Y904003D03*
Y1175066D03*
Y1181759D03*
Y1191798D03*
Y1188451D03*
Y1205184D03*
Y1198491D03*
X680299Y816995D03*
Y810302D03*
Y833727D03*
Y823688D03*
Y827034D03*
Y847113D03*
Y840420D03*
Y853806D03*
Y860499D03*
Y863845D03*
Y877231D03*
Y870538D03*
Y927428D03*
Y920735D03*
Y934121D03*
Y944160D03*
Y937467D03*
Y950853D03*
Y980971D03*
Y974278D03*
Y967585D03*
Y994357D03*
Y987664D03*
X679999Y1027822D03*
X680299Y1021129D03*
X679999Y1047900D03*
Y1041207D03*
Y1034514D03*
Y1054593D03*
X680299Y1074672D03*
Y1067979D03*
Y1091404D03*
Y1081365D03*
Y1084711D03*
Y1098097D03*
Y1141601D03*
Y1148294D03*
Y1154987D03*
Y1158333D03*
Y1171719D03*
Y1165026D03*
Y1221916D03*
Y1215223D03*
Y1238648D03*
Y1228609D03*
Y1231955D03*
Y1245341D03*
X696441Y813648D03*
Y806955D03*
Y820341D03*
Y830381D03*
Y823688D03*
Y850459D03*
Y843766D03*
Y837074D03*
Y867192D03*
Y860499D03*
Y857152D03*
Y873885D03*
Y917389D03*
Y924081D03*
Y934121D03*
Y930774D03*
Y947507D03*
Y940814D03*
Y964239D03*
Y977625D03*
Y970932D03*
Y991011D03*
Y984318D03*
Y1021129D03*
Y1024475D03*
Y1031168D03*
X696141Y1044554D03*
Y1037861D03*
X696441Y1051247D03*
Y1071325D03*
Y1064633D03*
Y1078018D03*
Y1094751D03*
Y1088058D03*
Y1081365D03*
Y1144947D03*
Y1138255D03*
Y1161680D03*
Y1154987D03*
Y1151640D03*
Y1168373D03*
Y1218569D03*
Y1211877D03*
Y1225262D03*
Y1241995D03*
Y1235302D03*
Y1228609D03*
X709999Y967585D03*
Y1054593D03*
X726141Y964239D03*
Y1021129D03*
Y1024475D03*
Y1051247D03*
X1131341Y967585D03*
Y1054593D03*
X1147483Y964239D03*
Y1021129D03*
Y1024475D03*
Y1051247D03*
X1161041Y816995D03*
Y810302D03*
Y833727D03*
Y823688D03*
Y827034D03*
Y847113D03*
Y840420D03*
Y853806D03*
Y860499D03*
Y863845D03*
Y877231D03*
Y870538D03*
Y927428D03*
Y920735D03*
Y934121D03*
Y944160D03*
Y937467D03*
Y950853D03*
Y980971D03*
Y974278D03*
Y967585D03*
Y994357D03*
Y987664D03*
Y1027822D03*
Y1021129D03*
Y1047900D03*
Y1041207D03*
Y1034515D03*
Y1054593D03*
Y1074672D03*
Y1067979D03*
Y1091404D03*
Y1081365D03*
Y1084711D03*
Y1098097D03*
Y1141601D03*
Y1148294D03*
Y1154987D03*
Y1158333D03*
Y1171719D03*
Y1165026D03*
Y1221916D03*
Y1215223D03*
Y1238648D03*
Y1228609D03*
Y1231955D03*
Y1245341D03*
X1177183Y813648D03*
Y806955D03*
Y820341D03*
Y830381D03*
Y823688D03*
Y850459D03*
Y843766D03*
Y837074D03*
Y867192D03*
Y860499D03*
Y857152D03*
Y873885D03*
Y917389D03*
Y924081D03*
Y934121D03*
Y930774D03*
Y947507D03*
Y940814D03*
Y964239D03*
Y977625D03*
Y970932D03*
Y991011D03*
Y984318D03*
X1177283Y1021129D03*
Y1024475D03*
Y1031168D03*
Y1044554D03*
Y1037861D03*
Y1051247D03*
Y1071326D03*
Y1064633D03*
Y1078018D03*
Y1094752D03*
Y1088059D03*
Y1081366D03*
Y1144948D03*
Y1138255D03*
Y1161680D03*
Y1154988D03*
Y1151641D03*
Y1168373D03*
Y1218570D03*
Y1211877D03*
Y1225263D03*
X1177250Y1241995D03*
X1177283Y1235302D03*
Y1228609D03*
X1220441Y883924D03*
Y890617D03*
Y897310D03*
Y900656D03*
Y914042D03*
Y907349D03*
Y1185105D03*
Y1178412D03*
Y1191798D03*
Y1208530D03*
Y1201837D03*
Y1195144D03*
X1236583Y880577D03*
Y887270D03*
Y897310D03*
Y893963D03*
Y910696D03*
Y904003D03*
Y1175066D03*
Y1181759D03*
Y1191798D03*
Y1188452D03*
Y1205184D03*
Y1198491D03*
X1325020Y899445D03*
Y893036D03*
X1326871Y889832D03*
X1330571D03*
X1323171Y896240D03*
X1330571D03*
X1326871D03*
X1325020Y912262D03*
X1326871Y909057D03*
X1330571D03*
X1326871Y902649D03*
X1330571D03*
X1323171Y915466D03*
X1330571D03*
X1326871D03*
X1325021Y931488D03*
X1326871Y928283D03*
X1330571D03*
Y921875D03*
X1326871D03*
X1325020Y918670D03*
X1326871Y941100D03*
X1325020Y937896D03*
X1330571Y941100D03*
X1323171Y934691D03*
X1330571D03*
X1326871D03*
Y947509D03*
X1330571D03*
X1325020Y950713D03*
X1326871Y960326D03*
X1325020Y957122D03*
X1330571Y960326D03*
X1326871Y966735D03*
X1330571D03*
X1326871Y953917D03*
X1330571D03*
X1323172D03*
X1326871Y979552D03*
X1330571D03*
X1325020Y976347D03*
X1323171Y973143D03*
X1325020Y969939D03*
X1323603Y1006093D03*
X1325453Y1002888D03*
X1327303Y999684D03*
X1331003D03*
X1327303Y1012501D03*
X1325453Y1009297D03*
X1331003Y1012501D03*
X1327304Y1031727D03*
X1325453Y1028523D03*
X1331003Y1031727D03*
X1325453Y1022114D03*
X1327303Y1018910D03*
X1331003D03*
X1323603Y1025318D03*
X1331004D03*
X1327304D03*
X1325453Y1047749D03*
Y1041340D03*
X1327303Y1038136D03*
X1331003D03*
X1323603Y1044544D03*
X1331003D03*
X1327303D03*
X1325453Y1060565D03*
X1327303Y1057361D03*
X1331003D03*
X1323603Y1063770D03*
X1327303D03*
X1331003D03*
X1327303Y1050952D03*
X1331003D03*
Y1070178D03*
X1327304D03*
X1325453Y1066974D03*
Y1079791D03*
X1327303Y1076587D03*
X1331003D03*
X1327303Y1089404D03*
X1325453Y1086200D03*
X1331003Y1089404D03*
X1323603Y1082995D03*
X1331003D03*
X1327303D03*
X1329153Y1124651D03*
X1331003Y1127856D03*
X1332420Y899445D03*
Y893036D03*
X1334271Y896240D03*
X1332420Y912262D03*
X1334271Y915466D03*
X1332420Y931488D03*
Y918670D03*
Y937896D03*
X1334271Y934691D03*
X1332420Y950713D03*
Y957122D03*
X1334271Y953917D03*
X1336120Y982756D03*
X1343520D03*
X1339820D03*
X1347220D03*
X1345371Y979552D03*
X1343520Y976347D03*
X1337971Y979552D03*
X1339820Y976347D03*
X1332420D03*
Y969939D03*
X1334271Y973143D03*
X1334704Y1006093D03*
X1332853Y1002888D03*
Y1009297D03*
Y1028523D03*
Y1022114D03*
X1334704Y1025318D03*
X1332853Y1047749D03*
Y1041340D03*
X1334704Y1044544D03*
X1332853Y1060565D03*
X1334704Y1063770D03*
X1332853Y1066974D03*
Y1079791D03*
Y1086200D03*
X1334704Y1082995D03*
X1334703Y1121447D03*
X1336554Y1124651D03*
X1340253D03*
X1343953D03*
X1347653D03*
X1332854D03*
X1338404Y1127856D03*
X1342104Y1121447D03*
X1345804Y1127856D03*
X1352561Y198148D03*
X1355771Y196298D03*
X1355765Y199999D03*
Y203699D03*
X1351353Y1124651D03*
X1355053D03*
X1358753D03*
X1362453D03*
X1349504Y1121447D03*
X1353204Y1127856D03*
X1356904Y1121447D03*
X1360604Y1127856D03*
X1366153Y1124651D03*
X1371704Y1121447D03*
X1373553Y1124651D03*
X1377253D03*
X1368004Y1127856D03*
X1369853Y1124651D03*
X1375404Y1127856D03*
X1379104Y1121447D03*
X1364304D03*
X1393471Y883423D03*
X1391620Y880219D03*
X1389771Y883423D03*
X1395320Y886627D03*
X1380953Y1124651D03*
X1384653D03*
X1382804Y1127856D03*
X1386504Y1121447D03*
X1408271Y883423D03*
X1406420Y880219D03*
X1400871Y883423D03*
X1399020Y880219D03*
X1404571Y883423D03*
X1397171D03*
X1411971D03*
X1410120Y886627D03*
X1402720D03*
X1428621Y880219D03*
X1423071Y883423D03*
X1421220Y880219D03*
X1415671Y883423D03*
X1413820Y880219D03*
X1426771Y883423D03*
X1419371D03*
X1424920Y886627D03*
X1417520D03*
X1445271Y883423D03*
X1443420Y880219D03*
X1437871Y883423D03*
X1436020Y880219D03*
X1430471Y883423D03*
X1441571D03*
X1434171D03*
X1439720Y886627D03*
X1432320D03*
X1447120D03*
X1460504Y1121447D03*
X1456804Y1127856D03*
X1453104Y1121447D03*
X1449404Y1127856D03*
X1445704Y1121447D03*
X1458653Y1124651D03*
X1454953D03*
X1451253D03*
X1447553D03*
X1464204Y1127856D03*
X1475304Y1121447D03*
X1471604Y1127856D03*
X1467904Y1121447D03*
X1466053Y1124651D03*
X1462353D03*
X1477153D03*
X1473453D03*
X1469753D03*
X1493804Y1006093D03*
X1490104D03*
X1486404D03*
X1493804Y1012501D03*
X1490104D03*
X1488253Y1009297D03*
X1493804Y1127856D03*
X1490104Y1121447D03*
X1486404Y1127856D03*
X1482704Y1121447D03*
X1479004Y1127856D03*
X1491953Y1124651D03*
X1488253D03*
X1484553D03*
X1480853D03*
X1502621Y899445D03*
X1506320D03*
X1506321Y912262D03*
X1508171Y909057D03*
X1500771Y902649D03*
X1508171D03*
X1502621Y912262D03*
X1500771Y909057D03*
X1502621Y905853D03*
X1510021D03*
X1498920D03*
X1506321D03*
X1502621Y931488D03*
X1500771Y928283D03*
X1506321Y931488D03*
X1508171Y928283D03*
X1500771Y921875D03*
X1502621Y918670D03*
X1508171Y921875D03*
X1506321Y918670D03*
X1502621Y925079D03*
X1510021D03*
X1498920D03*
X1506321D03*
X1500771Y941100D03*
X1502621Y937896D03*
X1508171Y941100D03*
X1506321Y937896D03*
X1500771Y947509D03*
X1508171D03*
X1510021Y944304D03*
X1502621D03*
X1506320D03*
X1498920D03*
X1500771Y966735D03*
X1508171D03*
X1498920Y963530D03*
X1502621Y950713D03*
X1506320D03*
X1508171Y960326D03*
X1506320Y957122D03*
X1500771Y960326D03*
X1502621Y957122D03*
X1510021Y963530D03*
X1502621Y969939D03*
X1506321D03*
X1497504Y1006093D03*
X1501204Y1012501D03*
X1508603D03*
X1503053Y1009297D03*
X1506753D03*
X1495653D03*
X1499353Y1015705D03*
X1510453D03*
X1501204Y1031727D03*
X1503053Y1028523D03*
X1508603Y1031727D03*
X1506753Y1028523D03*
Y1022114D03*
X1508603Y1018910D03*
X1503053Y1022114D03*
X1501204Y1018910D03*
X1503053Y1041340D03*
X1501204Y1038136D03*
X1506753Y1041340D03*
X1508603Y1038136D03*
X1503053Y1047749D03*
X1506753D03*
X1503053Y1034931D03*
X1510453D03*
X1499353D03*
X1506753D03*
X1503053Y1060565D03*
X1501204Y1057361D03*
X1506753Y1060565D03*
X1508604Y1057361D03*
X1501203Y1050952D03*
X1508604Y1050953D03*
X1499353Y1054157D03*
X1510453D03*
X1503053D03*
X1506753D03*
Y1079791D03*
X1508604Y1076587D03*
X1501204Y1070178D03*
X1503053Y1066974D03*
X1508604Y1070178D03*
X1506753Y1066974D03*
X1503053Y1079791D03*
X1501204Y1076587D03*
X1499353Y1073383D03*
X1510453D03*
X1503053D03*
X1506753D03*
X1497504Y1095813D03*
X1508603D03*
X1501204D03*
Y1089404D03*
X1503053Y1086200D03*
X1508604Y1089404D03*
X1506753Y1086200D03*
X1503053Y1092608D03*
X1510452D03*
X1499353D03*
X1506753D03*
Y1099017D03*
X1503053Y1124651D03*
X1497504Y1121447D03*
X1501204Y1127856D03*
X1499353Y1124651D03*
X1495653D03*
X1515571Y883423D03*
X1513720Y880219D03*
X1519271Y883423D03*
X1521121Y880219D03*
X1513720Y873810D03*
X1515571Y870606D03*
X1521121Y873810D03*
X1519271Y870606D03*
X1515570Y877014D03*
X1522970D03*
X1511871D03*
X1519271D03*
X1596941Y883924D03*
Y890617D03*
Y897310D03*
Y900656D03*
Y914042D03*
Y907349D03*
Y1185105D03*
Y1178412D03*
Y1191798D03*
Y1208530D03*
Y1201837D03*
Y1195144D03*
X1613083Y880577D03*
Y887270D03*
Y897310D03*
Y893963D03*
Y910696D03*
Y904003D03*
Y1175066D03*
Y1181759D03*
Y1191798D03*
Y1188451D03*
Y1205184D03*
Y1198491D03*
X1656441Y816995D03*
Y810302D03*
Y833727D03*
Y823688D03*
Y827034D03*
Y847113D03*
Y840420D03*
Y853806D03*
Y860499D03*
Y863845D03*
Y877231D03*
Y870538D03*
Y927428D03*
Y920735D03*
Y934121D03*
Y944160D03*
Y937467D03*
Y950853D03*
Y980971D03*
Y974278D03*
Y967585D03*
Y994357D03*
Y987664D03*
X1656141Y1027822D03*
X1656441Y1021129D03*
X1656141Y1047900D03*
Y1041207D03*
Y1034514D03*
Y1054593D03*
X1656441Y1074672D03*
Y1067979D03*
Y1091404D03*
Y1081365D03*
Y1084711D03*
Y1098097D03*
Y1141601D03*
Y1148294D03*
Y1154987D03*
Y1158333D03*
Y1171719D03*
Y1165026D03*
Y1221916D03*
Y1215223D03*
Y1238648D03*
Y1228609D03*
Y1231955D03*
Y1245341D03*
X1672583Y813648D03*
Y806955D03*
Y820341D03*
Y830381D03*
Y823688D03*
Y850459D03*
Y843766D03*
Y837074D03*
Y867192D03*
Y860499D03*
Y857152D03*
Y873885D03*
Y917389D03*
Y924081D03*
Y934121D03*
Y930774D03*
Y947507D03*
Y940814D03*
Y964239D03*
Y977625D03*
Y970932D03*
Y991011D03*
Y984318D03*
Y1021129D03*
Y1024475D03*
Y1031168D03*
X1672283Y1044554D03*
Y1037861D03*
X1672583Y1051247D03*
Y1071325D03*
Y1064633D03*
Y1078018D03*
Y1094751D03*
Y1088058D03*
Y1081365D03*
Y1144947D03*
Y1138255D03*
Y1161680D03*
Y1154987D03*
Y1151640D03*
Y1168373D03*
Y1218569D03*
Y1211877D03*
Y1225262D03*
Y1241995D03*
Y1235302D03*
Y1228609D03*
X1686141Y967585D03*
Y1054593D03*
X1702283Y964239D03*
Y1021129D03*
Y1024475D03*
Y1051247D03*
G54D48*
X676508Y145866D03*
G54D35*
X238780Y1643661D03*
X230906Y1649173D03*
X238780Y1653110D03*
Y1657834D03*
X230906Y1653897D03*
Y1663346D03*
X238780Y1667283D03*
Y1672007D03*
Y1681456D03*
X230906Y1668070D03*
Y1677519D03*
Y1682244D03*
X238780Y1686180D03*
Y1695629D03*
X230906Y1691692D03*
Y1696417D03*
X238780Y1700354D03*
Y1709803D03*
Y1714527D03*
X230906Y1705866D03*
Y1710590D03*
X238780Y1723976D03*
Y1728700D03*
X230906Y1720039D03*
Y1724763D03*
Y1734212D03*
X254528Y1643661D03*
X246654Y1649173D03*
X254528Y1653110D03*
Y1657834D03*
X246654Y1653897D03*
Y1663346D03*
X254528Y1667283D03*
Y1672007D03*
Y1681456D03*
X246654Y1668070D03*
Y1677519D03*
Y1682244D03*
X254528Y1686180D03*
Y1695629D03*
X246654Y1691692D03*
Y1696417D03*
X254528Y1700354D03*
Y1709803D03*
Y1714527D03*
X246654Y1705866D03*
Y1710590D03*
X254528Y1723976D03*
Y1728700D03*
X246654Y1720039D03*
Y1724763D03*
Y1734212D03*
X270276Y1643661D03*
X262402Y1649173D03*
X270276Y1653110D03*
Y1657834D03*
X262402Y1653897D03*
Y1663346D03*
X270276Y1667283D03*
Y1672007D03*
Y1681456D03*
X262402Y1668070D03*
Y1677519D03*
Y1682244D03*
X270276Y1686180D03*
Y1695629D03*
X262402Y1691692D03*
Y1696417D03*
X270276Y1700354D03*
Y1709803D03*
Y1714527D03*
X262402Y1705866D03*
Y1710590D03*
X270276Y1723976D03*
Y1728700D03*
X262402Y1720039D03*
Y1724763D03*
Y1734212D03*
X286024Y1643661D03*
X278150Y1649173D03*
X286024Y1653110D03*
Y1657834D03*
X278150Y1653897D03*
Y1663346D03*
X286024Y1667283D03*
Y1672007D03*
Y1681456D03*
X278150Y1668070D03*
Y1677519D03*
Y1682244D03*
X286024Y1686180D03*
Y1695629D03*
X278150Y1691692D03*
Y1696417D03*
X286024Y1700354D03*
Y1709803D03*
Y1714527D03*
X278150Y1705866D03*
Y1710590D03*
X286024Y1723976D03*
Y1728700D03*
X278150Y1720039D03*
Y1724763D03*
Y1734212D03*
X305709Y1672007D03*
X297835Y1677519D03*
Y1682244D03*
X305709Y1681456D03*
Y1686180D03*
X297835Y1691692D03*
Y1696417D03*
X305709Y1695629D03*
Y1700354D03*
X297835Y1705866D03*
Y1710590D03*
X305709Y1709803D03*
Y1714527D03*
X297835Y1720039D03*
Y1724763D03*
X305709Y1723976D03*
Y1728700D03*
X297835Y1734212D03*
X321457Y1672007D03*
X313583Y1677519D03*
Y1682244D03*
X321457Y1681456D03*
Y1686180D03*
X313583Y1691692D03*
Y1696417D03*
X321457Y1695629D03*
Y1700354D03*
X313583Y1705866D03*
Y1710590D03*
X321457Y1709803D03*
Y1714527D03*
X313583Y1720039D03*
Y1724763D03*
X321457Y1723976D03*
Y1728700D03*
X313583Y1734212D03*
X337205Y1672007D03*
X329331Y1677519D03*
Y1682244D03*
X337205Y1681456D03*
Y1686180D03*
X329331Y1691692D03*
Y1696417D03*
X337205Y1695629D03*
Y1700354D03*
X329331Y1705866D03*
Y1710590D03*
X337205Y1709803D03*
Y1714527D03*
X329331Y1720039D03*
Y1724763D03*
X337205Y1723976D03*
Y1728700D03*
X329331Y1734212D03*
X352953Y1672007D03*
X345079Y1677519D03*
Y1682244D03*
X352953Y1681456D03*
Y1686180D03*
X345079Y1691692D03*
Y1696417D03*
X352953Y1695629D03*
Y1700354D03*
X345079Y1705866D03*
Y1710590D03*
X352953Y1709803D03*
Y1714527D03*
X345079Y1720039D03*
Y1724763D03*
X352953Y1723976D03*
Y1728700D03*
X345079Y1734212D03*
X495079Y1677519D03*
Y1682244D03*
Y1691692D03*
Y1696417D03*
Y1705866D03*
Y1710590D03*
Y1720039D03*
Y1724763D03*
Y1734212D03*
X502953Y1672007D03*
X510827Y1677519D03*
X502953Y1681456D03*
X510827Y1682244D03*
X502953Y1686180D03*
X510827Y1691692D03*
X502953Y1695629D03*
X510827Y1696417D03*
X502953Y1700354D03*
X510827Y1705866D03*
X502953Y1709803D03*
X510827Y1710590D03*
X502953Y1714527D03*
X510827Y1720039D03*
X502953Y1723976D03*
X510827Y1724763D03*
X502953Y1728700D03*
X510827Y1734212D03*
X518701Y1672007D03*
X534449D03*
X526575Y1677519D03*
X518701Y1681456D03*
X526575Y1682244D03*
X534449Y1681456D03*
X518701Y1686180D03*
X534449D03*
X526575Y1691692D03*
X518701Y1695629D03*
X526575Y1696417D03*
X534449Y1695629D03*
X518701Y1700354D03*
X534449D03*
X526575Y1705866D03*
X518701Y1709803D03*
X526575Y1710590D03*
X534449Y1709803D03*
X518701Y1714527D03*
X534449D03*
X526575Y1720039D03*
X518701Y1723976D03*
X526575Y1724763D03*
X534449Y1723976D03*
X518701Y1728700D03*
X534449D03*
X526575Y1734212D03*
X550197Y1672007D03*
X542323Y1677519D03*
Y1682244D03*
X550197Y1681456D03*
Y1686180D03*
X542323Y1691692D03*
Y1696417D03*
X550197Y1695629D03*
Y1700354D03*
X542323Y1705866D03*
Y1710590D03*
X550197Y1709803D03*
Y1714527D03*
X542323Y1720039D03*
Y1724763D03*
X550197Y1723976D03*
Y1728700D03*
X542323Y1734212D03*
X562008Y1677519D03*
Y1682244D03*
Y1691692D03*
Y1696417D03*
Y1705866D03*
Y1710590D03*
Y1720039D03*
Y1724763D03*
Y1734212D03*
X569882Y1672007D03*
X577756Y1677519D03*
X569882Y1681456D03*
X577756Y1682244D03*
X569882Y1686180D03*
X577756Y1691692D03*
X569882Y1695629D03*
X577756Y1696417D03*
X569882Y1700354D03*
X577756Y1705866D03*
X569882Y1709803D03*
X577756Y1710590D03*
X569882Y1714527D03*
X577756Y1720039D03*
X569882Y1723976D03*
X577756Y1724763D03*
X569882Y1728700D03*
X577756Y1734212D03*
X585630Y1672007D03*
X593504Y1677519D03*
X585630Y1681456D03*
X593504Y1682244D03*
X585630Y1686180D03*
X593504Y1691692D03*
X585630Y1695629D03*
X593504Y1696417D03*
X585630Y1700354D03*
X593504Y1705866D03*
X585630Y1709803D03*
X593504Y1710590D03*
X585630Y1714527D03*
X593504Y1720039D03*
X585630Y1723976D03*
X593504Y1724763D03*
X585630Y1728700D03*
X593504Y1734212D03*
X601378Y1672007D03*
X609252Y1677519D03*
X601378Y1681456D03*
X609252Y1682244D03*
X601378Y1686180D03*
X609252Y1691692D03*
X601378Y1695629D03*
X609252Y1696417D03*
X601378Y1700354D03*
X609252Y1705866D03*
X601378Y1709803D03*
X609252Y1710590D03*
X601378Y1714527D03*
X609252Y1720039D03*
X601378Y1723976D03*
X609252Y1724763D03*
X601378Y1728700D03*
X609252Y1734212D03*
X617126Y1672007D03*
Y1681456D03*
Y1686180D03*
Y1695629D03*
Y1700354D03*
Y1709803D03*
Y1714527D03*
Y1723976D03*
Y1728700D03*
X1246654Y1672007D03*
X1238780Y1677519D03*
Y1682244D03*
X1246654Y1681456D03*
Y1686180D03*
X1238780Y1691692D03*
Y1696417D03*
X1246654Y1695629D03*
Y1700354D03*
X1238780Y1705866D03*
Y1710590D03*
X1246654Y1709803D03*
Y1714527D03*
X1238780Y1720039D03*
Y1724763D03*
X1246654Y1723976D03*
Y1728700D03*
X1238780Y1734212D03*
X1262402Y1672007D03*
X1254528Y1677519D03*
Y1682244D03*
X1262402Y1681456D03*
Y1686180D03*
X1254528Y1691692D03*
Y1696417D03*
X1262402Y1695629D03*
Y1700354D03*
X1254528Y1705866D03*
Y1710590D03*
X1262402Y1709803D03*
Y1714527D03*
X1254528Y1720039D03*
Y1724763D03*
X1262402Y1723976D03*
Y1728700D03*
X1254528Y1734212D03*
X1278150Y1672007D03*
X1270276Y1677519D03*
Y1682244D03*
X1278150Y1681456D03*
Y1686180D03*
X1270276Y1691692D03*
Y1696417D03*
X1278150Y1695629D03*
Y1700354D03*
X1270276Y1705866D03*
Y1710590D03*
X1278150Y1709803D03*
Y1714527D03*
X1270276Y1720039D03*
Y1724763D03*
X1278150Y1723976D03*
Y1728700D03*
X1270276Y1734212D03*
X1293898Y1672007D03*
X1286024Y1677519D03*
Y1682244D03*
X1293898Y1681456D03*
Y1686180D03*
X1286024Y1691692D03*
Y1696417D03*
X1293898Y1695629D03*
Y1700354D03*
X1286024Y1705866D03*
Y1710590D03*
X1293898Y1709803D03*
Y1714527D03*
X1286024Y1720039D03*
Y1724763D03*
X1293898Y1723976D03*
Y1728700D03*
X1286024Y1734212D03*
X1313583Y1672007D03*
X1305709Y1677519D03*
Y1682244D03*
X1313583Y1681456D03*
Y1686180D03*
X1305709Y1691692D03*
Y1696417D03*
X1313583Y1695629D03*
Y1700354D03*
X1305709Y1705866D03*
Y1710590D03*
X1313583Y1709803D03*
Y1714527D03*
X1305709Y1720039D03*
Y1724763D03*
X1313583Y1723976D03*
Y1728700D03*
X1305709Y1734212D03*
X1329331Y1672007D03*
X1321457Y1677519D03*
Y1682244D03*
X1329331Y1681456D03*
Y1686180D03*
X1321457Y1691692D03*
Y1696417D03*
X1329331Y1695629D03*
Y1700354D03*
X1321457Y1705866D03*
Y1710590D03*
X1329331Y1709803D03*
Y1714527D03*
X1321457Y1720039D03*
Y1724763D03*
X1329331Y1723976D03*
Y1728700D03*
X1321457Y1734212D03*
X1345079Y1672007D03*
X1337205Y1677519D03*
Y1682244D03*
X1345079Y1681456D03*
Y1686180D03*
X1337205Y1691692D03*
Y1696417D03*
X1345079Y1695629D03*
Y1700354D03*
X1337205Y1705866D03*
Y1710590D03*
X1345079Y1709803D03*
Y1714527D03*
X1337205Y1720039D03*
Y1724763D03*
X1345079Y1723976D03*
Y1728700D03*
X1337205Y1734212D03*
X1360827Y1672007D03*
X1352953Y1677519D03*
Y1682244D03*
X1360827Y1681456D03*
Y1686180D03*
X1352953Y1691692D03*
Y1696417D03*
X1360827Y1695629D03*
Y1700354D03*
X1352953Y1705866D03*
Y1710590D03*
X1360827Y1709803D03*
Y1714527D03*
X1352953Y1720039D03*
Y1724763D03*
X1360827Y1723976D03*
Y1728700D03*
X1352953Y1734212D03*
X1510827Y1672007D03*
X1502953Y1677519D03*
Y1682244D03*
X1510827Y1681456D03*
Y1686180D03*
X1502953Y1691692D03*
Y1696417D03*
X1510827Y1695629D03*
Y1700354D03*
X1502953Y1705866D03*
Y1710590D03*
X1510827Y1709803D03*
Y1714527D03*
X1502953Y1720039D03*
Y1724763D03*
X1510827Y1723976D03*
Y1728700D03*
X1502953Y1734212D03*
X1526575Y1672007D03*
X1518701Y1677519D03*
Y1682244D03*
X1526575Y1681456D03*
Y1686180D03*
X1518701Y1691692D03*
Y1696417D03*
X1526575Y1695629D03*
Y1700354D03*
X1518701Y1705866D03*
Y1710590D03*
X1526575Y1709803D03*
Y1714527D03*
X1518701Y1720039D03*
Y1724763D03*
X1526575Y1723976D03*
Y1728700D03*
X1518701Y1734212D03*
X1542323Y1672007D03*
X1534449Y1677519D03*
Y1682244D03*
X1542323Y1681456D03*
Y1686180D03*
X1534449Y1691692D03*
Y1696417D03*
X1542323Y1695629D03*
Y1700354D03*
X1534449Y1705866D03*
Y1710590D03*
X1542323Y1709803D03*
Y1714527D03*
X1534449Y1720039D03*
Y1724763D03*
X1542323Y1723976D03*
Y1728700D03*
X1534449Y1734212D03*
X1558071Y1672007D03*
X1550197Y1677519D03*
Y1682244D03*
X1558071Y1681456D03*
Y1686180D03*
X1550197Y1691692D03*
Y1696417D03*
X1558071Y1695629D03*
Y1700354D03*
X1550197Y1705866D03*
Y1710590D03*
X1558071Y1709803D03*
Y1714527D03*
X1550197Y1720039D03*
Y1724763D03*
X1558071Y1723976D03*
Y1728700D03*
X1550197Y1734212D03*
X1569882Y1677519D03*
Y1682244D03*
Y1691692D03*
Y1696417D03*
Y1705866D03*
Y1710590D03*
Y1720039D03*
Y1724763D03*
Y1734212D03*
X1577756Y1672007D03*
X1585630Y1677519D03*
X1577756Y1681456D03*
X1585630Y1682244D03*
X1577756Y1686180D03*
X1585630Y1691692D03*
X1577756Y1695629D03*
X1585630Y1696417D03*
X1577756Y1700354D03*
X1585630Y1705866D03*
X1577756Y1709803D03*
X1585630Y1710590D03*
X1577756Y1714527D03*
X1585630Y1720039D03*
X1577756Y1723976D03*
X1585630Y1724763D03*
X1577756Y1728700D03*
X1585630Y1734212D03*
X1593504Y1672007D03*
X1601378Y1677519D03*
X1593504Y1681456D03*
X1601378Y1682244D03*
X1593504Y1686180D03*
X1601378Y1691692D03*
X1593504Y1695629D03*
X1601378Y1696417D03*
X1593504Y1700354D03*
X1601378Y1705866D03*
X1593504Y1709803D03*
X1601378Y1710590D03*
X1593504Y1714527D03*
X1601378Y1720039D03*
X1593504Y1723976D03*
X1601378Y1724763D03*
X1593504Y1728700D03*
X1601378Y1734212D03*
X1609252Y1672007D03*
X1617126Y1677519D03*
X1609252Y1681456D03*
X1617126Y1682244D03*
X1609252Y1686180D03*
X1617126Y1691692D03*
X1609252Y1695629D03*
X1617126Y1696417D03*
X1609252Y1700354D03*
X1617126Y1705866D03*
X1609252Y1709803D03*
X1617126Y1710590D03*
X1609252Y1714527D03*
X1617126Y1720039D03*
X1609252Y1723976D03*
X1617126Y1724763D03*
X1609252Y1728700D03*
X1617126Y1734212D03*
X1625000Y1672007D03*
Y1681456D03*
Y1686180D03*
Y1695629D03*
Y1700354D03*
Y1709803D03*
Y1714527D03*
Y1723976D03*
Y1728700D03*
G54D75*
X1886720Y1001463D03*
X1876720D03*
X1875836Y1303980D03*
X1885836D03*
X1886211Y1364167D03*
X1876211D03*
X1876165Y1669023D03*
X1886165D03*
X1897608Y1001506D03*
X1898086Y1305044D03*
X1897682Y1364479D03*
X1897402Y1670072D03*
X1907608Y1001506D03*
X1908086Y1305044D03*
X1907682Y1364479D03*
X1907402Y1670072D03*
X1935200Y1362732D03*
X1925200D03*
X1924695Y1670036D03*
X1934695D03*
X1946178Y1362781D03*
X1945484Y1670313D03*
X1967697Y1362790D03*
X1956178Y1362781D03*
X1966555Y1669946D03*
X1955484Y1670313D03*
X1977697Y1362790D03*
X1976555Y1669946D03*
X1988618Y1363081D03*
X1998618D03*
X1998147Y1669691D03*
X1988147D03*
G54D22*
X45812Y451602D03*
X61157Y69340D03*
X49212Y451602D03*
X64557Y69340D03*
X72157Y75340D03*
X75557D03*
X64410Y1599102D03*
Y1602502D03*
X86557Y69340D03*
X83157D03*
X94157Y75340D03*
X108557Y69340D03*
X105157D03*
X97557Y75340D03*
X127157Y69340D03*
X116157Y75340D03*
X119557D03*
X130557Y69340D03*
X138157Y75340D03*
X141557D03*
X152557Y69340D03*
X149157D03*
X175761D03*
X172361D03*
X161361Y75340D03*
X164761D03*
X183361D03*
X186761D03*
X197761Y69340D03*
X194361D03*
X205495Y75340D03*
X208895D03*
X194197Y1602380D03*
X197597D03*
X206257D03*
X219895Y69340D03*
X216495D03*
X209657Y1602380D03*
X218317D03*
X221717D03*
X227495Y75340D03*
X230895D03*
X230377Y1602380D03*
X233777D03*
X242437D03*
X254497D03*
X245837D03*
X266557D03*
X257897D03*
X269957D03*
X278617D03*
X282017D03*
X290677D03*
X302737D03*
X294077D03*
X306137D03*
X314797D03*
X318197D03*
X330257D03*
X338917D03*
X326857D03*
X350977D03*
X342317D03*
X354377D03*
X363037D03*
X366437D03*
X375097D03*
X378497D03*
X478351D03*
X481751D03*
X490411D03*
X493811D03*
X514531D03*
X502471D03*
X517931D03*
X505871D03*
X526591D03*
X529991D03*
X538651D03*
X542051D03*
X562771D03*
X550711D03*
X566171D03*
X554111D03*
X574831D03*
X578231D03*
X598951D03*
X586891D03*
X590291D03*
X611011D03*
X614411D03*
X602351D03*
X623071D03*
X626471D03*
X647191D03*
X635131D03*
X638531D03*
X662651D03*
X659251D03*
X650591D03*
X723041Y-19800D03*
Y-23200D03*
X840001Y6800D03*
Y10200D03*
X980899Y-19800D03*
Y-23200D03*
Y6800D03*
Y10200D03*
X1032433Y-29811D03*
Y-33211D03*
Y-13211D03*
Y-9811D03*
Y-3211D03*
Y189D03*
X1156770Y638192D03*
X1153370D03*
X1161860Y642112D03*
X1165260D03*
X1173220Y636052D03*
X1169820D03*
X1183360Y642062D03*
X1186760D03*
X1196772Y1578182D03*
X1200172D03*
X1212232D03*
X1208832D03*
X1220892D03*
X1232952D03*
X1224292D03*
X1245012D03*
X1236352D03*
X1248412D03*
X1257072D03*
X1260472D03*
X1269132D03*
X1281192D03*
X1272532D03*
X1290291Y-29811D03*
Y-33211D03*
Y-13211D03*
Y-9811D03*
Y-3211D03*
Y189D03*
X1293252Y1578182D03*
X1284592D03*
X1296652D03*
X1307677Y322996D03*
X1311077D03*
X1305312Y1578182D03*
X1308712D03*
X1319618Y318073D03*
X1325080Y323902D03*
X1316218Y318073D03*
X1328480Y323902D03*
X1317372Y1578182D03*
X1320772D03*
X1329432D03*
X1341752Y-29811D03*
Y-33211D03*
Y-9811D03*
Y-13211D03*
Y189D03*
Y-3211D03*
X1335145Y332616D03*
X1341431Y322693D03*
X1331745Y332616D03*
X1338031Y322693D03*
X1345424Y328981D03*
X1332832Y1578182D03*
X1341492D03*
X1344892D03*
X1348824Y328981D03*
X1358371Y332275D03*
X1361771D03*
X1355200Y337843D03*
X1351800D03*
X1353552Y1578182D03*
X1356952D03*
X1365612D03*
X1377672D03*
X1369012D03*
X1381072D03*
X1407420Y220018D03*
X1410820D03*
X1404385Y240929D03*
X1400985D03*
X1467595Y1602380D03*
X1470995D03*
X1482650Y-29811D03*
Y-33211D03*
Y-9811D03*
Y-13211D03*
Y189D03*
Y-3211D03*
X1491715Y1602380D03*
X1479655D03*
X1483055D03*
X1503775D03*
X1507175D03*
X1495115D03*
X1515835D03*
X1519235D03*
X1538996Y69297D03*
X1535596D03*
X1527895Y1602380D03*
X1539955D03*
X1531295D03*
X1557596Y69297D03*
X1546596Y75297D03*
X1549996D03*
X1552015Y1602380D03*
X1555415D03*
X1543355D03*
X1560996Y69297D03*
X1568596Y75297D03*
X1571996D03*
X1564075Y1602380D03*
X1567475D03*
X1582996Y69297D03*
X1579596D03*
X1590596Y75297D03*
X1588195Y1602380D03*
X1576135D03*
X1591595D03*
X1579535D03*
X1604996Y69297D03*
X1601596D03*
X1593996Y75297D03*
X1600255Y1602380D03*
X1603655D03*
X1623596Y69297D03*
X1612596Y75297D03*
X1615996D03*
X1612315Y1602380D03*
X1615715D03*
X1626996Y69297D03*
X1635800Y75297D03*
X1639200D03*
X1636435Y1602380D03*
X1624375D03*
X1639835D03*
X1627775D03*
X1650200Y69297D03*
X1646800D03*
X1651895Y1602380D03*
X1648495D03*
X1672200Y69297D03*
X1668800D03*
X1657800Y75297D03*
X1661200D03*
X1679934D03*
X1683334D03*
X1694334Y69297D03*
X1690934D03*
X1705334Y75297D03*
X1701934D03*
G54D40*
X338042Y849978D03*
X337779Y880219D03*
X335928Y883423D03*
X337779Y893036D03*
X335928Y889832D03*
X334079Y886627D03*
X337779D03*
X331284Y978814D03*
X338211Y1118243D03*
X336361Y1121447D03*
X338211Y1131060D03*
X345178Y854584D03*
X350727Y851380D03*
X354427Y844971D03*
X348878Y848176D03*
X352578D03*
X348879Y860993D03*
X350729Y857789D03*
X352578Y860993D03*
X354429Y857789D03*
X341479Y880219D03*
X343329Y883423D03*
X350729Y870606D03*
X354429D03*
X352578Y873810D03*
X354429Y883423D03*
X348879Y873810D03*
X347029Y877014D03*
X348878Y880219D03*
X341478Y893036D03*
X343328Y889832D03*
X341479Y886627D03*
X345179D03*
X343761Y999684D03*
X349311Y1105426D03*
X341911D03*
X343762Y1108630D03*
X345611Y1111834D03*
X351161Y1102221D03*
X349312Y1111834D03*
X353011Y1105426D03*
X345611D03*
X341912Y1111834D03*
X354861Y1102221D03*
X353012Y1111834D03*
X351162Y1108630D03*
Y1127856D03*
X353011Y1118243D03*
X354861Y1121447D03*
X347461Y1115039D03*
X341912Y1118243D03*
X340061Y1127856D03*
X343761D03*
X347461Y1121447D03*
X340061D03*
X343761D03*
X347461Y1127856D03*
X345611Y1124651D03*
X349312Y1137469D03*
X351161Y1134264D03*
X347461D03*
X354861D03*
X341911Y1131060D03*
X356278Y848176D03*
X371078D03*
X363678D03*
X356279Y841467D03*
X361827Y844971D03*
X363679Y841467D03*
X369227Y844971D03*
X371079Y841467D03*
X358127Y844971D03*
X359978Y848176D03*
X365527Y844971D03*
X367378Y848176D03*
X371078Y867401D03*
X356278D03*
X363678D03*
X356278Y860993D03*
X371078D03*
X363678D03*
X356278Y854584D03*
X358129Y857789D03*
X363678Y854584D03*
X365529Y857789D03*
X371078Y854584D03*
X359978Y860993D03*
X361829Y857789D03*
X367378Y860993D03*
X369229Y857789D03*
X358129Y870606D03*
X361829D03*
X365529D03*
X359978Y873810D03*
X367378D03*
X369229Y870606D03*
X356278Y880219D03*
X358129Y883423D03*
X363678Y880219D03*
X365529Y883423D03*
X371078Y880219D03*
X361829Y883423D03*
X369229D03*
X371078Y873810D03*
X356278D03*
X363678D03*
Y899445D03*
X367378D03*
X371078Y893036D03*
X363679D03*
X367379D03*
X359978Y886627D03*
X367378D03*
X363678D03*
X371078D03*
X363678Y912262D03*
X361829Y909057D03*
X367378Y912262D03*
X369229Y909057D03*
X361829Y902649D03*
X369229D03*
X359978Y905853D03*
X367378D03*
X363678D03*
X371078D03*
X363678Y931488D03*
X361829Y928283D03*
X367378Y931488D03*
X369229Y928283D03*
X361829Y921875D03*
X363678Y918670D03*
X369229Y921875D03*
X367378Y918670D03*
X359978Y925079D03*
X367378D03*
X363678D03*
X371078D03*
X361829Y941100D03*
X363678Y937896D03*
X369229Y941100D03*
X367378Y937896D03*
X361829Y947509D03*
X369229D03*
X367378Y944304D03*
X359978D03*
X371078D03*
X363678D03*
X361829Y966735D03*
X369229D03*
X359978Y963530D03*
X363678Y950713D03*
X367378D03*
X361829Y960326D03*
X363678Y957122D03*
X369229Y960326D03*
X367378Y957122D03*
X371078Y963530D03*
X363678Y969939D03*
X367378D03*
X367811Y1002888D03*
X362262Y1012501D03*
X369662D03*
X364111Y1009297D03*
X367811D03*
X364111Y1002888D03*
X362262Y999684D03*
X371511Y1002888D03*
X369662Y999684D03*
X362262Y1031727D03*
X364111Y1028523D03*
X369662Y1031727D03*
X367811Y1028523D03*
X360411Y1015705D03*
X371511D03*
X364111Y1022114D03*
X362262Y1018910D03*
X367811Y1022114D03*
X369662Y1018910D03*
X364111Y1041340D03*
X362262Y1038136D03*
X367811Y1041340D03*
X369662Y1038136D03*
X360411Y1034931D03*
X371511D03*
X364111D03*
X367811D03*
X364111Y1047749D03*
X367811D03*
X364111Y1060565D03*
X362262Y1057361D03*
X367811Y1060565D03*
X369662Y1057361D03*
X362262Y1050952D03*
X369662D03*
X360411Y1054157D03*
X371511D03*
X364111D03*
X367811D03*
Y1079791D03*
X369662Y1076587D03*
X362262Y1070178D03*
X364111Y1066974D03*
X369662Y1070178D03*
X367811Y1066974D03*
X364111Y1079791D03*
X362262Y1076587D03*
X360411Y1073383D03*
X371511D03*
X364111D03*
X367811D03*
X362262Y1095813D03*
X369662D03*
X362262Y1089404D03*
X364111Y1086200D03*
X369662Y1089404D03*
X367811Y1086200D03*
X360411Y1092608D03*
X367811D03*
X364111D03*
X371511D03*
X364111Y1099017D03*
X367811D03*
Y1105426D03*
X369661Y1102221D03*
X358562D03*
X360412Y1105426D03*
X358561Y1108630D03*
X360412Y1111834D03*
X364112Y1105426D03*
X369661Y1108630D03*
X362261D03*
X365961D03*
X367812Y1111834D03*
X369662Y1121447D03*
X362261D03*
X365961Y1115039D03*
X358561D03*
X369661D03*
X358561Y1134264D03*
X362261Y1140973D03*
X365962Y1134264D03*
X369661Y1140973D03*
X356712Y1137469D03*
X360412D03*
X364112D03*
X367812D03*
X371512D03*
X369662Y1134264D03*
X362262D03*
X385878Y848176D03*
X378478D03*
X387727Y844971D03*
X376627D03*
X380327D03*
X384027D03*
X385879Y841467D03*
X372927Y844971D03*
X374778Y848176D03*
X378479Y841467D03*
X382178Y848176D03*
X378478Y867401D03*
X385878D03*
X378478Y860993D03*
X385878D03*
X387729Y857789D03*
X372929D03*
X378478Y854584D03*
X380329Y857789D03*
X384029D03*
X374778Y860993D03*
X376629Y857789D03*
X382178Y860993D03*
X385878Y854584D03*
X387729Y870606D03*
X372929D03*
X380329D03*
X374778Y873810D03*
X376629Y870606D03*
X382178Y873810D03*
X384029Y870606D03*
X372929Y883423D03*
X378478Y880219D03*
X380329Y883423D03*
X385878Y880219D03*
X387729Y883423D03*
X376629D03*
X384029D03*
X378478Y873810D03*
X385878D03*
X374778Y899445D03*
X382178D03*
Y893036D03*
X374778D03*
X385878D03*
X372929Y896240D03*
X380329D03*
X376629D03*
X384029D03*
X374778Y886627D03*
X382178D03*
X378478D03*
X385878D03*
X376629Y902649D03*
X380329D03*
X374778Y912262D03*
X376629Y909057D03*
X382178Y912262D03*
X380329Y909057D03*
X387729D03*
Y902649D03*
X372929Y915466D03*
X385878Y905853D03*
X380329Y915466D03*
X376629D03*
X384029D03*
X374778Y931488D03*
X376629Y928283D03*
X382178Y931488D03*
X380329Y928283D03*
X387729Y921875D03*
X376629D03*
X374778Y918670D03*
X380329Y921875D03*
X382178Y918670D03*
X387729Y928283D03*
X385878Y925079D03*
X380329Y941100D03*
X382178Y937896D03*
X376629Y947509D03*
X380329D03*
X376629Y941100D03*
X374778Y937896D03*
X372929Y934691D03*
X380329D03*
X376629D03*
X384029D03*
X387729Y947509D03*
Y941100D03*
X385878Y944304D03*
X376629Y960326D03*
X374778Y957122D03*
X380329Y960326D03*
X382178Y957122D03*
X374778Y950713D03*
X382178D03*
X372929Y953917D03*
X380329D03*
X376629D03*
X384029D03*
X387729Y960326D03*
Y966735D03*
X380329D03*
X376629D03*
X385878Y963530D03*
Y982756D03*
X387729Y979552D03*
X376629D03*
X380329D03*
X374778Y976347D03*
X382178D03*
X372929Y973143D03*
X374778Y969939D03*
X382178D03*
X384029Y973143D03*
X373362Y1006093D03*
X380762D03*
X377062D03*
X384462D03*
X375211Y1002888D03*
X377062Y999684D03*
X382611Y1002888D03*
X380762Y999684D03*
X377062Y1012501D03*
X375211Y1009297D03*
X380762Y1012501D03*
X382611Y1009297D03*
X377062Y1031727D03*
X375211Y1028523D03*
X380762Y1031727D03*
X382611Y1028523D03*
X375211Y1022114D03*
X377062Y1018910D03*
X382611Y1022114D03*
X380762Y1018910D03*
X377062Y1025318D03*
X384462D03*
X373360D03*
X380760D03*
X386311Y1015705D03*
X375211Y1047749D03*
X382611D03*
X375211Y1041340D03*
X377062Y1038136D03*
X382611Y1041340D03*
X380762Y1038136D03*
X373362Y1044544D03*
X380762D03*
X377062D03*
X384462D03*
X386311Y1034931D03*
X375211Y1060565D03*
X377062Y1057361D03*
X382611Y1060565D03*
X380762Y1057361D03*
X377062Y1050952D03*
X380762D03*
X373362Y1063770D03*
X384462D03*
X377062D03*
X380762D03*
X386311Y1054157D03*
X380762Y1070178D03*
X382611Y1066974D03*
X377062Y1070178D03*
X375211Y1066974D03*
Y1079791D03*
X377062Y1076587D03*
X382611Y1079791D03*
X380762Y1076587D03*
X386311Y1073383D03*
X377062Y1089404D03*
X375211Y1086200D03*
X380762Y1089404D03*
X382611Y1086200D03*
X373362Y1082995D03*
X386311Y1092608D03*
X384462Y1082995D03*
X377062D03*
X380762D03*
X375211Y1099017D03*
X380762Y1095813D03*
X382611Y1099017D03*
X386311Y1105426D03*
X382611Y1111834D03*
X375211Y1105426D03*
X377062Y1108630D03*
X380762Y1102221D03*
X378911Y1111834D03*
X384462Y1108630D03*
X386311Y1111834D03*
X378912Y1105426D03*
X375211Y1111834D03*
X382611Y1105426D03*
X384462Y1121447D03*
X377062D03*
X380762Y1115039D03*
X373362Y1134264D03*
X377061Y1140973D03*
X380762Y1134264D03*
X384461Y1140973D03*
X375212Y1137469D03*
X378912D03*
X382612D03*
X386312D03*
X384462Y1134264D03*
X377062D03*
X400678Y848176D03*
X393278D03*
X391427Y844971D03*
X395127D03*
X398827D03*
X400679Y841467D03*
X389578Y848176D03*
X393279Y841467D03*
X396978Y848176D03*
X402527Y844971D03*
X400678Y867401D03*
X393278D03*
X400678Y860993D03*
X393278D03*
Y854584D03*
X395129Y857789D03*
X400678Y854584D03*
X402529Y857789D03*
X389578Y860993D03*
X391429Y857789D03*
X396978Y860993D03*
X398829Y857789D03*
X391429Y870606D03*
X395129D03*
X402529D03*
X389578Y873810D03*
X396978D03*
X398829Y870606D03*
X393278Y880219D03*
X395129Y883423D03*
X400678Y880219D03*
X402529Y883423D03*
X391429D03*
X398829D03*
X393278Y873810D03*
X400678D03*
X402529Y896240D03*
X400678Y899445D03*
X389578D03*
X393278D03*
X393279Y893036D03*
X396979D03*
X396978Y886627D03*
X389578D03*
X398829Y896240D03*
X400678Y893036D03*
X393278Y886627D03*
X400678D03*
X404378Y899445D03*
X400678Y905853D03*
X402529Y915466D03*
Y909057D03*
X389578Y912262D03*
X393278D03*
X395129Y909057D03*
Y902649D03*
X393278Y905853D03*
X389578D03*
X396978D03*
X406229Y915466D03*
X400678Y912262D03*
X402529Y902649D03*
X400678Y931488D03*
X402529Y928283D03*
Y921875D03*
X393278Y931488D03*
X395129Y928283D03*
X389578Y918670D03*
X395129Y921875D03*
X393278Y918670D03*
X389578Y931488D03*
X393278Y925079D03*
X389578D03*
X396978D03*
X398829Y934691D03*
X402529D03*
X395129Y947509D03*
X389578Y937896D03*
X395129Y941100D03*
X393278Y937896D03*
Y944304D03*
X389578D03*
X396978D03*
X402529Y941100D03*
X400679Y944304D03*
X402529Y947509D03*
X389578Y957122D03*
X395129Y960326D03*
X393278Y957122D03*
X395129Y966735D03*
X389578Y950713D03*
X393278D03*
X396978Y963530D03*
X393278D03*
X389578D03*
X402529Y966735D03*
Y960326D03*
X398829Y953917D03*
X402529D03*
X400680Y950713D03*
X398829Y973143D03*
X400678Y976347D03*
X402529Y979552D03*
Y973143D03*
X393278Y982756D03*
X389578D03*
X396978D03*
X393278Y976347D03*
X395129Y979552D03*
X389579Y976347D03*
X389578Y969939D03*
X393278D03*
X399262Y1006093D03*
X402962D03*
X390011Y1002888D03*
X388162Y999684D03*
X393711Y1002888D03*
X395562Y999684D03*
X399262D03*
X402962D03*
X388162Y1012501D03*
X395562D03*
X390011Y1009297D03*
X393711D03*
X401111D03*
X402962Y1012501D03*
Y1031727D03*
X397411Y1015705D03*
X388162Y1031727D03*
X390011Y1028523D03*
X395562Y1031727D03*
X393711Y1028523D03*
X390011Y1022114D03*
X388162Y1018910D03*
X393711Y1022114D03*
X395562Y1018910D03*
X401111Y1028523D03*
Y1022114D03*
X402960Y1018910D03*
X402962Y1025318D03*
X399262D03*
X401111Y1015705D03*
X390011Y1041340D03*
X388162Y1038136D03*
X393711Y1041340D03*
X395562Y1038136D03*
X390011Y1047749D03*
X393711D03*
Y1034931D03*
X390011D03*
X397411D03*
X401111Y1047749D03*
X399262Y1044544D03*
X402962D03*
X401111Y1041340D03*
X402962Y1038136D03*
X406662Y1057361D03*
X390011Y1060565D03*
X388162Y1057361D03*
X393711Y1060565D03*
X395562Y1057361D03*
X388162Y1050952D03*
X395562D03*
X393711Y1054157D03*
X390011D03*
X397411D03*
X402962Y1057361D03*
Y1063770D03*
X401113Y1060565D03*
X399262Y1063770D03*
X401111Y1054157D03*
X402962Y1050952D03*
Y1076587D03*
Y1070178D03*
X390011Y1079791D03*
X388162Y1076587D03*
X393711Y1079791D03*
X395562Y1076587D03*
X388162Y1070178D03*
X390011Y1066974D03*
X395562Y1070178D03*
X393711Y1066974D03*
Y1073383D03*
X390011D03*
X397411D03*
X401112Y1066974D03*
X395562Y1095813D03*
X388162Y1089404D03*
X390011Y1086200D03*
X395562Y1089404D03*
X393711Y1086200D03*
X388162Y1095813D03*
X393711Y1092608D03*
X390011D03*
X397411D03*
X399262Y1082995D03*
X402962D03*
X402961Y1089404D03*
X393711Y1099017D03*
X390011D03*
X391862Y1102221D03*
X393711Y1105426D03*
X401111Y1099017D03*
X391862Y1108630D03*
X393711Y1111834D03*
X397411Y1105426D03*
X402962Y1108630D03*
Y1102221D03*
X395562Y1108630D03*
X399262D03*
X401111Y1111834D03*
X391862Y1121447D03*
X399262Y1115039D03*
X391862D03*
X402962D03*
X399262Y1121447D03*
X391861Y1140973D03*
X395562Y1134264D03*
X399261Y1140973D03*
X402962Y1134264D03*
X388162D03*
X390012Y1137469D03*
X393712D03*
X397412D03*
X401112D03*
X391862Y1134264D03*
X399262D03*
X408078Y848176D03*
X415478D03*
X406227Y844971D03*
X409927D03*
X413627D03*
X417327D03*
X404378Y848176D03*
X408079Y841467D03*
X411778Y848176D03*
X415479Y841467D03*
X419178Y848176D03*
X408078Y867401D03*
X415478D03*
Y860993D03*
X408078D03*
Y854584D03*
X409929Y857789D03*
X415478Y854584D03*
X417329Y857789D03*
X404378Y860993D03*
X406229Y857789D03*
X411778Y860993D03*
X413629Y857789D03*
X419178Y860993D03*
X404378Y873810D03*
X406229Y870606D03*
X408078Y880219D03*
X409929Y883423D03*
X406229D03*
X419178Y873810D03*
X417329Y870606D03*
X411778Y873810D03*
X413629Y870606D03*
X415478Y873810D03*
X408078D03*
X404378Y886627D03*
X411778D03*
X404378Y893036D03*
X415478Y886627D03*
X408078D03*
X406229Y896240D03*
X408078Y899445D03*
X415478D03*
X409929Y896240D03*
X415478Y893036D03*
X417329Y896240D03*
X422878Y893036D03*
X411778Y899445D03*
X413629Y896240D03*
X419178Y899445D03*
X422878Y912262D03*
X417329Y909057D03*
X406229D03*
X413629D03*
Y915466D03*
X411778Y905853D03*
X408078D03*
Y912262D03*
X406229Y902649D03*
X415478Y905853D03*
X411778Y912262D03*
X415478D03*
X417329Y915466D03*
X411779Y918670D03*
X406229Y921875D03*
X408078Y918670D03*
X408569Y929108D03*
X406308Y928626D03*
X417329Y921875D03*
X411872Y925264D03*
X415479Y918670D03*
X407589Y942164D03*
X405289D03*
X409889D03*
X415185Y956620D03*
X411685D03*
X409385D03*
X417685D03*
X404785Y971100D03*
X407085D03*
X409385D03*
X411685D03*
X420205D03*
X412365Y985610D03*
X410065D03*
X420145Y985550D03*
X409385Y1014540D03*
X407085D03*
X411685D03*
X412385Y1000080D03*
X410085D03*
X420215Y1000040D03*
X420405Y1014470D03*
X414461Y1028855D03*
X411961D03*
X416961D03*
X419461D03*
X415911Y1047749D03*
X419611D03*
X406662Y1044544D03*
X410362D03*
X408511Y1047749D03*
X414062Y1044544D03*
X404811Y1041340D03*
X412211D03*
X415911D03*
X419611D03*
X406662Y1050952D03*
X414060D03*
X417762Y1057361D03*
X421462Y1050952D03*
X419611Y1054157D03*
X406662Y1063770D03*
X408511Y1060565D03*
X410362Y1063770D03*
X412211Y1054157D03*
X404811D03*
X414062Y1057361D03*
X410362D03*
X417762Y1063770D03*
X414062D03*
X419611Y1060565D03*
Y1079791D03*
X408511Y1073383D03*
X406662Y1070178D03*
X404811Y1073383D03*
X417762Y1076587D03*
X408511Y1066974D03*
X415911Y1079791D03*
X412211Y1073383D03*
X415911D03*
X414062Y1070178D03*
X417762D03*
X412211Y1066974D03*
X419611D03*
X408511Y1079791D03*
X419612Y1099017D03*
X404811Y1092608D03*
X417762Y1095813D03*
X414061D03*
X406662Y1089404D03*
X410362D03*
X404811Y1086200D03*
X419611D03*
X414062Y1082995D03*
X410362D03*
X406662D03*
X408511Y1092608D03*
X414062Y1089404D03*
X419611Y1092608D03*
X412211Y1086200D03*
X404811Y1099017D03*
X408511Y1105426D03*
X412211Y1111834D03*
X415911D03*
X414062Y1102221D03*
X417762Y1108630D03*
X419611Y1105426D03*
X408511Y1099017D03*
X410362Y1108630D03*
X408511Y1111834D03*
X412211Y1105426D03*
X419611Y1111834D03*
X415911Y1105426D03*
X415912Y1124651D03*
X419612D03*
Y1118243D03*
X417761Y1121447D03*
Y1127856D03*
X414062Y1115039D03*
X406661Y1121447D03*
X414062Y1127856D03*
X406661Y1140973D03*
X410362Y1134264D03*
X404812Y1137469D03*
X408512D03*
X406662Y1134264D03*
X415912Y1137469D03*
Y1131060D03*
X414061Y1140973D03*
X419612Y1137469D03*
Y1131060D03*
X417761Y1134264D03*
Y1140973D03*
X412212Y1137469D03*
X422878Y848176D03*
X421027Y844971D03*
X424727D03*
X428427D03*
X433978Y848176D03*
X435829Y844671D03*
X422879Y841467D03*
X426578Y848176D03*
X430278D03*
Y867401D03*
X422878D03*
X430278Y860993D03*
X422878D03*
Y854584D03*
X424729Y857789D03*
X430278Y854584D03*
X433979Y860993D03*
X421029Y857789D03*
X426578Y860993D03*
X428429Y857789D03*
X432129D03*
X435829D03*
X432129Y870606D03*
X426578Y873810D03*
X424729Y870606D03*
X433979Y873810D03*
X428429Y870606D03*
X421029D03*
X435829D03*
X422878Y873810D03*
X430278D03*
X422878Y886627D03*
X430278D03*
Y899445D03*
X422878D03*
X424729Y896240D03*
X430278Y893036D03*
X432129Y896240D03*
X437678Y893036D03*
X421029Y896240D03*
X426578Y899445D03*
X428429Y896240D03*
X433978Y899445D03*
X435829Y896240D03*
X424729Y915466D03*
X426578Y912262D03*
X430278D03*
X432129Y915466D03*
X421029Y909057D03*
X435829D03*
Y915466D03*
X432128Y909057D03*
X433978Y905853D03*
X424728Y909057D03*
X422878Y905853D03*
X430278D03*
X426578D03*
X421029Y915466D03*
X433979Y912262D03*
X430278Y918670D03*
X432129Y921875D03*
X433979Y918670D03*
X435829Y921875D03*
X424927Y927255D03*
X423176Y929465D03*
X422427Y927255D03*
X425676Y929465D03*
X424729Y921875D03*
X422878Y918670D03*
X421029Y921875D03*
X426578Y918670D03*
X430279Y925079D03*
X432130Y928283D03*
X430279Y931487D03*
X432130Y934692D03*
X435830Y928283D03*
X427875Y941930D03*
Y944230D03*
X430280Y944305D03*
X432130Y941101D03*
X435830D03*
X432129Y947510D03*
X435830D03*
Y934692D03*
X427875Y956373D03*
Y954073D03*
X422685Y956620D03*
X425185D03*
X430280Y957123D03*
X432129Y960327D03*
Y953918D03*
X430280Y950714D03*
X435830Y960327D03*
Y953918D03*
X432129Y966736D03*
X430280Y963531D03*
X435830Y966736D03*
X430268Y976348D03*
X432129Y973144D03*
X430280Y969940D03*
X427875Y971267D03*
X422685Y971100D03*
X427875Y968967D03*
X435830Y973144D03*
X430280Y982757D03*
X432129Y979553D03*
X427875Y983111D03*
X435830Y979553D03*
X422685Y985580D03*
X427875Y985411D03*
Y997521D03*
X430712Y1009298D03*
X427875Y1012152D03*
X430712Y1002889D03*
X427875Y999821D03*
X422685Y1000060D03*
X436263Y1006094D03*
Y999685D03*
X432562Y1006094D03*
Y999685D03*
X427875Y1014452D03*
X423015Y1014470D03*
X436263Y1012502D03*
X432562D03*
X421961Y1028855D03*
X430712Y1022115D03*
Y1015706D03*
X427875Y1026704D03*
X430712Y1028524D03*
X436263Y1018911D03*
X432562D03*
Y1025319D03*
X436263D03*
X427875Y1029004D03*
Y1031304D03*
X436263Y1031728D03*
X432562D03*
X427011Y1047749D03*
X427012Y1041340D03*
X423312D03*
X425162Y1044544D03*
X423285Y1036884D03*
X430711Y1041340D03*
X430712Y1034932D03*
X427875Y1033604D03*
X423285Y1032284D03*
Y1034584D03*
X436262Y1038137D03*
X436261Y1044544D03*
X432562Y1038137D03*
X434412Y1041340D03*
X432561Y1044544D03*
X434412Y1047749D03*
X421462Y1044544D03*
X427011Y1054157D03*
X430711D03*
X428861Y1057361D03*
X432561D03*
X421462D03*
X425162Y1050952D03*
X423311Y1054157D03*
X428862Y1050952D03*
X436262Y1057361D03*
Y1050952D03*
Y1063770D03*
X425162D03*
X423311Y1060565D03*
X427011D03*
X428861Y1063770D03*
X430711Y1060565D03*
X423311Y1073383D03*
X432560Y1070178D03*
X421462Y1076587D03*
X423311Y1079791D03*
X436262Y1070178D03*
Y1076587D03*
X421462Y1070178D03*
X425162D03*
X428862D03*
X430711Y1066974D03*
X428861Y1076587D03*
X430711Y1079791D03*
X436262Y1082995D03*
Y1089404D03*
X436261Y1095813D03*
X421462Y1089404D03*
X423311Y1092608D03*
X427011D03*
X430710Y1086200D03*
X425162Y1082995D03*
Y1095813D03*
X430711Y1092608D03*
X423311Y1086200D03*
X428861Y1089404D03*
X427012Y1086200D03*
X421462Y1102221D03*
X423311Y1099017D03*
X428861Y1108630D03*
X427012Y1105426D03*
X425162Y1108630D03*
X430711Y1105426D03*
Y1099017D03*
X428861Y1102221D03*
X436262Y1108630D03*
Y1102221D03*
X432561Y1108630D03*
Y1102221D03*
X434412Y1099017D03*
X430711Y1111834D03*
X427012D03*
X430711Y1124651D03*
X428861Y1121447D03*
X427012Y1124651D03*
X425162Y1121447D03*
X421461D03*
X430711Y1118243D03*
X428861Y1115039D03*
X427012Y1118243D03*
X425162Y1115039D03*
X436262Y1121447D03*
Y1115039D03*
X432561Y1121447D03*
Y1115039D03*
X428861Y1127856D03*
X425162D03*
X421461D03*
X436262D03*
X432561D03*
X430711Y1137769D03*
X427012Y1137569D03*
X430711Y1131060D03*
X428861Y1134264D03*
X427012Y1131060D03*
X425162Y1134264D03*
X421461D03*
X428861Y1140973D03*
X425161D03*
X421461D03*
X436261Y1134264D03*
X432561D03*
X450628Y844971D03*
X446927Y844671D03*
X452479Y841467D03*
X448778Y848176D03*
X443227Y844671D03*
X437678Y848176D03*
X452478Y867401D03*
X445078D03*
X437678D03*
X445078Y860993D03*
X452479D03*
X437679Y854584D03*
X452478D03*
X450629Y857789D03*
X445078Y854584D03*
X443229Y857789D03*
X448779Y860993D03*
X446929Y857789D03*
X441378Y860993D03*
X448779Y873810D03*
X446929Y870606D03*
X441378Y873810D03*
X439529Y870606D03*
X450629D03*
X443229D03*
X437679Y873810D03*
X452479D03*
X445078D03*
X452478Y886627D03*
X445078D03*
X452478Y899445D03*
X441378D03*
X445078Y893036D03*
X446929Y896240D03*
X452479Y893036D03*
X445078Y899445D03*
X443229Y896240D03*
X448778Y899445D03*
X450630Y896240D03*
X443229Y909057D03*
X439529Y915466D03*
X445079Y905853D03*
X441379D03*
X450630Y909057D03*
X452479Y905853D03*
X448779D03*
X448780Y912262D03*
X441380D03*
X439529Y909057D03*
X445080Y912262D03*
X443229Y915466D03*
X450629D03*
X452478Y912262D03*
X448779Y918670D03*
X454329Y915466D03*
X439529Y921875D03*
X441378Y918670D03*
X450629Y921875D03*
X445078Y918670D03*
X443229Y921875D03*
X452478Y918670D03*
X446930Y934692D03*
X443230Y928283D03*
X448780Y931487D03*
X437679D03*
X450630Y928283D03*
X448780Y925079D03*
X445079Y931487D03*
X439530Y934692D03*
X445079Y925079D03*
X439530Y928283D03*
X437679Y925079D03*
X437680Y944305D03*
X441380D03*
X443230Y941101D03*
X445079Y944305D03*
X439530Y941101D03*
X450630D03*
X448780Y944305D03*
X443229Y947510D03*
X439529D03*
X450630D03*
X443230Y934692D03*
X445079Y957123D03*
X437680D03*
X441380D03*
X439529Y960327D03*
X443229D03*
Y953918D03*
X439529D03*
X437680Y950714D03*
X441380D03*
X445079D03*
X448780Y957123D03*
X450630Y953918D03*
Y960327D03*
X448780Y950714D03*
X445079Y963531D03*
X437680D03*
X441380D03*
X439529Y966736D03*
X443229D03*
X448780Y963531D03*
X450630Y966736D03*
X445079Y976348D03*
Y969940D03*
X439529Y973144D03*
X443229D03*
X437680Y976348D03*
X441380D03*
X437680Y969940D03*
X441380D03*
X450630Y973144D03*
X448780Y976348D03*
Y969940D03*
X445079Y982757D03*
X437680D03*
X441380D03*
X439529Y979553D03*
X443229D03*
X448780Y982757D03*
X450630Y979553D03*
X439962Y1006094D03*
X443662D03*
X445511Y1009298D03*
X438113D03*
X441813D03*
X445512Y1002889D03*
X438113D03*
X441813D03*
X439962Y999685D03*
X443662D03*
X451062Y1006094D03*
X449213Y1009298D03*
Y1002889D03*
X451062Y999685D03*
X439962Y1012502D03*
X443662D03*
X451062D03*
X445511Y1022115D03*
X438113D03*
X441813D03*
X445512Y1015706D03*
X438113D03*
X439962Y1018911D03*
X441813Y1015706D03*
X443662Y1018911D03*
Y1025319D03*
X439962D03*
X445511Y1028524D03*
X441813D03*
X438113D03*
X449213Y1022115D03*
X451062Y1018911D03*
X449213Y1015706D03*
X451062Y1025319D03*
X449213Y1028524D03*
X439962Y1031728D03*
X443662D03*
X451062D03*
X452911Y1047749D03*
X439962Y1038137D03*
X443662D03*
X438112Y1041340D03*
X439961Y1044544D03*
X441812Y1041340D03*
X443661Y1044544D03*
X447361D03*
X445511Y1041340D03*
X445512Y1034932D03*
X438113D03*
X441813D03*
X451062Y1038137D03*
X449211Y1041340D03*
X449213Y1034932D03*
X445510Y1047749D03*
X441812D03*
X438112D03*
X449211Y1054157D03*
X449213Y1060565D03*
X438112D03*
Y1054157D03*
X439961Y1057361D03*
X441812Y1054157D03*
Y1060565D03*
X443661Y1057361D03*
X445511Y1060565D03*
Y1054157D03*
X439961Y1050952D03*
X443661D03*
X439961Y1063770D03*
X443661D03*
X451061D03*
X452911Y1054157D03*
X451062Y1050952D03*
X454762D03*
Y1057361D03*
X451062D03*
X451061Y1076587D03*
X452911Y1073383D03*
X439961Y1076587D03*
Y1070178D03*
X441812Y1073383D03*
X438112D03*
X443661Y1070178D03*
Y1076587D03*
X445511Y1073383D03*
X441812Y1066974D03*
X438112D03*
X445511D03*
X441812Y1079791D03*
X438112D03*
X445511D03*
X452911Y1066974D03*
X449211D03*
X451062Y1070178D03*
X452911Y1086200D03*
X443661Y1082995D03*
X439961D03*
X441812Y1086200D03*
X445511D03*
X439961Y1089404D03*
X441812Y1092608D03*
X438112D03*
X443661Y1089404D03*
X445511Y1092608D03*
X447361Y1089404D03*
X438112Y1086200D03*
X449211Y1092608D03*
X439961Y1095813D03*
X443661D03*
X447361D03*
X451060Y1082995D03*
X441812Y1105426D03*
X438112D03*
X439961Y1108630D03*
X443661D03*
X445511Y1105426D03*
X439961Y1102221D03*
X441812Y1099017D03*
X438112D03*
X443661Y1102221D03*
X445511Y1099017D03*
X452912Y1105426D03*
X451061Y1108630D03*
X449212Y1105426D03*
X451061Y1102221D03*
X449212Y1099017D03*
X441812Y1111834D03*
X438112D03*
X445511D03*
X452912D03*
X449212D03*
X438112Y1124651D03*
X439961Y1121447D03*
X441812Y1124651D03*
X445511D03*
X443661Y1121447D03*
X438112Y1118243D03*
X441812D03*
X439961Y1115039D03*
X445511Y1118243D03*
X443661Y1115039D03*
X452912Y1124651D03*
Y1118243D03*
X451061Y1121447D03*
X449212Y1124651D03*
Y1118243D03*
X451061Y1115039D03*
X439961Y1127856D03*
X443661D03*
X451061D03*
X441812Y1137769D03*
X438112D03*
X445511D03*
X443661Y1134264D03*
X441812Y1131060D03*
X439961Y1134264D03*
X438112Y1131060D03*
X445511D03*
X452912Y1137769D03*
Y1131060D03*
X449212Y1137769D03*
Y1131060D03*
X451061Y1134264D03*
X459878Y848176D03*
X467278D03*
X467279Y841467D03*
X463578Y848176D03*
X459879Y841467D03*
X458027Y844971D03*
X454327D03*
X469127D03*
X465427D03*
X461727D03*
X456178Y848176D03*
X467278Y867401D03*
X459878D03*
Y860993D03*
X467278D03*
Y854584D03*
X465429Y857789D03*
X459878Y854584D03*
X458029Y857789D03*
X469129D03*
X463578Y860993D03*
X461729Y857789D03*
X456178Y860993D03*
X454329Y857789D03*
X469129Y870606D03*
X463578Y873810D03*
X461729Y870606D03*
X456178Y873810D03*
X454329Y870606D03*
X465429D03*
X458029D03*
X467278Y873810D03*
X459878D03*
Y886627D03*
X467278D03*
X459878Y899445D03*
X467278D03*
X454329Y896240D03*
X459878Y893036D03*
X461729Y896240D03*
X467278Y893036D03*
X456178Y899445D03*
X458029Y896240D03*
X463578Y899445D03*
X465429Y896240D03*
X470978Y899445D03*
X463578Y905853D03*
X470980Y912262D03*
X469129Y902649D03*
X454329Y909057D03*
X470978Y918670D03*
X467278Y912262D03*
X469129Y915466D03*
X458029Y909057D03*
X459878Y905853D03*
X461729Y915466D03*
X467278Y905853D03*
X461729Y909057D03*
X458029Y915466D03*
X459878Y918670D03*
X463578Y912262D03*
X459878D03*
X469129Y909057D03*
X467278Y918670D03*
X454329Y921875D03*
X468236Y928349D03*
X465936D03*
X463636D03*
X461336D03*
X459036D03*
X469129Y921875D03*
X463578Y918670D03*
X465429Y921875D03*
X458029D03*
X469251Y942246D03*
X453585Y942238D03*
Y939938D03*
Y944538D03*
X453403Y956999D03*
X461424Y956620D03*
X458404D03*
X453403Y959299D03*
X468904Y956620D03*
Y971100D03*
X458404D03*
X461424Y971140D03*
X453403Y973099D03*
Y970799D03*
Y986899D03*
X461424Y985580D03*
X458404D03*
X453403Y984599D03*
X468904Y985580D03*
X453403Y998399D03*
Y1012199D03*
X458404Y1000080D03*
X461424D03*
X453403Y1000699D03*
X468904Y1000080D03*
X458404Y1014540D03*
X461295Y1014510D03*
X453403Y1014499D03*
X465680Y1028855D03*
X463180D03*
X460680D03*
X458180D03*
X457942Y1031909D03*
X467711Y1047750D03*
X460311D03*
X471411Y1041340D03*
X467711D03*
X454762Y1044544D03*
Y1038136D03*
X460971Y1037069D03*
X463271D03*
X458671D03*
X457942Y1034409D03*
X456611Y1041340D03*
X464011D03*
X462162Y1044544D03*
X458462D03*
X464011Y1054157D03*
X465860Y1050952D03*
X456611Y1060565D03*
X462161Y1057361D03*
Y1063770D03*
X460312Y1054157D03*
X458462Y1057361D03*
X467712Y1054157D03*
Y1060565D03*
X454761Y1063770D03*
X464012Y1060565D03*
X458460Y1050952D03*
X460311Y1060565D03*
Y1073383D03*
X458460Y1070178D03*
X460311Y1066974D03*
X464011D03*
X465860Y1070178D03*
X469560D03*
X464012Y1079791D03*
X460312D03*
X462162Y1076587D03*
X456611Y1066974D03*
X465862Y1076587D03*
X464011Y1073383D03*
X458462Y1076587D03*
X465862Y1082995D03*
X462162D03*
X462161Y1095812D03*
X458461D03*
X465861Y1089403D03*
X456612Y1092607D03*
X454761Y1089403D03*
X460311Y1086200D03*
X454760Y1082995D03*
X465861Y1095812D03*
X464012Y1092607D03*
X454761Y1095812D03*
X458461Y1089403D03*
X462161D03*
X467711Y1099017D03*
X462162Y1102221D03*
X458461Y1108630D03*
X456612Y1105426D03*
X454761Y1108630D03*
Y1102221D03*
X460312Y1111834D03*
X456611D03*
X460312Y1099016D03*
X464012Y1124651D03*
X462161Y1121447D03*
X460312Y1124651D03*
X456611D03*
X454761Y1121447D03*
X464011Y1118243D03*
X462161Y1115039D03*
X460312Y1118243D03*
X456611D03*
X454761Y1115039D03*
X462161Y1127856D03*
X454761D03*
X465861D03*
X464012Y1137469D03*
X460312D03*
X456612D03*
X464012Y1131060D03*
X462161Y1134264D03*
X460312Y1131060D03*
X456611D03*
X454761Y1134264D03*
X462161Y1140973D03*
X458461D03*
X454761D03*
X467712Y1137469D03*
X465861Y1134264D03*
X467712Y1131060D03*
X465861Y1140973D03*
X474678Y848176D03*
X482078D03*
X483927Y844971D03*
X480227D03*
X476527D03*
X470978Y848176D03*
X482079Y841467D03*
X478378Y848176D03*
X474679Y841467D03*
X472827Y844971D03*
X474678Y867401D03*
X482078D03*
X474678Y860993D03*
X482078D03*
Y854584D03*
X480229Y857789D03*
X474678Y854584D03*
X472829Y857789D03*
X483929D03*
X478378Y860993D03*
X476529Y857789D03*
X470978Y860993D03*
X480229Y870606D03*
X476529D03*
X478378Y873810D03*
X483929Y870606D03*
X474678Y880219D03*
X476529Y883423D03*
X482078Y880219D03*
X483929Y883423D03*
X472829D03*
X480229D03*
X474678Y873810D03*
X482078D03*
X474678Y893036D03*
X472829Y896240D03*
X482078Y893036D03*
X483929Y896240D03*
X478378Y886627D03*
Y899445D03*
X474678Y886627D03*
X482078D03*
X476529Y896240D03*
Y915466D03*
X478380Y912262D03*
X478379Y918670D03*
X480229Y902649D03*
X483929Y915466D03*
X480229D03*
X472828D03*
X472829Y902649D03*
X480228Y909057D03*
X482078Y905853D03*
X476529Y902649D03*
X470978Y905853D03*
X478378D03*
X472829Y909057D03*
X476529D03*
X480229Y928283D03*
X478378Y931488D03*
Y925079D03*
X482078D03*
X472829Y921875D03*
X470536Y928349D03*
X478378Y937896D03*
X480229Y941100D03*
X483929Y934691D03*
X480229Y947509D03*
X471550Y942152D03*
X473851Y942246D03*
X478378Y963530D03*
X483929Y953917D03*
X480228Y960326D03*
X478378Y950713D03*
X480229Y953917D03*
X478378Y957122D03*
X471404Y956620D03*
X480229Y966735D03*
X482078Y963529D03*
X483929Y973143D03*
X482078Y982756D03*
X478379Y969939D03*
X476285Y973826D03*
Y971526D03*
X471404Y971100D03*
X473904D03*
X480229Y979552D03*
X478378Y982756D03*
X480229Y973143D03*
X478378Y976347D03*
X471404Y985580D03*
X480662Y999684D03*
X478811Y1002888D03*
Y1009297D03*
X480662Y1012501D03*
X484362Y1006093D03*
X471404Y1000080D03*
X484362Y1025318D03*
X480662Y1031727D03*
X482511Y1015705D03*
X480661Y1018910D03*
X478811Y1022114D03*
Y1028523D03*
Y1015705D03*
X476325Y1031795D03*
Y1027195D03*
Y1029495D03*
X470724Y1028827D03*
X480662Y1025318D03*
X484362Y1044544D03*
X475111Y1047749D03*
X469562Y1044544D03*
X478811Y1034931D03*
X480662Y1038136D03*
X478811Y1041340D03*
X480662Y1044544D03*
X473262D03*
X476962D03*
X478811Y1047749D03*
X484362Y1063770D03*
X473261Y1057361D03*
X471412Y1060565D03*
X475112Y1054157D03*
X469562Y1063770D03*
X469561Y1057361D03*
X473262Y1063770D03*
X469561Y1050952D03*
X473262D03*
X482511Y1054157D03*
X480662Y1063770D03*
X480661Y1057361D03*
X478812Y1060565D03*
X476962Y1063770D03*
Y1057361D03*
X478812Y1054157D03*
X476961Y1050952D03*
X478811Y1066974D03*
X471411D03*
X476962Y1076587D03*
X480662D03*
Y1070178D03*
X476962D03*
X473262Y1076587D03*
X469562D03*
X471411Y1073383D03*
Y1079791D03*
X475111Y1073383D03*
X482511D03*
X484362Y1082995D03*
X473262Y1095813D03*
X469562Y1082995D03*
X480662Y1089404D03*
X478812Y1092607D03*
X475112D03*
X473261Y1089403D03*
X471412Y1086199D03*
X476961Y1082994D03*
X482512Y1092607D03*
X476961Y1095812D03*
X471412Y1092607D03*
X475112Y1086199D03*
X478812D03*
X480662Y1102221D03*
X473262Y1121447D03*
X480662D03*
X484362Y1134264D03*
X482512Y1137469D03*
X476962Y1134264D03*
X475112Y1137469D03*
X480661Y1140973D03*
X478812Y1137469D03*
X473261Y1140973D03*
X480662Y1134264D03*
X469561D03*
X489478Y848176D03*
X496878D03*
X493178D03*
X489478Y841467D03*
X487627Y844971D03*
X500578Y848176D03*
X496878Y841467D03*
X495027Y844971D03*
X491327D03*
X485778Y848176D03*
X498727Y844971D03*
X489478Y867401D03*
X496878D03*
X489478Y860993D03*
X496878D03*
X489478Y854584D03*
X487629Y857789D03*
X500578Y860993D03*
X498729Y857789D03*
X495029D03*
X491329D03*
X485778Y860993D03*
X496878Y854584D03*
X493178Y860993D03*
X487629Y870606D03*
X495029D03*
X485778Y873810D03*
X491329Y870606D03*
X493178Y873810D03*
X498729Y870606D03*
X500578Y873810D03*
X489478Y880219D03*
X491329Y883423D03*
X496878Y880219D03*
X498729Y883423D03*
X487629D03*
X495029D03*
X496878Y873810D03*
X489478D03*
X500578Y899445D03*
X485778D03*
X493178D03*
Y893036D03*
X496878D03*
X485778D03*
X491329Y896240D03*
X487629D03*
X495029D03*
X485778Y886627D03*
X493178D03*
X500578D03*
X489478D03*
X496878D03*
X485778Y912262D03*
X487629Y909057D03*
X493178Y912262D03*
X491329Y909057D03*
X500578Y912262D03*
X498729Y909057D03*
Y902649D03*
X487629D03*
X491329D03*
X487629Y915466D03*
X500578Y905853D03*
X495029Y915466D03*
X496878Y905853D03*
X491329Y915466D03*
X500578Y931488D03*
X498729Y921875D03*
X500578Y918670D03*
X498729Y928283D03*
X496878Y925079D03*
X500578D03*
X491329Y921875D03*
X493178Y918670D03*
X485778Y931488D03*
X491329Y928283D03*
X493178Y931488D03*
X487629Y928283D03*
Y921875D03*
X485778Y918670D03*
X498729Y947509D03*
Y941100D03*
X500578Y937896D03*
X496878Y944304D03*
X500578D03*
X487629Y947509D03*
X491329D03*
X487629Y941100D03*
X485778Y937896D03*
X491329Y941100D03*
X493178Y937896D03*
X487629Y934691D03*
X495029D03*
X491329D03*
X500578Y950713D03*
X487629Y966735D03*
X491329D03*
X498729D03*
X496878Y963530D03*
X485778Y950713D03*
X493178D03*
X491329Y960326D03*
X493178Y957122D03*
X487629Y960326D03*
X485778Y957122D03*
X500578D03*
X498729Y960326D03*
X495029Y953917D03*
X487629D03*
X491329D03*
X487629Y979552D03*
X485778Y976347D03*
X491329Y979552D03*
X493178Y976347D03*
X500578Y982756D03*
X496878D03*
X498729Y979552D03*
X500578Y976347D03*
X495029Y973143D03*
X487629D03*
X491329D03*
X485778Y969939D03*
X493178D03*
X500578D03*
X501011Y1002888D03*
X499162Y999684D03*
Y1012501D03*
X501011Y1009297D03*
X495462Y1006093D03*
X486211Y1002888D03*
X493611D03*
X488062Y999684D03*
X491762D03*
X491761Y1012501D03*
X493611Y1009297D03*
X488062Y1012501D03*
X486211Y1009297D03*
X497311Y1015705D03*
X499162Y1031727D03*
X501011Y1028523D03*
Y1022114D03*
X499162Y1018910D03*
X488062Y1031727D03*
X486211Y1028523D03*
X491762Y1031727D03*
X493611Y1028523D03*
X486211Y1022114D03*
X488062Y1018910D03*
X493611Y1022114D03*
X491762Y1018910D03*
X488062Y1025318D03*
X495462D03*
X491762D03*
X501011Y1041340D03*
X499162Y1038136D03*
X501011Y1047749D03*
Y1034931D03*
X497311D03*
X486211Y1047749D03*
X493611D03*
X486211Y1041340D03*
X488062Y1038136D03*
X493611Y1041340D03*
X491762Y1038136D03*
X488062Y1044544D03*
X495462D03*
X491762D03*
X501011Y1060565D03*
X499162Y1057361D03*
Y1050952D03*
X501011Y1054157D03*
X497311D03*
X486211Y1060565D03*
X488062Y1057361D03*
X493611Y1060565D03*
X491762Y1057361D03*
X488062Y1050952D03*
X491762D03*
X488062Y1063770D03*
X495462D03*
X491762D03*
X499162Y1070178D03*
X501011Y1066974D03*
Y1079791D03*
X499162Y1076587D03*
X497311Y1073383D03*
X501011D03*
X486211Y1079791D03*
X488062Y1076587D03*
X493611Y1079791D03*
X491762Y1076587D03*
X488062Y1070178D03*
X486211Y1066974D03*
X491762Y1070178D03*
X493611Y1066974D03*
X491762Y1089404D03*
X493611Y1086200D03*
X499162Y1089404D03*
X501011Y1086200D03*
X488062Y1089404D03*
X486211Y1086200D03*
X497311Y1092608D03*
X495462Y1082995D03*
X501011Y1092608D03*
X488062Y1082995D03*
X491762D03*
X488062Y1095813D03*
X501012Y1105426D03*
Y1111833D03*
X488062Y1115039D03*
Y1121447D03*
X493612Y1137469D03*
X488061Y1140973D03*
X501012Y1137469D03*
X495461Y1140973D03*
X491762Y1134264D03*
X489912Y1137469D03*
X486212D03*
X499162Y1134264D03*
X497312Y1137469D03*
X495462Y1134264D03*
X488062D03*
X511678Y848176D03*
X504278D03*
X517227Y844971D03*
X511679Y841467D03*
X509827Y844971D03*
X504279Y841467D03*
X515378Y848176D03*
X513527Y844971D03*
X507978Y848176D03*
X506127Y844971D03*
X502427D03*
X511678Y867401D03*
X504278D03*
X511678Y860993D03*
X504278D03*
X517229Y857789D03*
X513529D03*
X509829D03*
X506129D03*
X515378Y860993D03*
X511678Y854584D03*
X507978Y860993D03*
X504278Y854584D03*
X502429Y857789D03*
X517229Y870606D03*
X502429D03*
X509829D03*
X513529D03*
X515378Y873810D03*
X506129Y870606D03*
X507978Y873810D03*
X511678Y880219D03*
X513529Y883423D03*
X504278Y880219D03*
X506129Y883423D03*
X509829D03*
X517229D03*
X502429D03*
X511678Y873810D03*
X504278D03*
X511678Y899445D03*
Y893036D03*
X507978D03*
X509829Y896240D03*
X517229D03*
X513529D03*
X504278Y899445D03*
X515378Y886627D03*
X507978D03*
X511678D03*
X504278D03*
X513529Y902649D03*
X517229D03*
X511678Y912262D03*
X513529Y909057D03*
X517229D03*
X513529Y915466D03*
X509829D03*
X517229D03*
X504278Y912262D03*
X506129Y909057D03*
Y902649D03*
X507978Y905853D03*
X504278D03*
X511678Y931488D03*
X513529Y928283D03*
X517229D03*
X506129D03*
Y921875D03*
X504278Y918670D03*
X513529Y921875D03*
X511678Y918670D03*
X517229Y921875D03*
X504278Y931488D03*
Y925079D03*
X507978D03*
X513529Y941100D03*
X511678Y937896D03*
X517229Y941100D03*
X513529Y934691D03*
X509829D03*
X517229D03*
X513529Y947509D03*
X517229D03*
X506129D03*
Y941100D03*
X504278Y937896D03*
X507978Y944304D03*
X504278D03*
X511678Y950713D03*
X513529Y960326D03*
X511678Y957122D03*
X517229Y960326D03*
Y966735D03*
X513529D03*
X504278Y950713D03*
X513529Y953917D03*
X517229D03*
X509829D03*
X506129Y966735D03*
X504278Y957122D03*
X506129Y960326D03*
X507978Y963530D03*
Y982756D03*
X504278D03*
Y976347D03*
X506129Y979552D03*
X513529D03*
X517229D03*
X511678Y976347D03*
X509829Y973143D03*
X511678Y969939D03*
X504278D03*
X502862Y1006093D03*
X504711Y1002888D03*
X506561Y999684D03*
X506562Y1012501D03*
X504711Y1009297D03*
X517661Y999684D03*
X512111Y1002888D03*
X513962Y999684D03*
Y1031727D03*
X512111Y1028523D03*
X517662Y1031727D03*
X512111Y1022114D03*
X513962Y1018910D03*
X517662D03*
X513962Y1025318D03*
X510262D03*
X517662D03*
X508411Y1015705D03*
X506562Y1031727D03*
X504711Y1028523D03*
Y1022114D03*
X506562Y1018910D03*
X504711Y1041340D03*
X506562Y1038136D03*
X512111Y1047749D03*
Y1041340D03*
X513962Y1038136D03*
X517662D03*
X504711Y1047749D03*
X510262Y1044544D03*
X508411Y1034931D03*
X513962Y1044544D03*
X517662D03*
X504711Y1034931D03*
X512111Y1060565D03*
X513962Y1057361D03*
X517662D03*
X510262Y1063770D03*
X513962D03*
X517662D03*
X513962Y1050952D03*
X517662D03*
X504711Y1060565D03*
X506562Y1057361D03*
Y1050952D03*
X508411Y1054157D03*
X504711D03*
X517662Y1070178D03*
X513962D03*
X512111Y1066974D03*
X504711Y1079791D03*
X506562Y1076587D03*
Y1070178D03*
X504711Y1066974D03*
X512111Y1079791D03*
X513962Y1076587D03*
X517662D03*
X508411Y1073383D03*
X504711D03*
X513962Y1089404D03*
X512111Y1086200D03*
X517662Y1089404D03*
X513962Y1082995D03*
X510262D03*
X517662D03*
X510262Y1095813D03*
X506561D03*
X506562Y1089404D03*
X504711Y1086200D03*
X508411Y1092608D03*
X504711D03*
X517662Y1102221D03*
X515811Y1099017D03*
X510262Y1102221D03*
X502861Y1108629D03*
X512112Y1105426D03*
X508412Y1111833D03*
X506561Y1102220D03*
X504712Y1111833D03*
Y1105426D03*
X510261Y1108630D03*
X512112Y1111833D03*
X508412Y1105426D03*
X502862Y1115039D03*
X510262Y1121447D03*
X502862D03*
X517662D03*
X506561Y1115038D03*
X517661Y1140973D03*
X513962Y1134264D03*
X512112Y1137469D03*
X506562Y1134264D03*
X504712Y1137469D03*
X515812D03*
X510261Y1140973D03*
X508412Y1137469D03*
X502861Y1140973D03*
X510262Y1134264D03*
X502862D03*
X517662D03*
X519078Y848176D03*
X532028Y844671D03*
X526478Y848176D03*
X524627Y844971D03*
X519079Y841467D03*
X533878Y848176D03*
X530178D03*
X522778D03*
X520927Y844971D03*
X532029Y864197D03*
X533879Y854584D03*
X519078Y867401D03*
X526479D03*
Y860993D03*
X519078D03*
X528329Y857789D03*
X522778Y860993D03*
X520929Y857789D03*
X526478Y854584D03*
X524629Y857789D03*
X519078Y854584D03*
X524629Y870606D03*
X532029D03*
X520929D03*
X522778Y873810D03*
X528329Y870606D03*
X530178Y873810D03*
X519078Y880219D03*
X520929Y883423D03*
X526479Y880219D03*
X528329Y883423D03*
X524629D03*
X526479Y873810D03*
X519078D03*
Y899445D03*
Y893036D03*
X522778D03*
X520929Y896240D03*
X530178Y893036D03*
X522778Y886627D03*
X530179D03*
X526479D03*
X519078D03*
X533879D03*
X519078Y912262D03*
X520929Y915466D03*
X519078Y931488D03*
Y918670D03*
Y937896D03*
X520929Y934691D03*
X519078Y950713D03*
Y957122D03*
X520929Y953917D03*
X519078Y976347D03*
Y969939D03*
X520929Y973143D03*
X519513Y1002888D03*
X530611D03*
X532461Y999684D03*
X526911Y1002888D03*
X525062Y999684D03*
X519511Y1028523D03*
Y1022114D03*
X521362Y1025318D03*
X519511Y1047749D03*
Y1041340D03*
X521362Y1044544D03*
X519511Y1060565D03*
X521362Y1063770D03*
X519511Y1066974D03*
Y1079791D03*
Y1086200D03*
X521362Y1082995D03*
X528762Y1102221D03*
X525062D03*
X523212Y1099017D03*
X530611Y1105426D03*
X526911Y1118243D03*
X525062Y1121447D03*
X534311Y1118243D03*
X532461Y1121446D03*
X534311Y1124650D03*
X532461Y1127855D03*
X532462Y1134264D03*
X525061Y1140973D03*
X523212Y1137469D03*
X534312D03*
X526912D03*
X521362Y1134264D03*
X519512Y1137469D03*
X525062Y1134264D03*
X528761Y1140973D03*
X532461D03*
X543129Y851380D03*
X539429D03*
X535729Y864197D03*
X543128D03*
X546828D03*
X535729Y857789D03*
X543130D03*
X539429D03*
X541279Y860993D03*
Y854584D03*
X541711Y1118243D03*
X538010Y1118242D03*
X543561Y1121446D03*
X539861Y1127855D03*
X536161D03*
Y1121446D03*
X539861D03*
X541711Y1124650D03*
X543561Y1127855D03*
X538012Y1131059D03*
X650599Y766798D03*
X918264Y506011D03*
X1030780Y1266532D03*
X1074480Y1263742D03*
X1181941Y766798D03*
X1297012Y157449D03*
X1293802Y159299D03*
Y166699D03*
X1293511Y179048D03*
X1296999Y183349D03*
X1297007Y172249D03*
X1296999Y175949D03*
X1293802Y170399D03*
X1294163Y175865D03*
X1296999Y179649D03*
Y194449D03*
Y198149D03*
Y190749D03*
Y187049D03*
Y201849D03*
X1293805Y211099D03*
X1293798Y205833D03*
X1296999Y216649D03*
X1293807Y218499D03*
Y214799D03*
X1296999Y212949D03*
Y205549D03*
X1294357Y224688D03*
X1296999Y224049D03*
X1293807Y222199D03*
X1300393Y235762D03*
X1303417Y164849D03*
X1300213Y162999D03*
X1300212Y166699D03*
X1306622D03*
X1309832Y157449D03*
X1306626Y162999D03*
Y159299D03*
X1313037Y162999D03*
X1309832Y164849D03*
X1313037Y159299D03*
X1303417Y157449D03*
X1300217Y159299D03*
X1313033Y166699D03*
X1300212Y170399D03*
X1306626D03*
X1303407Y183349D03*
X1309817Y175949D03*
X1300212Y174099D03*
X1313037Y170399D03*
X1306617Y185199D03*
X1309832Y172249D03*
X1313027Y181499D03*
Y185199D03*
X1303407Y175949D03*
Y179649D03*
X1306617Y177799D03*
X1309817Y179649D03*
X1300204Y181499D03*
X1309817Y194449D03*
X1306617Y188899D03*
X1303407Y194449D03*
X1306617Y196299D03*
X1300207D03*
X1303407Y190749D03*
Y187049D03*
X1300204Y188899D03*
X1313027Y192599D03*
X1309817Y190749D03*
X1313025Y188899D03*
X1309817Y198149D03*
X1303407D03*
X1300207Y203699D03*
Y207399D03*
X1309832Y209249D03*
X1313027Y203699D03*
X1300220Y218499D03*
X1309833Y220349D03*
X1303416Y205549D03*
X1306614Y203699D03*
X1306627Y214799D03*
X1316242Y209249D03*
X1300207Y211099D03*
X1303422Y220349D03*
X1300220Y222199D03*
X1313033D03*
X1303425Y224049D03*
X1300493Y238062D03*
X1314184Y849978D03*
X1313921Y880219D03*
X1312070Y883423D03*
X1313921Y893036D03*
X1312070Y889832D03*
X1310221Y886627D03*
X1313921D03*
X1307426Y978814D03*
X1314353Y1118243D03*
X1312503Y1121447D03*
X1314353Y1131060D03*
X1319452Y162999D03*
X1316242Y168549D03*
X1319442Y159299D03*
X1316241Y157449D03*
X1316242Y164849D03*
X1322652D03*
X1329062D03*
X1326918Y161161D03*
X1329062Y157449D03*
X1322652D03*
X1325853Y174099D03*
X1331102Y179724D03*
Y182874D03*
Y186024D03*
X1325085Y176402D03*
X1324802Y179724D03*
Y186024D03*
Y182874D03*
X1315352Y186024D03*
Y179724D03*
X1319442Y174099D03*
X1332268D03*
X1324802Y195474D03*
X1327952D03*
X1318502D03*
X1321652D03*
X1327952Y201774D03*
X1321652D03*
X1331102Y189174D03*
X1315405Y189227D03*
X1329062Y212949D03*
X1325852Y211099D03*
X1319442D03*
X1324802Y204924D03*
X1327952D03*
X1318502D03*
X1315352D03*
X1322652Y209249D03*
X1325857Y218499D03*
X1322652Y216649D03*
X1329062Y220349D03*
X1325856Y222199D03*
X1322652Y224049D03*
Y220349D03*
X1321320Y854584D03*
X1326869Y851380D03*
X1330569Y844971D03*
X1325020Y848176D03*
X1328720D03*
X1325021Y860993D03*
X1326871Y857789D03*
X1328720Y860993D03*
X1330571Y857789D03*
X1317621Y880219D03*
X1319471Y883423D03*
X1326871Y870606D03*
X1330571D03*
X1328720Y873810D03*
X1330571Y883423D03*
X1325020Y873810D03*
X1323171Y877014D03*
X1325020Y880219D03*
X1317620Y893036D03*
X1319470Y889832D03*
X1317621Y886627D03*
X1321321D03*
X1319903Y999684D03*
X1325453Y1105426D03*
X1329153D03*
X1325454Y1111834D03*
X1327303Y1102221D03*
X1321753Y1111834D03*
X1318054D03*
X1318053Y1105426D03*
X1327304Y1108630D03*
X1329154Y1111834D03*
X1331003Y1102221D03*
X1319904Y1108630D03*
X1321753Y1105426D03*
X1327304Y1127856D03*
X1329153Y1118243D03*
X1331003Y1121447D03*
X1323603D03*
X1319903Y1127856D03*
X1316203D03*
X1318054Y1118243D03*
X1321753Y1124651D03*
X1323603Y1127856D03*
X1319903Y1121447D03*
X1316203D03*
X1323603Y1115039D03*
X1325452Y1137469D03*
X1327303Y1134264D03*
X1331003D03*
X1323603D03*
X1318053Y1131060D03*
X1339727Y161149D03*
X1341992Y156897D03*
X1332268Y162999D03*
X1342903Y170399D03*
X1339727Y168549D03*
X1335472Y164849D03*
X1346140Y161149D03*
X1342937Y162999D03*
X1335472Y157449D03*
X1346140D03*
X1339727D03*
X1332268Y170399D03*
X1334252Y176574D03*
X1339727Y183349D03*
X1346137Y175949D03*
X1342937Y177799D03*
X1346137Y183349D03*
Y179649D03*
X1337901Y196035D03*
X1339727Y187049D03*
X1337345Y201831D03*
X1339727Y201849D03*
X1337402Y198624D03*
X1342937Y192599D03*
X1346137Y187049D03*
X1346147Y201849D03*
Y198149D03*
X1336527Y214799D03*
X1339727Y216649D03*
X1346147Y212949D03*
Y216649D03*
X1336527Y218499D03*
X1342937D03*
Y214799D03*
X1332262Y211099D03*
X1339686Y205478D03*
X1332262Y207399D03*
X1339727Y209249D03*
Y220349D03*
X1336527Y222199D03*
X1346147Y220349D03*
X1347220Y848176D03*
X1339820D03*
X1332420D03*
X1332421Y841467D03*
X1337969Y844971D03*
X1339821Y841467D03*
X1345369Y844971D03*
X1347221Y841467D03*
X1334269Y844971D03*
X1336120Y848176D03*
X1341669Y844971D03*
X1343520Y848176D03*
X1347220Y867401D03*
X1332420D03*
X1339820D03*
Y860993D03*
X1347220D03*
X1332420D03*
Y854584D03*
X1334271Y857789D03*
X1337971D03*
X1341671D03*
X1345371D03*
X1336120Y860993D03*
X1339820Y854584D03*
X1343520Y860993D03*
X1347220Y854584D03*
X1334271Y870606D03*
X1337971D03*
X1341671D03*
X1336120Y873810D03*
X1343520D03*
X1345371Y870606D03*
X1332420Y880219D03*
X1334271Y883423D03*
X1339820Y880219D03*
X1341671Y883423D03*
X1347220Y880219D03*
X1337971Y883423D03*
X1345371D03*
X1339820Y873810D03*
X1332420D03*
X1347220D03*
X1339820Y899445D03*
X1343520D03*
X1347220Y893036D03*
X1339821D03*
X1343521D03*
X1336120Y886627D03*
X1343520D03*
X1347220D03*
X1339820D03*
Y912262D03*
X1337971Y909057D03*
X1343520Y912262D03*
X1345371Y909057D03*
X1337971Y902649D03*
X1345371D03*
X1336120Y905853D03*
X1343520D03*
X1339820D03*
X1347220D03*
X1339820Y931488D03*
X1337971Y928283D03*
X1343520Y931488D03*
X1345371Y928283D03*
X1337971Y921875D03*
X1339820Y918670D03*
X1345371Y921875D03*
X1343520Y918670D03*
X1336120Y925079D03*
X1343520D03*
X1339820D03*
X1347220D03*
X1337971Y941100D03*
X1339820Y937896D03*
X1345371Y941100D03*
X1343520Y937896D03*
X1337971Y947509D03*
X1345371D03*
X1343520Y944304D03*
X1336120D03*
X1347220D03*
X1339820D03*
X1337971Y966735D03*
X1345371D03*
X1336120Y963530D03*
X1339820Y950713D03*
X1343520D03*
X1337971Y960326D03*
X1339820Y957122D03*
X1345371Y960326D03*
X1343520Y957122D03*
X1347220Y963530D03*
X1339820Y969939D03*
X1343520D03*
X1343953Y1002888D03*
X1338404Y1012501D03*
X1345804D03*
X1340253Y1009297D03*
X1343953D03*
X1340253Y1002888D03*
X1338404Y999684D03*
X1347653Y1002888D03*
X1345804Y999684D03*
X1338404Y1031727D03*
X1340253Y1028523D03*
X1345804Y1031727D03*
X1343953Y1028523D03*
X1336553Y1015705D03*
X1347653D03*
X1340253Y1022114D03*
X1338404Y1018910D03*
X1343953Y1022114D03*
X1345804Y1018910D03*
X1340253Y1041340D03*
X1338404Y1038136D03*
X1343953Y1041340D03*
X1345804Y1038136D03*
X1336553Y1034931D03*
X1347653D03*
X1340253D03*
X1343953D03*
X1340253Y1047749D03*
X1343953D03*
X1340253Y1060565D03*
X1338404Y1057361D03*
X1343953Y1060565D03*
X1345804Y1057361D03*
X1338404Y1050952D03*
X1345804D03*
X1336553Y1054157D03*
X1347653D03*
X1340253D03*
X1343953D03*
Y1079791D03*
X1345804Y1076587D03*
X1338404Y1070178D03*
X1340253Y1066974D03*
X1345804Y1070178D03*
X1343953Y1066974D03*
X1340253Y1079791D03*
X1338404Y1076587D03*
X1336553Y1073383D03*
X1347653D03*
X1340253D03*
X1343953D03*
X1338404Y1095813D03*
X1345804D03*
X1338404Y1089404D03*
X1340253Y1086200D03*
X1345804Y1089404D03*
X1343953Y1086200D03*
X1336553Y1092608D03*
X1343953D03*
X1340253D03*
X1347653D03*
X1340253Y1099017D03*
X1343953D03*
X1334704Y1102221D03*
X1345803D03*
X1343953Y1105426D03*
X1336554D03*
X1345803Y1108630D03*
X1340254Y1105426D03*
X1336554Y1111834D03*
X1334703Y1108630D03*
X1343954Y1111834D03*
X1342103Y1108630D03*
X1338403D03*
X1345804Y1121447D03*
X1338403D03*
X1342103Y1115039D03*
X1345803D03*
X1334703D03*
Y1134264D03*
X1338403Y1140973D03*
X1342104Y1134264D03*
X1345803Y1140973D03*
X1332854Y1137469D03*
X1336554D03*
X1340254D03*
X1343954D03*
X1347654D03*
X1338404Y1134264D03*
X1345804D03*
X1352550Y157449D03*
X1355961Y155458D03*
X1352557Y168548D03*
X1355762Y166698D03*
X1349344Y162999D03*
X1348386Y156646D03*
X1352551Y161148D03*
X1352557Y172248D03*
X1349351Y177798D03*
Y170398D03*
Y174098D03*
X1352557Y175948D03*
X1349351Y181498D03*
X1355761Y185198D03*
X1349351D03*
X1355761Y174098D03*
Y181498D03*
X1352557Y183348D03*
X1349351Y192598D03*
X1352551Y187048D03*
X1355761Y188898D03*
X1349361Y199998D03*
X1352561Y201848D03*
X1355766Y214798D03*
X1349351Y218498D03*
X1352561Y216648D03*
X1355766Y218498D03*
X1352561Y220348D03*
X1355766Y222198D03*
X1360186Y226264D03*
X1362020Y848176D03*
X1354620D03*
X1363869Y844971D03*
X1352769D03*
X1356469D03*
X1360169D03*
X1362021Y841467D03*
X1349069Y844971D03*
X1350920Y848176D03*
X1354621Y841467D03*
X1358320Y848176D03*
X1354620Y867401D03*
X1362020D03*
Y860993D03*
X1354620D03*
X1349071Y857789D03*
X1354620Y854584D03*
X1356471Y857789D03*
X1360171D03*
X1363871D03*
X1350920Y860993D03*
X1352771Y857789D03*
X1358320Y860993D03*
X1362020Y854584D03*
X1363871Y870606D03*
X1349071D03*
X1356471D03*
X1350920Y873810D03*
X1352771Y870606D03*
X1358320Y873810D03*
X1360171Y870606D03*
X1349071Y883423D03*
X1354620Y880219D03*
X1356471Y883423D03*
X1362020Y880219D03*
X1363871Y883423D03*
X1352771D03*
X1360171D03*
X1354620Y873810D03*
X1362020D03*
X1350920Y899445D03*
X1358320D03*
Y893036D03*
X1350920D03*
X1362020D03*
X1349071Y896240D03*
X1356471D03*
X1352771D03*
X1360171D03*
X1350920Y886627D03*
X1358320D03*
X1354620D03*
X1362020D03*
X1352771Y902649D03*
X1356471D03*
X1350920Y912262D03*
X1352771Y909057D03*
X1358320Y912262D03*
X1356471Y909057D03*
X1363871D03*
Y902649D03*
X1349071Y915466D03*
X1362020Y905853D03*
X1356471Y915466D03*
X1352771D03*
X1360171D03*
X1350920Y931488D03*
X1352771Y928283D03*
X1358320Y931488D03*
X1356471Y928283D03*
X1363871Y921875D03*
X1352771D03*
X1350920Y918670D03*
X1356471Y921875D03*
X1358320Y918670D03*
X1363871Y928283D03*
X1362020Y925079D03*
X1356471Y941100D03*
X1358320Y937896D03*
X1352771Y947509D03*
X1356471D03*
X1352771Y941100D03*
X1350920Y937896D03*
X1349071Y934691D03*
X1356471D03*
X1352771D03*
X1360171D03*
X1363871Y947509D03*
Y941100D03*
X1362020Y944304D03*
X1352771Y960326D03*
X1350920Y957122D03*
X1356471Y960326D03*
X1358320Y957122D03*
X1350920Y950713D03*
X1358320D03*
X1349071Y953917D03*
X1356471D03*
X1352771D03*
X1360171D03*
X1363871Y960326D03*
Y966735D03*
X1356471D03*
X1352771D03*
X1362020Y963530D03*
Y982756D03*
X1363871Y979552D03*
X1352771D03*
X1356471D03*
X1350920Y976347D03*
X1358320D03*
X1349071Y973143D03*
X1350920Y969939D03*
X1358320D03*
X1360171Y973143D03*
X1349504Y1006093D03*
X1356904D03*
X1353204D03*
X1360604D03*
X1351353Y1002888D03*
X1353204Y999684D03*
X1358753Y1002888D03*
X1356904Y999684D03*
X1353204Y1012501D03*
X1351353Y1009297D03*
X1356904Y1012501D03*
X1358753Y1009297D03*
X1353204Y1031727D03*
X1351353Y1028523D03*
X1356904Y1031727D03*
X1358753Y1028523D03*
X1351353Y1022114D03*
X1353204Y1018910D03*
X1358753Y1022114D03*
X1356904Y1018910D03*
X1353204Y1025318D03*
X1360604D03*
X1349502D03*
X1356902D03*
X1362453Y1015705D03*
X1351353Y1047749D03*
X1358753D03*
X1351353Y1041340D03*
X1353204Y1038136D03*
X1358753Y1041340D03*
X1356904Y1038136D03*
X1349504Y1044544D03*
X1356904D03*
X1353204D03*
X1360604D03*
X1362453Y1034931D03*
X1351353Y1060565D03*
X1353204Y1057361D03*
X1358753Y1060565D03*
X1356904Y1057361D03*
X1353204Y1050952D03*
X1356904D03*
X1349504Y1063770D03*
X1360604D03*
X1353204D03*
X1356904D03*
X1362453Y1054157D03*
X1356904Y1070178D03*
X1358753Y1066974D03*
X1353204Y1070178D03*
X1351353Y1066974D03*
Y1079791D03*
X1353204Y1076587D03*
X1358753Y1079791D03*
X1356904Y1076587D03*
X1362453Y1073383D03*
X1353204Y1089404D03*
X1351353Y1086200D03*
X1356904Y1089404D03*
X1358753Y1086200D03*
X1349504Y1082995D03*
X1362453Y1092608D03*
X1360604Y1082995D03*
X1353204D03*
X1356904D03*
X1351354Y1099017D03*
X1356904Y1095813D03*
X1358753Y1099017D03*
X1362453Y1111834D03*
Y1105426D03*
X1358753D03*
X1351353Y1111834D03*
Y1105426D03*
X1358753Y1111834D03*
X1360604Y1108630D03*
X1355053Y1111834D03*
X1356904Y1102221D03*
X1353204Y1108630D03*
X1355054Y1105426D03*
X1360604Y1121447D03*
X1353204D03*
X1356904Y1115039D03*
X1349504Y1134264D03*
X1353203Y1140973D03*
X1356904Y1134264D03*
X1360603Y1140973D03*
X1351354Y1137469D03*
X1355054D03*
X1358754D03*
X1362454D03*
X1353204Y1134264D03*
X1360604D03*
X1376820Y848176D03*
X1369420D03*
X1367569Y844971D03*
X1369421Y841467D03*
X1373120Y848176D03*
X1376821Y841467D03*
X1365720Y848176D03*
X1371269Y844971D03*
X1374969D03*
X1378669D03*
X1376820Y867401D03*
X1369420D03*
X1376820Y860993D03*
X1369420D03*
X1365720D03*
X1367571Y857789D03*
X1373120Y860993D03*
X1374971Y857789D03*
X1369420Y854584D03*
X1371271Y857789D03*
X1376820Y854584D03*
X1378671Y857789D03*
X1367571Y870606D03*
X1371271D03*
X1378671D03*
X1365720Y873810D03*
X1373120D03*
X1374971Y870606D03*
X1369420Y880219D03*
X1371271Y883423D03*
X1376820Y880219D03*
X1378671Y883423D03*
X1367571D03*
X1374971D03*
X1369420Y873810D03*
X1376820D03*
X1378671Y896240D03*
X1376820Y899445D03*
X1365720D03*
X1369420D03*
X1369421Y893036D03*
X1373121D03*
X1373120Y886627D03*
X1365720D03*
X1374971Y896240D03*
X1376820Y893036D03*
X1369420Y886627D03*
X1376820D03*
X1380520Y899445D03*
X1376820Y905853D03*
X1378671Y915466D03*
Y909057D03*
X1365720Y912262D03*
X1369420D03*
X1371271Y909057D03*
Y902649D03*
X1369420Y905853D03*
X1365720D03*
X1373120D03*
X1376820Y912262D03*
X1378671Y902649D03*
X1376820Y931488D03*
X1378671Y928283D03*
X1369420Y931488D03*
X1371271Y928283D03*
X1365720Y918670D03*
X1371271Y921875D03*
X1369420Y918670D03*
X1365720Y931488D03*
X1369420Y925079D03*
X1365720D03*
X1373120D03*
X1378671Y921875D03*
X1374971Y934691D03*
X1378671D03*
X1371271Y947509D03*
X1365720Y937896D03*
X1371271Y941100D03*
X1369420Y937896D03*
Y944304D03*
X1365720D03*
X1373120D03*
X1378671Y947509D03*
X1365720Y957122D03*
X1371271Y960326D03*
X1369420Y957122D03*
X1371271Y966735D03*
X1365720Y950713D03*
X1369420D03*
X1373120Y963530D03*
X1369420D03*
X1365720D03*
X1378671Y966735D03*
Y960326D03*
Y953917D03*
X1374971D03*
X1376822Y950713D03*
X1374971Y973143D03*
X1376820Y976347D03*
X1378671Y979552D03*
Y973143D03*
X1369420Y982756D03*
X1365720D03*
X1373120D03*
X1369420Y976347D03*
X1371271Y979552D03*
X1365721Y976347D03*
X1365720Y969939D03*
X1369420D03*
X1375404Y1006093D03*
X1379104D03*
X1366153Y1002888D03*
X1364304Y999684D03*
X1369853Y1002888D03*
X1371704Y999684D03*
X1375404D03*
X1379104D03*
X1364304Y1012501D03*
X1371704D03*
X1366153Y1009297D03*
X1369853D03*
X1377253D03*
X1379104Y1012501D03*
Y1031727D03*
X1373553Y1015705D03*
X1364304Y1031727D03*
X1366153Y1028523D03*
X1371704Y1031727D03*
X1369853Y1028523D03*
X1366153Y1022114D03*
X1364304Y1018910D03*
X1369853Y1022114D03*
X1371704Y1018910D03*
X1377253Y1028523D03*
X1375404Y1025318D03*
X1377253Y1022114D03*
X1379102Y1018910D03*
X1379104Y1025318D03*
X1377253Y1015705D03*
X1366153Y1041340D03*
X1364304Y1038136D03*
X1369853Y1041340D03*
X1371704Y1038136D03*
X1366153Y1047749D03*
X1369853D03*
Y1034931D03*
X1366153D03*
X1373553D03*
X1375404Y1044544D03*
X1377253Y1041340D03*
X1379104Y1044544D03*
Y1038136D03*
X1377253Y1047749D03*
X1366153Y1060565D03*
X1364304Y1057361D03*
X1369853Y1060565D03*
X1371704Y1057361D03*
X1364304Y1050952D03*
X1371704D03*
X1369853Y1054157D03*
X1366153D03*
X1373553D03*
X1379104Y1057361D03*
Y1063770D03*
X1377255Y1060565D03*
X1375404Y1063770D03*
X1377253Y1054157D03*
X1379104Y1050952D03*
X1380953Y1054157D03*
X1379104Y1076587D03*
Y1070178D03*
X1366153Y1079791D03*
X1364304Y1076587D03*
X1369853Y1079791D03*
X1371704Y1076587D03*
X1364304Y1070178D03*
X1366153Y1066974D03*
X1371704Y1070178D03*
X1369853Y1066974D03*
Y1073383D03*
X1366153D03*
X1373553D03*
X1377254Y1066974D03*
X1371704Y1095813D03*
X1364304Y1089404D03*
X1366153Y1086200D03*
X1371704Y1089404D03*
X1369853Y1086200D03*
X1364304Y1095813D03*
X1369853Y1092608D03*
X1366153D03*
X1373553D03*
X1375404Y1082995D03*
X1379104D03*
X1379103Y1089404D03*
X1369853Y1099017D03*
X1366153D03*
X1368004Y1102221D03*
X1369853Y1105426D03*
Y1111834D03*
X1368004Y1108630D03*
X1377253Y1099017D03*
X1379104Y1108630D03*
X1373553Y1105426D03*
X1371704Y1108630D03*
X1379104Y1102221D03*
X1377253Y1111834D03*
X1375404Y1108630D03*
X1368004Y1121447D03*
X1375404Y1115039D03*
X1368004D03*
X1379104D03*
X1375404Y1121447D03*
X1368003Y1140973D03*
X1371704Y1134264D03*
X1375403Y1140973D03*
X1379104Y1134264D03*
X1364304D03*
X1366154Y1137469D03*
X1369854D03*
X1373554D03*
X1377254D03*
X1368004Y1134264D03*
X1375404D03*
X1374847Y1153069D03*
X1391620Y848176D03*
X1384220D03*
X1380520D03*
X1386069Y844971D03*
X1389769D03*
X1393469D03*
X1382369D03*
X1384221Y841467D03*
X1387920Y848176D03*
X1391621Y841467D03*
X1395320Y848176D03*
X1384220Y867401D03*
X1391620D03*
X1384220Y860993D03*
X1391620D03*
X1380520D03*
X1382371Y857789D03*
X1387920Y860993D03*
X1389771Y857789D03*
X1395320Y860993D03*
X1384220Y854584D03*
X1386071Y857789D03*
X1391620Y854584D03*
X1393471Y857789D03*
X1380520Y873810D03*
X1382371Y870606D03*
X1384220Y880219D03*
X1386071Y883423D03*
X1382371D03*
X1395320Y873810D03*
X1393471Y870606D03*
X1387920Y873810D03*
X1389771Y870606D03*
X1391620Y873810D03*
X1384220D03*
X1386071Y896240D03*
X1389771D03*
X1393471D03*
X1387920Y899445D03*
X1391620Y893036D03*
X1395320Y899445D03*
X1380520Y886627D03*
X1387920D03*
X1380520Y893036D03*
X1382371Y896240D03*
X1384220Y886627D03*
X1391620D03*
Y899445D03*
X1384221Y899446D03*
X1393471Y909057D03*
X1382371D03*
X1389771D03*
Y915466D03*
X1399020Y905853D03*
X1382371Y915466D03*
X1384220Y918670D03*
X1387920Y905853D03*
X1384220D03*
Y912262D03*
X1382371Y902649D03*
X1391620Y905853D03*
X1387920Y912262D03*
X1391620D03*
X1393471Y915466D03*
X1391621Y918670D03*
X1382371Y921875D03*
X1382809Y927986D03*
X1385070Y928468D03*
X1393471Y921875D03*
X1391550Y925219D03*
X1387921Y918670D03*
X1386030Y942163D03*
X1383730D03*
X1381430D03*
X1392534Y942097D03*
X1394834D03*
X1393826Y956619D03*
X1387826D03*
X1391326D03*
X1385526D03*
X1380926Y971099D03*
X1383226D03*
X1387826D03*
X1385526D03*
X1396346D03*
X1396286Y985549D03*
X1388506Y985609D03*
X1386206D03*
X1385526Y1014539D03*
X1387826D03*
X1383226D03*
X1386226Y1000079D03*
X1396356Y1000039D03*
X1388526Y1000079D03*
X1396546Y1014469D03*
X1388102Y1028854D03*
X1390602D03*
X1393102D03*
X1395602D03*
X1380953Y1041340D03*
X1388353D03*
X1392053D03*
X1395753D03*
Y1047749D03*
X1392053D03*
X1382804Y1044544D03*
X1386504D03*
X1384653Y1047749D03*
X1390204Y1044544D03*
X1382804Y1050952D03*
Y1057361D03*
X1386504D03*
X1390204Y1050952D03*
X1393904Y1057361D03*
X1395753Y1054157D03*
X1382804Y1063770D03*
X1384653Y1060565D03*
X1386504Y1063770D03*
X1388353Y1054157D03*
X1390204Y1057361D03*
X1393904Y1063770D03*
X1390204D03*
X1395753Y1060565D03*
Y1079791D03*
X1384653Y1073383D03*
X1382804Y1070178D03*
X1380953Y1073383D03*
X1393904Y1076587D03*
X1392053Y1079791D03*
X1384653Y1066974D03*
X1388353Y1073383D03*
X1392053D03*
X1390204Y1070178D03*
X1393904D03*
X1388353Y1066974D03*
X1395753D03*
X1384653Y1079791D03*
X1395754Y1099017D03*
X1380953Y1092608D03*
X1393904Y1095813D03*
X1390203D03*
X1388353Y1086200D03*
X1386504Y1082995D03*
X1390204Y1089404D03*
X1382804D03*
X1390204Y1082995D03*
X1382804D03*
X1395753Y1086200D03*
Y1092608D03*
X1380953Y1086200D03*
X1386504Y1089404D03*
X1384653Y1092608D03*
X1380953Y1099017D03*
X1395753Y1105426D03*
X1393904Y1108630D03*
X1390204Y1102221D03*
X1392053Y1111834D03*
X1388353D03*
X1384653Y1105426D03*
Y1099017D03*
X1392053Y1105426D03*
X1395753Y1111834D03*
X1388353Y1105426D03*
X1384653Y1111834D03*
X1386504Y1108630D03*
X1392054Y1124651D03*
X1393903Y1121447D03*
Y1127856D03*
X1395754Y1118243D03*
Y1124651D03*
X1390204Y1115039D03*
X1382803Y1121447D03*
X1390204Y1127856D03*
X1382803Y1140973D03*
X1386504Y1134264D03*
X1380954Y1137469D03*
X1384654D03*
X1382804Y1134264D03*
X1390203Y1140973D03*
X1392054Y1131060D03*
Y1137469D03*
X1393903Y1134264D03*
Y1140973D03*
X1395754Y1131060D03*
Y1137469D03*
X1388354D03*
X1399020Y848176D03*
X1397169Y844971D03*
X1399021Y841467D03*
X1402720Y848176D03*
X1406420D03*
X1411969Y844971D03*
X1400869D03*
X1404569D03*
X1410120Y848176D03*
X1406420Y867401D03*
X1399020D03*
X1406420Y860993D03*
X1399020D03*
X1397171Y857789D03*
X1402720Y860993D03*
X1404571Y857789D03*
X1410121Y860993D03*
X1411971Y857789D03*
X1399020Y854584D03*
X1400871Y857789D03*
X1406420Y854584D03*
X1408271Y857789D03*
Y870606D03*
X1402720Y873810D03*
X1400871Y870606D03*
X1410121Y873810D03*
X1404571Y870606D03*
X1397171D03*
X1411971D03*
X1399020Y873810D03*
X1406420D03*
X1397171Y896240D03*
X1402720Y899445D03*
X1404571Y896240D03*
X1410120Y899445D03*
X1399020Y893036D03*
X1400871Y896240D03*
X1406420Y893036D03*
X1408271Y896240D03*
X1411971D03*
X1406420Y886627D03*
X1399020D03*
X1406420Y899445D03*
X1399020D03*
Y912262D03*
X1400871Y915466D03*
X1402720Y912262D03*
X1406420D03*
X1408271Y915466D03*
X1397171Y909057D03*
X1411971D03*
Y915466D03*
X1408270Y909057D03*
X1410120Y905853D03*
X1400870Y909057D03*
X1406420Y905853D03*
X1402720D03*
X1397171Y915466D03*
X1410121Y912262D03*
X1406420Y918670D03*
X1408271Y921875D03*
X1410121Y918670D03*
X1411971Y921875D03*
X1401528Y927155D03*
X1399028D03*
X1401817Y929464D03*
X1399317D03*
X1400871Y921875D03*
X1399020Y918670D03*
X1397171Y921875D03*
X1402720Y918670D03*
X1411971Y934691D03*
X1406420Y925079D03*
X1408271Y928283D03*
X1406420Y931488D03*
X1411971Y928283D03*
X1406421Y944304D03*
X1408271Y941100D03*
X1411971D03*
X1404016Y944229D03*
Y941929D03*
X1408270Y947509D03*
X1411971D03*
X1408271Y934691D03*
X1406421Y950713D03*
Y957122D03*
X1408270Y953917D03*
Y960326D03*
X1411971Y953917D03*
Y960326D03*
X1404016Y954072D03*
Y956372D03*
X1401326Y956619D03*
X1398826D03*
X1406421Y963530D03*
X1408270Y966735D03*
X1411971D03*
X1406421Y969939D03*
X1406409Y976347D03*
X1408270Y973143D03*
X1411971D03*
X1404016Y971266D03*
Y968966D03*
X1398826Y971099D03*
X1406421Y982756D03*
X1408270Y979552D03*
X1411971D03*
X1404016Y983110D03*
Y985410D03*
X1398826Y985579D03*
X1404016Y997520D03*
X1412404Y999684D03*
Y1006093D03*
Y1012501D03*
X1406853Y1002888D03*
Y1009297D03*
X1408703Y999684D03*
Y1006093D03*
Y1012501D03*
X1404016Y1012151D03*
Y999820D03*
X1398826Y1000059D03*
X1404016Y1014451D03*
X1399156Y1014469D03*
X1398102Y1028854D03*
X1406853Y1028523D03*
X1412404Y1018910D03*
X1406853Y1015705D03*
Y1022114D03*
X1408703Y1018910D03*
X1412404Y1025318D03*
X1408703D03*
X1404016Y1026703D03*
X1412404Y1031727D03*
X1408703D03*
X1404016Y1029003D03*
Y1031303D03*
X1403153Y1047749D03*
X1403154Y1041340D03*
X1399454D03*
X1401304Y1044544D03*
X1412403Y1038136D03*
Y1044544D03*
X1406853Y1034931D03*
Y1041340D03*
X1408703Y1038136D03*
Y1044544D03*
X1410554Y1041340D03*
X1404016Y1033603D03*
X1399426Y1036883D03*
Y1034583D03*
Y1032283D03*
X1410554Y1047749D03*
X1397604Y1044544D03*
X1403153Y1054157D03*
X1406853D03*
X1405003Y1057361D03*
X1408703D03*
Y1063770D03*
X1412404Y1050952D03*
Y1057361D03*
Y1063770D03*
X1397604Y1057361D03*
X1401304Y1050952D03*
X1399453Y1054157D03*
X1405004Y1050952D03*
X1397604D03*
X1401304Y1063770D03*
X1399453Y1060565D03*
X1403153D03*
X1405003Y1063770D03*
X1406853Y1060565D03*
X1397604Y1076587D03*
X1408702Y1070178D03*
X1399453Y1073383D03*
Y1079791D03*
X1412404Y1070178D03*
Y1076587D03*
X1397604Y1070178D03*
X1401304D03*
X1405004D03*
X1406853Y1066974D03*
X1405003Y1076587D03*
X1406853Y1079791D03*
X1412404Y1082995D03*
Y1089404D03*
X1412403Y1095813D03*
X1401304Y1082995D03*
X1405003Y1089404D03*
X1399453Y1086200D03*
X1406853Y1092608D03*
X1399453D03*
X1397604Y1089404D03*
X1403154Y1086200D03*
X1406852D03*
X1403153Y1092608D03*
X1401304Y1095813D03*
X1397604Y1102221D03*
X1399453Y1099017D03*
X1412404Y1102221D03*
Y1108630D03*
X1401304D03*
X1403154Y1105426D03*
Y1111834D03*
X1405003Y1102221D03*
Y1108630D03*
X1406853Y1099017D03*
Y1105426D03*
Y1111834D03*
X1408703Y1102221D03*
Y1108630D03*
X1410554Y1099017D03*
X1412404Y1115039D03*
Y1121447D03*
Y1127856D03*
X1397603Y1121447D03*
Y1127856D03*
X1401304Y1115039D03*
Y1121447D03*
Y1127856D03*
X1403154Y1118243D03*
Y1124651D03*
X1405003Y1115039D03*
Y1121447D03*
Y1127856D03*
X1406853Y1118243D03*
Y1124651D03*
X1408703Y1115039D03*
Y1121447D03*
Y1127856D03*
X1412403Y1134264D03*
X1397603D03*
Y1140973D03*
X1401304Y1134264D03*
X1401303Y1140973D03*
X1403154Y1131060D03*
Y1137569D03*
X1405003Y1134264D03*
Y1140973D03*
X1406853Y1131060D03*
Y1137769D03*
X1408703Y1134264D03*
X1413820Y848176D03*
X1428620Y867401D03*
X1421220D03*
X1413820D03*
X1421220Y860993D03*
X1428621D03*
X1424921D03*
X1421220Y854584D03*
X1417520Y860993D03*
X1428620Y854584D03*
X1426771Y857789D03*
X1423071D03*
X1419371D03*
X1413821Y854584D03*
X1424921Y873810D03*
X1423071Y870606D03*
X1417520Y873810D03*
X1415671Y870606D03*
X1426771D03*
X1419371D03*
X1413821Y873810D03*
X1428621D03*
X1421220D03*
X1413820Y893036D03*
X1421220Y899445D03*
X1419371Y896240D03*
X1424920Y899445D03*
X1426772Y896240D03*
X1417520Y899445D03*
X1421220Y893036D03*
X1423071Y896240D03*
X1428621Y893036D03*
X1428620Y899445D03*
Y886627D03*
X1421220D03*
X1419371Y909057D03*
X1415671Y915466D03*
X1421221Y905853D03*
X1417521D03*
X1430471Y909057D03*
X1426772D03*
X1428621Y905853D03*
X1424921D03*
X1424922Y912262D03*
X1417522D03*
X1415671Y909057D03*
X1421222Y912262D03*
X1419371Y915466D03*
X1426771D03*
X1428620Y912262D03*
X1424921Y918670D03*
X1430471Y915466D03*
X1415671Y921875D03*
X1417520Y918670D03*
X1426771Y921875D03*
X1421220Y918670D03*
X1419371Y921875D03*
X1428620Y918670D03*
X1424921Y931488D03*
X1419371Y928283D03*
X1413820Y931488D03*
X1424921Y925079D03*
X1419371Y934691D03*
X1421220Y931488D03*
Y925079D03*
X1415671Y928283D03*
X1413820Y925079D03*
X1426771Y928283D03*
X1413821Y944304D03*
X1415671Y941100D03*
X1417521Y944304D03*
X1419371Y941100D03*
X1421220Y944304D03*
X1424921D03*
X1426771Y941100D03*
X1415670Y947509D03*
X1419370D03*
X1426771D03*
X1423071Y934691D03*
X1415671D03*
X1413821Y950713D03*
Y957122D03*
X1415670Y953917D03*
Y960326D03*
X1417521Y950713D03*
Y957122D03*
X1419370Y953917D03*
Y960326D03*
X1421220Y950713D03*
Y957122D03*
X1424921Y950713D03*
Y957122D03*
X1426771Y953917D03*
Y960326D03*
X1413821Y963530D03*
X1415670Y966735D03*
X1417521Y963530D03*
X1419370Y966735D03*
X1421220Y963530D03*
X1424921D03*
X1426771Y966735D03*
X1413821Y969939D03*
Y976347D03*
X1415670Y973143D03*
X1417521Y969939D03*
Y976347D03*
X1419370Y973143D03*
X1421220Y969939D03*
Y976347D03*
X1424921Y969939D03*
Y976347D03*
X1426771Y973143D03*
X1413821Y982756D03*
X1415670Y979552D03*
X1417521Y982756D03*
X1419370Y979552D03*
X1421220Y982756D03*
X1424921D03*
X1426771Y979552D03*
X1414254Y1002888D03*
Y1009297D03*
X1416103Y999684D03*
Y1006093D03*
Y1012501D03*
X1417954Y1002888D03*
Y1009297D03*
X1419803Y999684D03*
Y1006093D03*
Y1012501D03*
X1421653Y1002888D03*
Y1009297D03*
X1425354Y1002888D03*
Y1009297D03*
X1427203Y999684D03*
Y1006093D03*
Y1012501D03*
X1421653Y1028523D03*
X1414254D03*
X1417954D03*
X1425354D03*
X1414254Y1015705D03*
Y1022114D03*
X1416103Y1018910D03*
X1417954Y1015705D03*
Y1022114D03*
X1419803Y1018910D03*
X1421653Y1015705D03*
Y1022114D03*
X1425354Y1015705D03*
Y1022114D03*
X1427203Y1018910D03*
X1416103Y1025318D03*
X1419803D03*
X1427203D03*
X1416103Y1031727D03*
X1419803D03*
X1427203D03*
X1429053Y1047749D03*
X1414254Y1034931D03*
Y1041340D03*
X1416103Y1038136D03*
Y1044544D03*
X1417954Y1034931D03*
Y1041340D03*
X1419803Y1038136D03*
Y1044544D03*
X1421653Y1034931D03*
Y1041340D03*
X1423503Y1044544D03*
X1425354Y1034931D03*
X1425353Y1041340D03*
X1427203Y1038136D03*
X1421653Y1047749D03*
X1414254D03*
X1417954D03*
X1425353Y1054157D03*
X1425355Y1060565D03*
X1414254Y1054157D03*
X1416103Y1050952D03*
X1417954Y1054157D03*
X1419803Y1050952D03*
X1421653Y1054157D03*
X1414254Y1060565D03*
X1416103Y1057361D03*
X1417954Y1060565D03*
X1419803Y1057361D03*
X1421653Y1060565D03*
X1416103Y1063770D03*
X1419803D03*
X1427203D03*
X1429053Y1054157D03*
X1427203Y1050952D03*
X1430903D03*
X1430904Y1057361D03*
X1427204D03*
X1429053Y1073383D03*
X1427203Y1076587D03*
X1414254Y1066974D03*
Y1073383D03*
X1416103Y1070178D03*
Y1076587D03*
X1417954Y1066974D03*
Y1073383D03*
X1419803Y1070178D03*
Y1076587D03*
X1421653Y1066974D03*
Y1073383D03*
X1414254Y1079791D03*
X1417954D03*
X1421653D03*
X1429053Y1066974D03*
X1425353D03*
X1427204Y1070178D03*
X1429053Y1086200D03*
X1416103Y1082995D03*
X1419803D03*
X1414254Y1086200D03*
Y1092608D03*
X1416103Y1089404D03*
Y1095813D03*
X1417954Y1086200D03*
Y1092608D03*
X1419803Y1089404D03*
Y1095813D03*
X1421653Y1086200D03*
Y1092608D03*
X1423503Y1089404D03*
Y1095813D03*
X1425353Y1092608D03*
X1427202Y1082995D03*
X1414254Y1099017D03*
Y1105426D03*
Y1111834D03*
X1416103Y1102221D03*
Y1108630D03*
X1417954Y1099017D03*
Y1105426D03*
Y1111834D03*
X1419803Y1102221D03*
Y1108630D03*
X1421653Y1099017D03*
Y1105426D03*
Y1111834D03*
X1425354Y1099017D03*
Y1105426D03*
Y1111834D03*
X1427203Y1102221D03*
Y1108630D03*
X1429054Y1105426D03*
Y1111834D03*
X1414254Y1118243D03*
Y1124651D03*
X1416103Y1115039D03*
Y1121447D03*
Y1127856D03*
X1417954Y1118243D03*
Y1124651D03*
X1419803Y1115039D03*
Y1121447D03*
Y1127856D03*
X1421653Y1118243D03*
Y1124651D03*
X1425354Y1118243D03*
Y1124651D03*
X1427203Y1115039D03*
Y1121447D03*
Y1127856D03*
X1429054Y1118243D03*
Y1124651D03*
X1414254Y1131060D03*
Y1137769D03*
X1416103Y1134264D03*
X1417954Y1131060D03*
Y1137769D03*
X1419803Y1134264D03*
X1421653Y1131060D03*
Y1137769D03*
X1425354Y1131060D03*
Y1137769D03*
X1427203Y1134264D03*
X1429054Y1131060D03*
Y1137769D03*
X1443420Y848176D03*
X1436020D03*
X1443420Y867401D03*
X1436020D03*
X1443420Y860993D03*
X1436020D03*
X1445271Y857789D03*
X1439720Y860993D03*
X1437871Y857789D03*
X1432320Y860993D03*
X1430471Y857789D03*
X1443420Y854584D03*
X1441571Y857789D03*
X1436020Y854584D03*
X1434171Y857789D03*
X1445271Y870606D03*
X1439720Y873810D03*
X1437871Y870606D03*
X1432320Y873810D03*
X1430471Y870606D03*
X1441571D03*
X1434171D03*
X1436020Y873810D03*
X1443420D03*
X1430471Y896240D03*
X1436020Y893036D03*
X1437871Y896240D03*
X1441571D03*
X1432320Y899445D03*
X1434171Y896240D03*
X1439720Y899445D03*
X1443420Y893036D03*
X1436020Y899445D03*
X1443420D03*
X1436020Y886627D03*
X1443420D03*
X1447120Y899445D03*
X1445271Y902649D03*
X1434171Y909057D03*
X1437871Y915466D03*
X1443420Y912262D03*
X1445271Y915466D03*
X1437871Y909057D03*
X1434171Y915466D03*
X1436020Y918670D03*
X1439720Y912262D03*
X1436020D03*
Y905853D03*
X1439720D03*
X1443420D03*
X1445271Y909057D03*
X1430471Y921875D03*
X1443420Y918670D03*
X1439777Y928348D03*
X1437477D03*
X1435177D03*
X1444377D03*
X1442077D03*
X1445271Y921875D03*
X1439720Y918670D03*
X1441571Y921875D03*
X1434171D03*
X1445392Y942195D03*
X1429726Y944537D03*
Y939937D03*
Y942237D03*
X1429544Y959298D03*
Y956998D03*
X1437565Y956619D03*
X1434545D03*
X1445045D03*
X1429544Y970798D03*
Y973098D03*
X1437565Y971139D03*
X1434545Y971099D03*
X1429544Y986898D03*
Y984598D03*
X1437565Y985579D03*
X1434545D03*
X1445045D03*
X1429544Y998398D03*
Y1012198D03*
Y1000698D03*
X1437565Y1000079D03*
X1434545D03*
X1445045D03*
X1429544Y1014498D03*
X1437436Y1014509D03*
X1434545Y1014539D03*
X1445036Y1014549D03*
X1439321Y1028854D03*
X1436821D03*
X1434321D03*
X1441821D03*
X1434083Y1031908D03*
X1447553Y1041340D03*
X1443853D03*
X1436453Y1047750D03*
X1443853D03*
X1430904Y1044544D03*
Y1038136D03*
X1434083Y1034408D03*
X1434813Y1037069D03*
X1439413D03*
X1437113D03*
X1432753Y1041340D03*
X1440153D03*
X1438304Y1044544D03*
X1434604D03*
X1432753Y1060565D03*
X1438303Y1057361D03*
Y1063770D03*
X1442002Y1050952D03*
X1440153Y1054157D03*
X1436454D03*
X1434604Y1057361D03*
X1443854Y1054157D03*
Y1060565D03*
X1430903Y1063770D03*
X1440154Y1060565D03*
X1434603Y1050952D03*
X1436453Y1060565D03*
Y1073383D03*
X1434602Y1070178D03*
X1436453Y1066974D03*
X1440153D03*
X1442002Y1070178D03*
X1447553Y1066974D03*
X1440154Y1079791D03*
X1436454D03*
X1438304Y1076587D03*
X1432753Y1066974D03*
X1442004Y1076587D03*
X1440153Y1073383D03*
X1434604Y1076587D03*
X1438304Y1082995D03*
X1442004D03*
X1438303Y1095812D03*
X1434603D03*
X1442003Y1089403D03*
X1432754Y1092607D03*
X1430903Y1089403D03*
X1436454Y1086199D03*
X1430902Y1082995D03*
X1442003Y1095812D03*
X1440154Y1092607D03*
X1430903Y1095812D03*
X1434603Y1089403D03*
X1438303D03*
X1438304Y1102221D03*
X1443853Y1099017D03*
X1430903Y1102221D03*
Y1108630D03*
X1432754Y1105426D03*
X1432753Y1111834D03*
X1434603Y1108630D03*
X1436454Y1111834D03*
Y1099016D03*
X1430903Y1115039D03*
Y1121447D03*
Y1127856D03*
X1432753Y1118243D03*
Y1124651D03*
X1436454Y1118243D03*
Y1124651D03*
X1438303Y1115039D03*
Y1121447D03*
Y1127856D03*
X1440153Y1118243D03*
X1440154Y1124651D03*
X1442003Y1127856D03*
X1443854Y1131060D03*
Y1137469D03*
X1430903Y1134264D03*
Y1140973D03*
X1432753Y1131060D03*
X1432754Y1137469D03*
X1434603Y1140973D03*
X1436454Y1131060D03*
Y1137469D03*
X1438303Y1134264D03*
Y1140973D03*
X1440154Y1131060D03*
Y1137469D03*
X1442003Y1134264D03*
Y1140973D03*
X1450820Y848176D03*
X1458220D03*
X1450820Y867401D03*
X1458220D03*
X1450820Y860993D03*
X1458220D03*
X1460071Y857789D03*
X1454520Y860993D03*
X1452671Y857789D03*
X1447120Y860993D03*
X1458220Y854584D03*
X1456371Y857789D03*
X1450820Y854584D03*
X1448971Y857789D03*
X1456371Y870606D03*
X1452671D03*
X1454520Y873810D03*
X1460071Y870606D03*
X1450820Y880219D03*
X1452671Y883423D03*
X1458220Y880219D03*
X1460071Y883423D03*
X1448971D03*
X1456371D03*
X1458220Y873810D03*
X1450820D03*
Y893036D03*
X1448971Y896240D03*
X1458220Y893036D03*
X1460071Y896240D03*
X1454520Y886627D03*
Y899445D03*
X1458220Y886627D03*
X1450820D03*
X1452671Y896240D03*
X1456371Y902649D03*
X1460071Y915466D03*
X1456371D03*
X1447122Y912262D03*
X1454521Y918670D03*
X1452671Y915466D03*
X1454522Y912262D03*
X1448971Y902649D03*
X1456370Y909057D03*
X1458220Y905853D03*
X1452671Y902649D03*
X1448970Y915466D03*
X1447120Y905853D03*
X1454520D03*
X1448971Y909057D03*
X1452671D03*
X1456371Y928283D03*
X1454522Y931488D03*
X1454520Y925079D03*
X1458220D03*
X1448971Y921875D03*
X1447120Y918670D03*
X1446677Y928348D03*
X1454520Y937896D03*
X1456371Y941100D03*
X1460071Y934691D03*
X1456371Y947509D03*
X1449992Y942195D03*
X1447692D03*
X1454520Y963530D03*
X1456371Y966735D03*
X1458220Y963529D03*
X1460071Y953917D03*
X1456370Y960326D03*
X1456371Y953917D03*
X1454520Y957122D03*
Y950713D03*
X1447545Y956619D03*
X1460071Y973143D03*
X1458220Y982756D03*
X1454521Y969939D03*
X1450045Y971099D03*
X1445445D03*
X1447745D03*
X1452426Y973825D03*
Y971525D03*
X1456371Y979552D03*
X1454520Y982756D03*
X1456371Y973143D03*
X1454520Y976347D03*
X1447545Y985579D03*
X1456804Y999684D03*
X1454953Y1002888D03*
Y1009297D03*
X1456804Y1012501D03*
X1460504Y1006093D03*
X1447545Y1000079D03*
X1447345Y1014539D03*
X1460504Y1025318D03*
X1456804Y1031727D03*
X1454953Y1028523D03*
Y1022114D03*
X1456803Y1018910D03*
X1454953Y1015705D03*
X1446934Y1028889D03*
X1452466Y1031794D03*
Y1029494D03*
Y1027194D03*
X1456804Y1025318D03*
X1458653Y1015705D03*
X1460504Y1044544D03*
X1451253Y1047749D03*
X1445704Y1044544D03*
X1454953Y1034931D03*
X1456804Y1038136D03*
X1454953Y1041340D03*
X1456804Y1044544D03*
X1449404D03*
X1454953Y1047749D03*
X1453104Y1044544D03*
X1460504Y1063770D03*
X1456804D03*
X1458653Y1054157D03*
X1454954D03*
X1453104Y1057361D03*
Y1063770D03*
X1454954Y1060565D03*
X1456803Y1057361D03*
X1453103Y1050952D03*
X1445703Y1057361D03*
X1445704Y1063770D03*
X1447554Y1060565D03*
X1449403Y1057361D03*
X1449404Y1063770D03*
X1451254Y1054157D03*
X1445703Y1050952D03*
X1449404D03*
X1454953Y1066974D03*
X1445702Y1070178D03*
X1453104Y1076587D03*
X1456804D03*
Y1070178D03*
X1453104D03*
X1447553Y1073383D03*
X1449404Y1076587D03*
X1445704D03*
X1447553Y1079791D03*
X1451253Y1073383D03*
X1458653D03*
X1460504Y1082995D03*
X1445704D03*
X1456804Y1089404D03*
X1449404Y1095813D03*
X1454954Y1092607D03*
X1451254D03*
X1449403Y1089403D03*
X1447554Y1086199D03*
X1453103Y1082994D03*
X1458654Y1092607D03*
X1453103Y1095812D03*
X1447554Y1092607D03*
X1451254Y1086199D03*
X1454954D03*
X1456804Y1102221D03*
Y1121447D03*
X1449404D03*
X1460504Y1134264D03*
X1458654Y1137469D03*
X1453104Y1134264D03*
X1451254Y1137469D03*
X1456803Y1140973D03*
X1454954Y1137469D03*
X1449403Y1140973D03*
X1456804Y1134264D03*
X1445703D03*
X1465620Y848176D03*
X1473020D03*
X1465620Y867401D03*
X1473020D03*
X1465620Y860993D03*
X1473020D03*
X1467471Y857789D03*
X1461920Y860993D03*
X1476720D03*
X1474871Y857789D03*
X1471171D03*
X1465620Y854584D03*
X1463771Y857789D03*
X1473020Y854584D03*
X1469320Y860993D03*
X1463771Y870606D03*
X1471171D03*
X1461920Y873810D03*
X1467471Y870606D03*
X1469320Y873810D03*
X1474871Y870606D03*
X1476720Y873810D03*
X1465620Y880219D03*
X1467471Y883423D03*
X1473020Y880219D03*
X1474871Y883423D03*
X1463771D03*
X1471171D03*
X1473020Y873810D03*
X1465620D03*
X1476720Y899445D03*
X1461920D03*
X1469320D03*
Y893036D03*
X1473020D03*
X1461920D03*
X1467471Y896240D03*
X1463771D03*
X1471171D03*
X1461920Y886627D03*
X1469320D03*
X1476720D03*
X1473020D03*
X1465620D03*
X1461920Y912262D03*
X1463771Y909057D03*
X1469320Y912262D03*
X1467471Y909057D03*
X1476720Y912262D03*
X1474871Y909057D03*
Y902649D03*
X1463771D03*
X1467471D03*
X1463771Y915466D03*
X1476720Y905853D03*
X1471171Y915466D03*
X1473020Y905853D03*
X1467471Y915466D03*
X1476720Y931488D03*
X1474871Y921875D03*
X1476720Y918670D03*
X1474871Y928283D03*
X1473020Y925079D03*
X1476720D03*
X1467471Y921875D03*
X1469320Y918670D03*
X1461920Y931488D03*
X1467471Y928283D03*
X1469320Y931488D03*
X1463771Y928283D03*
Y921875D03*
X1461920Y918670D03*
X1474871Y947509D03*
Y941100D03*
X1476720Y937896D03*
X1473020Y944304D03*
X1476720D03*
X1463771Y947509D03*
X1467471D03*
X1463771Y941100D03*
X1461920Y937896D03*
X1467471Y941100D03*
X1469320Y937896D03*
X1463771Y934691D03*
X1471171D03*
X1467471D03*
X1476720Y950713D03*
X1463771Y966735D03*
X1467471D03*
X1474871D03*
X1473020Y963530D03*
X1461920Y950713D03*
X1469320D03*
X1467471Y960326D03*
X1469320Y957122D03*
X1463771Y960326D03*
X1461920Y957122D03*
X1476720D03*
X1474871Y960326D03*
X1471171Y953917D03*
X1463771D03*
X1467471D03*
X1463771Y979552D03*
X1461920Y976347D03*
X1467471Y979552D03*
X1469320Y976347D03*
X1476720Y982756D03*
X1473020D03*
X1474871Y979552D03*
X1476720Y976347D03*
X1471171Y973143D03*
X1463771D03*
X1467471D03*
X1461920Y969939D03*
X1469320D03*
X1476720D03*
X1477153Y1002888D03*
X1475304Y999684D03*
Y1012501D03*
X1477153Y1009297D03*
X1471604Y1006093D03*
X1462353Y1002888D03*
X1469753D03*
X1464204Y999684D03*
X1467904D03*
X1467903Y1012501D03*
X1469753Y1009297D03*
X1464204Y1012501D03*
X1462353Y1009297D03*
X1473453Y1015705D03*
X1475304Y1031727D03*
X1477153Y1028523D03*
Y1022114D03*
X1475304Y1018910D03*
X1464204Y1031727D03*
X1462353Y1028523D03*
X1467904Y1031727D03*
X1469753Y1028523D03*
X1462353Y1022114D03*
X1464204Y1018910D03*
X1469753Y1022114D03*
X1467904Y1018910D03*
X1464204Y1025318D03*
X1471604D03*
X1467904D03*
X1477153Y1041340D03*
X1475304Y1038136D03*
X1477153Y1047749D03*
Y1034931D03*
X1473453D03*
X1462353Y1047749D03*
X1469753D03*
X1462353Y1041340D03*
X1464204Y1038136D03*
X1469753Y1041340D03*
X1467904Y1038136D03*
X1464204Y1044544D03*
X1471604D03*
X1467904D03*
X1477153Y1060565D03*
X1475304Y1057361D03*
Y1050952D03*
X1477153Y1054157D03*
X1473453D03*
X1462353Y1060565D03*
X1464204Y1057361D03*
X1469753Y1060565D03*
X1467904Y1057361D03*
X1464204Y1050952D03*
X1467904D03*
X1464204Y1063770D03*
X1471604D03*
X1467904D03*
X1475304Y1070178D03*
X1477153Y1066974D03*
Y1079791D03*
X1475304Y1076587D03*
X1473453Y1073383D03*
X1477153D03*
X1462353Y1079791D03*
X1464204Y1076587D03*
X1469753Y1079791D03*
X1467904Y1076587D03*
X1464204Y1070178D03*
X1462353Y1066974D03*
X1467904Y1070178D03*
X1469753Y1066974D03*
X1467904Y1089404D03*
X1469753Y1086200D03*
X1475304Y1089404D03*
X1477153Y1086200D03*
X1464204Y1089404D03*
X1462353Y1086200D03*
X1473453Y1092608D03*
X1471604Y1082995D03*
X1477153Y1092608D03*
X1464204Y1082995D03*
X1467904D03*
X1464204Y1095813D03*
X1477154Y1105426D03*
Y1111833D03*
X1464204Y1115039D03*
Y1121447D03*
X1469754Y1137469D03*
X1464203Y1140973D03*
X1477154Y1137469D03*
X1471603Y1140973D03*
X1467904Y1134264D03*
X1466054Y1137469D03*
X1462354D03*
X1475304Y1134264D03*
X1473454Y1137469D03*
X1471604Y1134264D03*
X1464204D03*
X1487820Y848176D03*
X1480420D03*
X1487820Y867401D03*
X1480420D03*
X1487820Y860993D03*
X1480420D03*
X1491520D03*
X1489671Y857789D03*
X1484120Y860993D03*
X1482271Y857789D03*
X1493371D03*
X1487820Y854584D03*
X1485971Y857789D03*
X1480420Y854584D03*
X1478571Y857789D03*
X1493371Y870606D03*
X1478571D03*
X1485971D03*
X1489671D03*
X1491520Y873810D03*
X1482271Y870606D03*
X1484120Y873810D03*
X1487820Y880219D03*
X1489671Y883423D03*
X1480420Y880219D03*
X1482271Y883423D03*
X1485971D03*
X1493371D03*
X1478571D03*
X1487820Y873810D03*
X1480420D03*
X1487820Y899445D03*
Y893036D03*
X1484120D03*
X1485971Y896240D03*
X1493371D03*
X1489671D03*
X1480420Y899445D03*
X1491520Y886627D03*
X1484120D03*
X1480420D03*
X1487820D03*
X1489671Y902649D03*
X1493371D03*
X1487820Y912262D03*
X1489671Y909057D03*
X1493371D03*
X1489671Y915466D03*
X1485971D03*
X1493371D03*
X1480420Y912262D03*
X1482271Y909057D03*
Y902649D03*
X1484120Y905853D03*
X1480420D03*
X1487820Y931488D03*
X1489671Y928283D03*
X1493371D03*
X1482271D03*
Y921875D03*
X1480420Y918670D03*
X1489671Y921875D03*
X1487820Y918670D03*
X1493371Y921875D03*
X1480420Y931488D03*
Y925079D03*
X1484120D03*
X1489671Y941100D03*
X1487820Y937896D03*
X1493371Y941100D03*
X1489671Y934691D03*
X1485971D03*
X1493371D03*
X1489671Y947509D03*
X1493371D03*
X1482271D03*
Y941100D03*
X1480420Y937896D03*
X1484120Y944304D03*
X1480420D03*
X1487820Y950713D03*
X1489671Y960326D03*
X1487820Y957122D03*
X1493371Y960326D03*
Y966735D03*
X1489671D03*
X1480420Y950713D03*
X1489671Y953917D03*
X1493371D03*
X1485971D03*
X1482271Y966735D03*
X1480420Y957122D03*
X1482271Y960326D03*
X1484120Y963530D03*
Y982756D03*
X1480420D03*
Y976347D03*
X1482271Y979552D03*
X1489671D03*
X1493371D03*
X1487820Y976347D03*
X1485971Y973143D03*
X1487820Y969939D03*
X1480420D03*
X1479004Y1006093D03*
X1480853Y1002888D03*
X1482703Y999684D03*
X1482704Y1012501D03*
X1480853Y1009297D03*
X1493803Y999684D03*
X1488253Y1002888D03*
X1490104Y999684D03*
Y1031727D03*
X1488253Y1028523D03*
X1493804Y1031727D03*
X1488253Y1022114D03*
X1490104Y1018910D03*
X1493804D03*
X1490104Y1025318D03*
X1486404D03*
X1493804D03*
X1484553Y1015705D03*
X1482704Y1031727D03*
X1480853Y1028523D03*
Y1022114D03*
X1482704Y1018910D03*
X1480853Y1041340D03*
X1482704Y1038136D03*
X1488253Y1047749D03*
Y1041340D03*
X1490104Y1038136D03*
X1493804D03*
X1480853Y1047749D03*
X1486404Y1044544D03*
X1484553Y1034931D03*
X1490104Y1044544D03*
X1493804D03*
X1480853Y1034931D03*
X1488253Y1060565D03*
X1490104Y1057361D03*
X1493804D03*
X1486404Y1063770D03*
X1490104D03*
X1493804D03*
X1490104Y1050952D03*
X1493804D03*
X1480853Y1060565D03*
X1482704Y1057361D03*
Y1050952D03*
X1484553Y1054157D03*
X1480853D03*
X1493804Y1070178D03*
X1490104D03*
X1488253Y1066974D03*
X1480853Y1079791D03*
X1482704Y1076587D03*
Y1070178D03*
X1480853Y1066974D03*
X1488253Y1079791D03*
X1490104Y1076587D03*
X1493804D03*
X1484553Y1073383D03*
X1480853D03*
X1490104Y1089404D03*
X1488253Y1086200D03*
X1493804Y1089404D03*
X1490104Y1082995D03*
X1486404D03*
X1493804D03*
X1486404Y1095813D03*
X1482703D03*
X1482704Y1089404D03*
X1480853Y1086200D03*
X1484553Y1092608D03*
X1480853D03*
X1493804Y1102221D03*
X1491953Y1099017D03*
X1486404Y1102221D03*
X1479003Y1108629D03*
X1488254Y1105426D03*
X1484554Y1111833D03*
X1482703Y1102220D03*
X1480854Y1111833D03*
Y1105426D03*
X1486403Y1108630D03*
X1488254Y1111833D03*
X1484554Y1105426D03*
X1479004Y1115039D03*
Y1121447D03*
X1493804D03*
X1486404D03*
X1482703Y1115038D03*
X1493803Y1140973D03*
X1490104Y1134264D03*
X1488254Y1137469D03*
X1482704Y1134264D03*
X1480854Y1137469D03*
X1491954D03*
X1486403Y1140973D03*
X1484554Y1137469D03*
X1479003Y1140973D03*
X1479004Y1134264D03*
X1493804D03*
X1486404D03*
X1495220Y848176D03*
X1508171Y864197D03*
X1510021Y854584D03*
X1495220Y867401D03*
X1502621D03*
X1495220Y860993D03*
X1502621D03*
X1504471Y857789D03*
X1498920Y860993D03*
X1497071Y857789D03*
X1502620Y854584D03*
X1500771Y857789D03*
X1495220Y854584D03*
X1500771Y870606D03*
X1508171D03*
X1497071D03*
X1498920Y873810D03*
X1504471Y870606D03*
X1506321Y873810D03*
X1495220Y880219D03*
X1497071Y883423D03*
X1502621Y880219D03*
X1504471Y883423D03*
X1500771D03*
X1495220Y873810D03*
X1502621D03*
X1495220Y899445D03*
Y893036D03*
X1498920D03*
X1497071Y896240D03*
X1506320Y893036D03*
X1498920Y886627D03*
X1506321D03*
X1495220D03*
X1502621D03*
X1510021D03*
X1495220Y912262D03*
X1497071Y915466D03*
X1495220Y931488D03*
Y918670D03*
Y937896D03*
X1497071Y934691D03*
X1495220Y950713D03*
Y957122D03*
X1497071Y953917D03*
X1495220Y976347D03*
Y969939D03*
X1497071Y973143D03*
X1495655Y1002888D03*
X1506753D03*
X1508603Y999684D03*
X1503053Y1002888D03*
X1501204Y999684D03*
X1495653Y1028523D03*
Y1022114D03*
X1497504Y1025318D03*
X1495653Y1047749D03*
Y1041340D03*
X1497504Y1044544D03*
X1495653Y1060565D03*
X1497504Y1063770D03*
X1495653Y1066974D03*
Y1079791D03*
Y1086200D03*
X1497504Y1082995D03*
X1506753Y1105426D03*
X1504904Y1102221D03*
X1501204D03*
X1499354Y1099017D03*
X1503053Y1118243D03*
X1510453D03*
X1501204Y1121447D03*
X1508603Y1121446D03*
X1510453Y1124650D03*
X1508603Y1127855D03*
X1508604Y1134264D03*
X1501203Y1140973D03*
X1499354Y1137469D03*
X1510454D03*
X1503054D03*
X1497504Y1134264D03*
X1495654Y1137469D03*
X1501204Y1134264D03*
X1508603Y1140973D03*
X1504903D03*
X1519271Y851380D03*
X1515571D03*
X1511871Y864197D03*
X1519270D03*
X1522970D03*
X1511871Y857789D03*
X1519271D03*
X1515571D03*
X1517421Y860993D03*
Y854584D03*
X1517853Y1118243D03*
X1519703Y1121446D03*
X1516003Y1127855D03*
X1512303D03*
Y1121446D03*
X1516003D03*
X1517853Y1124650D03*
X1519703Y1127855D03*
X1514154Y1131059D03*
X1611475Y1259227D03*
X1714440Y1255381D03*
X1821083Y1252034D03*
G54D39*
X322500Y1391830D03*
X537477Y1395413D03*
X1298642Y1391830D03*
X1513618Y1395413D03*
G54D10*
X27559Y87795D03*
X40708Y631890D03*
Y1368897D03*
X51181Y1714961D03*
X373622Y87795D03*
X395670Y1714961D03*
X661023Y631890D03*
X707677Y1714961D03*
X800787Y87795D03*
X931692Y757874D03*
Y1072834D03*
Y1387795D03*
X1045865Y87795D03*
X1155708Y1714961D03*
X1271260Y631890D03*
X1461805Y1714961D03*
X1499606Y87795D03*
X1816771Y631890D03*
Y1368897D03*
X1806299Y1714961D03*
X1829921Y87795D03*
G54D36*
X277098Y185236D03*
X395208D03*
G54D32*
X205159Y1430034D03*
X393067Y1354446D03*
X422833D03*
X453169D03*
X468443Y1379662D03*
X482543Y1353962D03*
X718638Y1429579D03*
X1178470Y1466363D03*
X1369208Y1353946D03*
X1398974D03*
X1429310D03*
X1444043Y1379362D03*
X1459076Y1353946D03*
X1679944Y1463655D03*
X1836248Y269763D03*
Y299056D03*
G54D30*
X174685Y637367D03*
X174393Y668511D03*
X526478Y1439952D03*
X1502956Y1439530D03*
X1682882Y618174D03*
Y669109D03*
X1769790Y194789D03*
X1799350D03*
G54D47*
X493500Y246362D03*
X559236Y1441207D03*
G54D50*
X688500Y1601900D03*
X1041435Y153357D03*
X1056225Y153131D03*
X1099970Y1702570D03*
G54D65*
X1133779Y1653543D03*
G54D37*
X278126Y676260D03*
Y700414D03*
X395771Y1242785D03*
X420171D03*
X444493D03*
X468893D03*
X493293D03*
X1371912D03*
X1396312D03*
X1420634D03*
X1445034D03*
X1469434D03*
G54D28*
X159474Y1320753D03*
X183847Y1320778D03*
X208247D03*
X275289Y575702D03*
Y599861D03*
Y624015D03*
Y648169D03*
X673093Y1320778D03*
X697466Y1320803D03*
X721866D03*
X1100800Y251488D03*
X1100700Y275788D03*
X1131100Y1357088D03*
X1155500D03*
X1179900D03*
X1577000Y591888D03*
Y616388D03*
Y640888D03*
Y665288D03*
Y689788D03*
Y714288D03*
X1634259Y1354374D03*
X1658632Y1354399D03*
X1683032D03*
G54D77*
X1902608Y988322D03*
X1902682Y1351295D03*
X1951178Y1349597D03*
X1993618Y1349897D03*
G54D74*
X1881720Y988279D03*
X1881211Y1350983D03*
X1930200Y1349548D03*
X1972697Y1349606D03*
G54D23*
X40120Y744554D03*
Y1000853D03*
Y1287664D03*
X69820Y744554D03*
Y1000853D03*
Y1287664D03*
X99520Y744554D03*
Y1000853D03*
Y1287664D03*
X129220Y744554D03*
Y1000853D03*
Y1287664D03*
X158920Y744554D03*
Y1000853D03*
Y1287664D03*
X188620Y744554D03*
Y1000853D03*
Y1287664D03*
X218320Y744554D03*
Y1000853D03*
Y1287664D03*
X248020Y744554D03*
Y1000853D03*
Y1287664D03*
X633320Y744554D03*
Y1000853D03*
Y1287664D03*
X663020Y744554D03*
Y1000853D03*
Y1287664D03*
X692720Y744554D03*
Y1000853D03*
Y1287664D03*
X722420Y744554D03*
Y1000853D03*
Y1287664D03*
X752120Y744554D03*
Y1000853D03*
Y1287664D03*
X781820Y744554D03*
Y1000853D03*
Y1287664D03*
X811520Y744554D03*
Y1000853D03*
Y1287664D03*
X841220Y744554D03*
Y1000853D03*
Y1287664D03*
X1016262Y744554D03*
Y1000853D03*
Y1287664D03*
X1045962Y744554D03*
Y1000853D03*
Y1287664D03*
X1075662Y744554D03*
Y1000853D03*
Y1287664D03*
X1105362Y744554D03*
Y1000853D03*
Y1287664D03*
X1135062Y744554D03*
Y1000853D03*
Y1287664D03*
X1164762Y744554D03*
Y1000853D03*
Y1287664D03*
X1194462Y744554D03*
Y1000853D03*
Y1287664D03*
X1224162Y744554D03*
Y1000853D03*
Y1287664D03*
X1609462Y744554D03*
Y1000853D03*
Y1287664D03*
X1639162Y744554D03*
Y1000853D03*
Y1287664D03*
X1668862Y744554D03*
Y1000853D03*
Y1287664D03*
X1698562Y744554D03*
Y1000853D03*
Y1287664D03*
X1728262Y744554D03*
Y1000853D03*
Y1287664D03*
X1757962Y744554D03*
Y1000853D03*
Y1287664D03*
X1787662Y744554D03*
Y1000853D03*
Y1287664D03*
X1817362Y744554D03*
Y1000853D03*
Y1287664D03*
G54D60*
X928739Y321653D03*
G54D33*
X250326Y185236D03*
X368437D03*
G54D61*
X916545Y309459D03*
X911494Y321653D03*
X916545Y333847D03*
X940933Y309459D03*
X928739Y304408D03*
Y338898D03*
X940933Y333847D03*
X945984Y321653D03*
G54D67*
X1247638Y269488D03*
X1405118Y112008D03*
X1766929Y1714960D03*
G54D13*
X19685Y-29134D03*
Y1803261D03*
X1837795Y-29134D03*
Y1803261D03*
X2081889Y-29134D03*
Y1803261D03*
G54D68*
X1405876Y1453298D03*
X1430204Y1452014D03*
G54D18*
X38346Y1420330D03*
X117932Y605380D03*
X763601Y605413D03*
X1094074Y605380D03*
X1739706Y605455D03*
X1819208Y1420330D03*
G54D21*
X49280Y337402D03*
X41870Y1511291D03*
X441043Y1672205D03*
Y1718465D03*
X1416437Y1672204D03*
Y1718464D03*
X1808192Y1569255D03*
X1812980Y502472D03*
G54D38*
X306772Y991220D03*
X350099Y811121D03*
X356063Y1171318D03*
X531240Y811121D03*
X525276Y1171318D03*
X574567Y991220D03*
X1282914D03*
X1326240Y811121D03*
X1332205Y1171318D03*
X1507382Y811121D03*
X1501418Y1171318D03*
X1550709Y991220D03*
G54D53*
X791280Y1704890D03*
X1066280D03*
G54D34*
X238780Y1648385D03*
X230906Y1644448D03*
X238780Y1662558D03*
X230906Y1658621D03*
X238780Y1676732D03*
X230906Y1672795D03*
X238780Y1690905D03*
X230906Y1686968D03*
X238780Y1705078D03*
X230906Y1701141D03*
Y1715314D03*
X238780Y1719251D03*
X230906Y1729488D03*
X238780Y1733425D03*
X254528Y1648385D03*
X246654Y1644448D03*
X254528Y1662558D03*
X246654Y1658621D03*
X254528Y1676732D03*
X246654Y1672795D03*
X254528Y1690905D03*
X246654Y1686968D03*
X254528Y1705078D03*
X246654Y1701141D03*
Y1715314D03*
X254528Y1719251D03*
X246654Y1729488D03*
X254528Y1733425D03*
X270276Y1648385D03*
X262402Y1644448D03*
X270276Y1662558D03*
X262402Y1658621D03*
X270276Y1676732D03*
X262402Y1672795D03*
X270276Y1690905D03*
X262402Y1686968D03*
X270276Y1705078D03*
X262402Y1701141D03*
Y1715314D03*
X270276Y1719251D03*
X262402Y1729488D03*
X270276Y1733425D03*
X286024Y1648385D03*
X278150Y1644448D03*
X286024Y1662558D03*
X278150Y1658621D03*
X286024Y1676732D03*
X278150Y1672795D03*
X286024Y1690905D03*
X278150Y1686968D03*
X286024Y1705078D03*
X278150Y1701141D03*
Y1715314D03*
X286024Y1719251D03*
X278150Y1729488D03*
X286024Y1733425D03*
X297835Y1672795D03*
X305709Y1676732D03*
X297835Y1686968D03*
X305709Y1690905D03*
X297835Y1701141D03*
X305709Y1705078D03*
X297835Y1715314D03*
X305709Y1719251D03*
X297835Y1729488D03*
X305709Y1733425D03*
X313583Y1672795D03*
X321457Y1676732D03*
X313583Y1686968D03*
X321457Y1690905D03*
X313583Y1701141D03*
X321457Y1705078D03*
X313583Y1715314D03*
X321457Y1719251D03*
X313583Y1729488D03*
X321457Y1733425D03*
X329331Y1672795D03*
X337205Y1676732D03*
X329331Y1686968D03*
X337205Y1690905D03*
X329331Y1701141D03*
X337205Y1705078D03*
X329331Y1715314D03*
X337205Y1719251D03*
X329331Y1729488D03*
X337205Y1733425D03*
X345079Y1672795D03*
X352953Y1676732D03*
X345079Y1686968D03*
X352953Y1690905D03*
X345079Y1701141D03*
X352953Y1705078D03*
X345079Y1715314D03*
X352953Y1719251D03*
X345079Y1729488D03*
X352953Y1733425D03*
X495079Y1672795D03*
Y1686968D03*
Y1701141D03*
Y1715314D03*
Y1729488D03*
X510827Y1672795D03*
X502953Y1676732D03*
X518701D03*
X510827Y1686968D03*
X502953Y1690905D03*
X518701D03*
X510827Y1701141D03*
X502953Y1705078D03*
X518701D03*
X510827Y1715314D03*
X502953Y1719251D03*
X518701D03*
X510827Y1729488D03*
X502953Y1733425D03*
X518701D03*
X526575Y1672795D03*
X534449Y1676732D03*
X526575Y1686968D03*
X534449Y1690905D03*
X526575Y1701141D03*
X534449Y1705078D03*
X526575Y1715314D03*
X534449Y1719251D03*
X526575Y1729488D03*
X534449Y1733425D03*
X542323Y1672795D03*
X550197Y1676732D03*
X542323Y1686968D03*
X550197Y1690905D03*
X542323Y1701141D03*
X550197Y1705078D03*
X542323Y1715314D03*
X550197Y1719251D03*
X542323Y1729488D03*
X550197Y1733425D03*
X562008Y1672795D03*
Y1686968D03*
Y1701141D03*
Y1715314D03*
Y1729488D03*
X577756Y1672795D03*
X569882Y1676732D03*
X577756Y1686968D03*
X569882Y1690905D03*
X577756Y1701141D03*
X569882Y1705078D03*
X577756Y1715314D03*
X569882Y1719251D03*
X577756Y1729488D03*
X569882Y1733425D03*
X593504Y1672795D03*
X585630Y1676732D03*
X593504Y1686968D03*
X585630Y1690905D03*
X593504Y1701141D03*
X585630Y1705078D03*
X593504Y1715314D03*
X585630Y1719251D03*
X593504Y1729488D03*
X585630Y1733425D03*
X609252Y1672795D03*
X601378Y1676732D03*
X609252Y1686968D03*
X601378Y1690905D03*
X609252Y1701141D03*
X601378Y1705078D03*
X609252Y1715314D03*
X601378Y1719251D03*
X609252Y1729488D03*
X601378Y1733425D03*
X617126Y1676732D03*
Y1690905D03*
Y1705078D03*
Y1719251D03*
Y1733425D03*
X1238780Y1672795D03*
X1246654Y1676732D03*
X1238780Y1686968D03*
X1246654Y1690905D03*
X1238780Y1701141D03*
X1246654Y1705078D03*
X1238780Y1715314D03*
X1246654Y1719251D03*
X1238780Y1729488D03*
X1246654Y1733425D03*
X1254528Y1672795D03*
X1262402Y1676732D03*
X1254528Y1686968D03*
X1262402Y1690905D03*
X1254528Y1701141D03*
X1262402Y1705078D03*
X1254528Y1715314D03*
X1262402Y1719251D03*
X1254528Y1729488D03*
X1262402Y1733425D03*
X1270276Y1672795D03*
X1278150Y1676732D03*
X1270276Y1686968D03*
X1278150Y1690905D03*
X1270276Y1701141D03*
X1278150Y1705078D03*
X1270276Y1715314D03*
X1278150Y1719251D03*
X1270276Y1729488D03*
X1278150Y1733425D03*
X1286024Y1672795D03*
X1293898Y1676732D03*
X1286024Y1686968D03*
X1293898Y1690905D03*
X1286024Y1701141D03*
X1293898Y1705078D03*
X1286024Y1715314D03*
X1293898Y1719251D03*
X1286024Y1729488D03*
X1293898Y1733425D03*
X1305709Y1672795D03*
X1313583Y1676732D03*
X1305709Y1686968D03*
X1313583Y1690905D03*
X1305709Y1701141D03*
X1313583Y1705078D03*
X1305709Y1715314D03*
X1313583Y1719251D03*
X1305709Y1729488D03*
X1313583Y1733425D03*
X1321457Y1672795D03*
X1329331Y1676732D03*
X1321457Y1686968D03*
X1329331Y1690905D03*
X1321457Y1701141D03*
X1329331Y1705078D03*
X1321457Y1715314D03*
X1329331Y1719251D03*
X1321457Y1729488D03*
X1329331Y1733425D03*
X1337205Y1672795D03*
X1345079Y1676732D03*
X1337205Y1686968D03*
X1345079Y1690905D03*
X1337205Y1701141D03*
X1345079Y1705078D03*
X1337205Y1715314D03*
X1345079Y1719251D03*
X1337205Y1729488D03*
X1345079Y1733425D03*
X1352953Y1672795D03*
X1360827Y1676732D03*
X1352953Y1686968D03*
X1360827Y1690905D03*
X1352953Y1701141D03*
X1360827Y1705078D03*
X1352953Y1715314D03*
X1360827Y1719251D03*
X1352953Y1729488D03*
X1360827Y1733425D03*
X1502953Y1672795D03*
X1510827Y1676732D03*
X1502953Y1686968D03*
X1510827Y1690905D03*
X1502953Y1701141D03*
X1510827Y1705078D03*
X1502953Y1715314D03*
X1510827Y1719251D03*
X1502953Y1729488D03*
X1510827Y1733425D03*
X1518701Y1672795D03*
X1526575Y1676732D03*
X1518701Y1686968D03*
X1526575Y1690905D03*
X1518701Y1701141D03*
X1526575Y1705078D03*
X1518701Y1715314D03*
X1526575Y1719251D03*
X1518701Y1729488D03*
X1526575Y1733425D03*
X1534449Y1672795D03*
X1542323Y1676732D03*
X1534449Y1686968D03*
X1542323Y1690905D03*
X1534449Y1701141D03*
X1542323Y1705078D03*
X1534449Y1715314D03*
X1542323Y1719251D03*
X1534449Y1729488D03*
X1542323Y1733425D03*
X1550197Y1672795D03*
X1558071Y1676732D03*
X1550197Y1686968D03*
X1558071Y1690905D03*
X1550197Y1701141D03*
X1558071Y1705078D03*
X1550197Y1715314D03*
X1558071Y1719251D03*
X1550197Y1729488D03*
X1558071Y1733425D03*
X1569882Y1672795D03*
Y1686968D03*
Y1701141D03*
Y1715314D03*
Y1729488D03*
X1585630Y1672795D03*
X1577756Y1676732D03*
X1585630Y1686968D03*
X1577756Y1690905D03*
X1585630Y1701141D03*
X1577756Y1705078D03*
X1585630Y1715314D03*
X1577756Y1719251D03*
X1585630Y1729488D03*
X1577756Y1733425D03*
X1601378Y1672795D03*
X1593504Y1676732D03*
X1601378Y1686968D03*
X1593504Y1690905D03*
X1601378Y1701141D03*
X1593504Y1705078D03*
X1601378Y1715314D03*
X1593504Y1719251D03*
X1601378Y1729488D03*
X1593504Y1733425D03*
X1617126Y1672795D03*
X1609252Y1676732D03*
X1625000D03*
X1617126Y1686968D03*
X1609252Y1690905D03*
X1625000D03*
X1617126Y1701141D03*
X1609252Y1705078D03*
X1625000D03*
X1617126Y1715314D03*
X1609252Y1719251D03*
X1625000D03*
X1617126Y1729488D03*
X1609252Y1733425D03*
X1625000D03*
G54D44*
X441043Y1698268D03*
X1416437Y1698267D03*
G54D55*
X805690Y204724D03*
X1057658D03*
G54D20*
X41492Y290637D03*
X44833Y1659909D03*
X61340Y384362D03*
X61250Y396142D03*
X49250Y396332D03*
X49400Y384392D03*
X47618Y413113D03*
X47619Y421155D03*
X56799Y1524094D03*
Y1528094D03*
Y1532094D03*
Y1544094D03*
Y1548094D03*
Y1552094D03*
Y1556094D03*
X54333Y1604359D03*
X50900Y1677775D03*
X65881Y305426D03*
X72774Y1549669D03*
X66906Y1598324D03*
Y1603280D03*
X84274Y1517619D03*
X81038Y1536899D03*
X91538Y1539399D03*
X84700Y1627000D03*
X99274Y1526019D03*
X126225Y504368D03*
X120225D03*
Y510368D03*
X126225Y516368D03*
X120225D03*
X112749Y1524594D03*
Y1540594D03*
Y1544594D03*
Y1548594D03*
Y1536594D03*
Y1564594D03*
Y1560594D03*
X132225Y504368D03*
Y510368D03*
X132401Y516368D03*
X129670Y1563160D03*
X153271Y1540961D03*
X153138Y1549032D03*
X166986Y575918D03*
X161321Y1540858D03*
X161374Y1549073D03*
X189800Y705062D03*
X208312Y576125D03*
X196526Y567825D03*
X208312Y581085D03*
Y578605D03*
X197423Y601496D03*
X194059Y604901D03*
X208312Y615085D03*
Y610125D03*
Y612605D03*
X194059Y638901D03*
X197423Y635496D03*
X208312Y649085D03*
Y644125D03*
Y646605D03*
X213912Y576125D03*
X220668Y574131D03*
X223775D03*
X224064Y568113D03*
X221464D03*
X213912Y578605D03*
Y581085D03*
X217556Y590575D03*
X217561Y582131D03*
Y579531D03*
X223775Y587731D03*
X223759Y590675D03*
X220652D03*
X223775Y584531D03*
X220668Y576731D03*
Y579331D03*
X223775Y581931D03*
Y579331D03*
Y576731D03*
X220668Y581931D03*
Y608131D03*
X223775D03*
X224064Y602113D03*
X221464D03*
X223403Y596820D03*
Y594220D03*
X213912Y612605D03*
Y615085D03*
Y610125D03*
X217561Y616131D03*
Y613531D03*
X217556Y624575D03*
X223759Y624675D03*
X220652D03*
X223775Y618531D03*
X220668Y610731D03*
Y613331D03*
X223775Y615931D03*
Y613331D03*
Y610731D03*
X220668Y615931D03*
X223775Y621731D03*
X223403Y630820D03*
Y628220D03*
X224064Y636113D03*
X221464D03*
X213912Y646605D03*
Y649085D03*
Y644125D03*
X217561Y650131D03*
Y647531D03*
X223775Y655731D03*
Y652531D03*
X220668Y644731D03*
Y647331D03*
Y642131D03*
X223775Y649931D03*
Y647331D03*
Y644731D03*
Y642131D03*
X220668Y649931D03*
X217556Y658575D03*
X223403Y664820D03*
X223759Y658675D03*
X220652D03*
X217510Y668712D03*
X225167Y672006D03*
X222567D03*
X219967D03*
X217367D03*
X211348Y688087D03*
Y685287D03*
X214100Y687376D03*
Y690376D03*
Y684376D03*
Y681376D03*
Y678376D03*
X211348Y690787D03*
Y693587D03*
X214100Y693576D03*
X224506Y698138D03*
Y700738D03*
X221906Y698138D03*
Y700738D03*
X219306D03*
Y698138D03*
X231864Y568113D03*
X229264D03*
X226664D03*
X238393Y570490D03*
X240993D03*
X229264Y602113D03*
X226664D03*
X226003Y594220D03*
Y596820D03*
X228603Y594220D03*
Y596820D03*
X231864Y602113D03*
X233803Y594220D03*
Y596820D03*
X231203Y594220D03*
Y596820D03*
X238393Y604490D03*
X240993D03*
Y596820D03*
X238393D03*
X240993Y594220D03*
X238393D03*
X226003Y628220D03*
Y630820D03*
X228603Y628220D03*
Y630820D03*
X231864Y636113D03*
X233803Y628220D03*
Y630820D03*
X231203Y628220D03*
Y630820D03*
X229264Y636113D03*
X226664D03*
X238393Y638490D03*
X240993D03*
Y630820D03*
X238393D03*
X240993Y628220D03*
X238393D03*
X228603Y664820D03*
X233803D03*
X231203D03*
X226003D03*
X230367Y672006D03*
X227767D03*
X227106Y698138D03*
Y700738D03*
X246400Y563162D03*
X263580Y218627D03*
X318651Y22921D03*
X320825Y159062D03*
X410700Y1658460D03*
X435340Y125346D03*
X435240Y1609200D03*
X433383Y1602629D03*
X450380Y104647D03*
X440019Y1576809D03*
X442128Y1574879D03*
X441308Y1602654D03*
X505055Y1387601D03*
Y1382301D03*
Y1396001D03*
Y1398601D03*
Y1390201D03*
X563634Y1334315D03*
X561034D03*
X612670Y142872D03*
X612520Y154812D03*
X624610Y142842D03*
X624520Y154622D03*
X702975Y414864D03*
X739206Y608020D03*
Y603064D03*
X758830Y1674823D03*
X819114Y115223D03*
X824498Y145198D03*
X831114Y115223D03*
X829114Y150273D03*
X854577Y99651D03*
X876124Y66072D03*
Y86072D03*
Y106072D03*
Y126072D03*
X887869Y386618D03*
X881372Y920655D03*
X898062Y976652D03*
Y969716D03*
X942646Y400793D03*
X946865Y974077D03*
X953235Y972642D03*
X946938Y991162D03*
X943720Y985772D03*
X956022Y1620730D03*
X953022D03*
Y1632730D03*
X956022D03*
Y1629730D03*
X953022D03*
X956022Y1626730D03*
X953022D03*
Y1623730D03*
X956022D03*
X963610Y981292D03*
X959535Y990477D03*
X963780Y997496D03*
X962022Y1620730D03*
X959022D03*
Y1632730D03*
X962022D03*
Y1629730D03*
X959022D03*
X962022Y1626730D03*
X959022D03*
Y1623730D03*
X962022D03*
X978403Y-9022D03*
Y-13978D03*
Y-19022D03*
Y-23978D03*
Y6022D03*
Y10978D03*
Y20978D03*
Y16022D03*
X988835Y185443D03*
X989500Y376362D03*
X985672Y432961D03*
X987662Y1620870D03*
Y1629870D03*
Y1626870D03*
Y1623870D03*
Y1632870D03*
X1002500Y266862D03*
X991770Y418835D03*
X992608Y432961D03*
X1002640Y594692D03*
X990662Y1620870D03*
X993662D03*
Y1629870D03*
X990662D03*
X993662Y1626870D03*
X990662D03*
Y1623870D03*
X993662D03*
X990662Y1632870D03*
X993662D03*
X1001810Y1662700D03*
Y1665200D03*
X1018000Y263862D03*
X1022000Y264362D03*
X1014500Y263862D03*
X1010500D03*
X1018000Y266862D03*
X1010500D03*
X1006500D03*
X1014500D03*
X1011611Y430038D03*
X1019252Y1620870D03*
X1022252D03*
Y1623870D03*
Y1626870D03*
X1019252Y1623870D03*
Y1626870D03*
X1019910Y1662700D03*
Y1665200D03*
X1025000Y264362D03*
X1038220Y589862D03*
X1030980Y598722D03*
X1023740Y596152D03*
X1036480Y596272D03*
X1025252Y1620870D03*
Y1623870D03*
Y1626870D03*
X1023580Y1662700D03*
Y1665200D03*
X1027370Y1662700D03*
Y1665200D03*
X1040924Y286073D03*
X1043720Y589362D03*
X1050200Y598062D03*
X1050390Y604172D03*
X1053200Y612162D03*
X1050721Y1633043D03*
X1053721D03*
Y1624043D03*
Y1627043D03*
Y1630043D03*
X1050721Y1624043D03*
Y1627043D03*
Y1630043D03*
X1053721Y1621043D03*
X1050721D03*
X1044850Y1665050D03*
Y1662550D03*
X1067718Y288500D03*
X1070618D03*
X1056280Y601232D03*
X1056721Y1633043D03*
Y1624043D03*
Y1627043D03*
Y1630043D03*
Y1621043D03*
X1095900Y1646935D03*
X1095649Y1638875D03*
X1099457D03*
X1104457Y1675490D03*
X1120544Y312200D03*
X1129995Y301637D03*
X1150914Y197407D03*
X1148354Y222677D03*
X1150272Y638346D03*
X1160720Y180862D03*
X1165000Y190962D03*
X1162500D03*
X1164300Y197262D03*
X1163732Y204887D03*
X1160732D03*
X1158172Y230157D03*
X1159912Y638216D03*
X1166722Y636206D03*
X1158762Y642266D03*
X1168402Y642136D03*
X1159930Y1645632D03*
X1164830D03*
X1161613Y1669112D03*
X1173065Y194174D03*
X1172865Y210174D03*
X1172795Y222174D03*
X1180398Y289814D03*
X1171540Y310902D03*
X1176362Y636076D03*
X1180262Y642216D03*
X1181930Y1645632D03*
X1186830D03*
X1175830D03*
X1170930D03*
X1183613Y1669112D03*
X1172613D03*
X1189902Y642086D03*
X1192500Y1645942D03*
X1197400D03*
X1194183Y1669422D03*
X1192340Y1691422D03*
X1197240D03*
X1194023Y1714902D03*
X1206093Y120362D03*
X1214593Y168962D03*
X1208518Y174162D03*
X1203858Y185451D03*
X1208365Y271151D03*
X1210457Y1658415D03*
X1218810Y1691732D03*
X1213910D03*
X1203110Y1691467D03*
X1208010D03*
X1215593Y1715212D03*
X1204793Y1714947D03*
X1228704Y112122D03*
X1223100Y127300D03*
X1226093Y152792D03*
X1227500Y380400D03*
X1242520Y165362D03*
X1236593Y209562D03*
X1236584Y217462D03*
X1245614Y227462D03*
X1266093Y129962D03*
X1256093Y143462D03*
X1264685Y175506D03*
X1279485Y105752D03*
X1278949Y123567D03*
X1282293Y248962D03*
X1275557Y269477D03*
Y272436D03*
X1282653Y269446D03*
X1278557Y272436D03*
Y269477D03*
X1272557Y272436D03*
X1287795Y-29033D03*
Y-33989D03*
Y-9033D03*
Y-13989D03*
Y-19033D03*
Y-23989D03*
Y967D03*
Y-3989D03*
X1293430Y84072D03*
X1294354Y105912D03*
X1295053Y140181D03*
X1292293Y143162D03*
X1287943Y233748D03*
X1284437Y230280D03*
X1293893Y237962D03*
X1286611Y260908D03*
X1295887Y315571D03*
X1314741Y68652D03*
X1300454Y95302D03*
X1302964Y124633D03*
X1301993Y140462D03*
X1313950Y261612D03*
X1308790Y290172D03*
X1302450Y290072D03*
X1307798Y287561D03*
X1313246Y287631D03*
X1308220Y304262D03*
X1303120Y304162D03*
X1330102Y59025D03*
X1327920Y84418D03*
X1316478Y92970D03*
X1330273Y128373D03*
X1326493Y249562D03*
X1317893Y257462D03*
X1328393Y264262D03*
X1339280Y126175D03*
X1356223Y131569D03*
X1362793Y145262D03*
X1366124Y101529D03*
X1377597Y197604D03*
X1375300Y208422D03*
X1378452Y236055D03*
X1389609Y145291D03*
X1389443Y147859D03*
X1386780Y197668D03*
X1395321D03*
X1409558Y151948D03*
Y156904D03*
X1401240Y171672D03*
X1404071Y197668D03*
X1412851D03*
X1398700Y1597800D03*
X1436436Y300319D03*
X1456423Y209362D03*
X1453823Y205982D03*
X1445777Y362021D03*
X1449296Y410497D03*
X1451580Y1627990D03*
X1462777Y362021D03*
X1470877Y374496D03*
X1463277Y406446D03*
X1470954D03*
X1476570Y1657974D03*
X1480154Y-29033D03*
Y-33989D03*
Y-9033D03*
Y-13989D03*
Y-19033D03*
Y-23989D03*
Y967D03*
Y-3989D03*
X1481155Y1387742D03*
X1481255Y1382042D03*
X1481155Y1396342D03*
Y1398942D03*
Y1390342D03*
X1478724Y1637189D03*
X1505821Y215802D03*
X1524770Y195792D03*
X1521201Y215551D03*
X1531750Y199762D03*
X1529610Y211614D03*
X1532590Y225432D03*
X1561494Y584292D03*
X1604040Y219692D03*
X1604290Y242472D03*
X1636393Y181778D03*
X1632899Y213012D03*
X1670004Y537065D03*
Y543065D03*
Y531065D03*
X1683394Y469878D03*
X1683476Y473378D03*
X1684356Y476290D03*
X1681602Y485180D03*
X1684356Y485628D03*
X1677464Y491790D03*
X1682004Y537065D03*
X1682180Y543065D03*
X1676004D03*
X1682004Y531065D03*
X1676004D03*
X1697648Y463724D03*
X1693648D03*
X1692883Y703943D03*
X1709027Y655141D03*
X1725473Y474859D03*
X1754307Y262186D03*
X1751068Y262123D03*
X1754245Y269724D03*
X1751068Y266048D03*
X1754307Y266111D03*
X1754414Y275329D03*
X1752165Y273901D03*
X1749565D03*
X1751006Y269661D03*
X1749595Y276711D03*
X1752195D03*
X1748989Y380206D03*
X1764955Y301951D03*
X1768757Y380498D03*
X1793061Y24659D03*
X1828880Y1626595D03*
Y1646595D03*
Y1666595D03*
Y1686595D03*
X1840691Y329470D03*
Y349470D03*
Y369470D03*
Y389470D03*
Y409470D03*
Y429470D03*
Y449470D03*
Y469470D03*
Y489470D03*
Y509470D03*
Y529470D03*
Y549470D03*
Y569470D03*
Y589470D03*
Y669470D03*
Y1329470D03*
Y1409470D03*
Y1429470D03*
Y1449470D03*
Y1469470D03*
Y1489470D03*
Y1509470D03*
Y1529470D03*
Y1549470D03*
Y1569470D03*
Y1589470D03*
X1854470Y112379D03*
Y152379D03*
Y172379D03*
Y192379D03*
Y212379D03*
Y232379D03*
Y252379D03*
Y272379D03*
Y292379D03*
G54D59*
X922441Y154311D03*
Y243799D03*
G54D12*
X14092Y287115D03*
X17371Y49388D03*
X22223Y388057D03*
X29509Y398132D03*
X29962Y401000D03*
X24700Y765600D03*
X37371Y49388D03*
X36255Y304972D03*
X42809Y360862D03*
X39410Y384582D03*
X39226Y395346D03*
X33020Y382822D03*
X36524Y398013D03*
X30680Y438142D03*
X58379Y69340D03*
X60379Y66844D03*
Y71836D03*
X60692Y87118D03*
X54920Y185039D03*
Y177165D03*
X46834Y360862D03*
X55190D03*
X53825Y421746D03*
X54762Y444993D03*
X53800Y435451D03*
X58658Y754145D03*
X55177Y1322328D03*
X55277Y1326068D03*
X46994Y1663165D03*
X69058Y3010D03*
X79047Y23978D03*
X74091D03*
X72091Y25974D03*
X73020Y37106D03*
Y48720D03*
X67335Y69340D03*
X65335Y66844D03*
Y71836D03*
X65648Y87118D03*
X71379Y72844D03*
Y77836D03*
X76335Y72844D03*
Y77836D03*
X78335Y75340D03*
X69379D03*
X71772Y421746D03*
X75490Y432519D03*
X68365Y443677D03*
X64150Y434972D03*
X74340Y663422D03*
X76365Y699244D03*
X76565Y717949D03*
X72315Y717414D03*
X64325Y715674D03*
X75564Y1509952D03*
X78120Y1512936D03*
Y1521336D03*
X75922Y1564874D03*
Y1556474D03*
X73429Y1570008D03*
X78415D03*
X73832Y1689362D03*
X77833Y1689162D03*
X89058Y3010D03*
X81196Y17042D03*
Y22034D03*
X86152Y17042D03*
Y22034D03*
X95369Y17042D03*
Y22034D03*
X79196Y19538D03*
X88152D03*
X93369D03*
X88264Y23978D03*
X93220D03*
X86264Y25974D03*
X95220D03*
X81047D03*
X94279Y37106D03*
X87193D03*
X80106D03*
X94279Y48720D03*
X87193D03*
X80106D03*
X80379Y69340D03*
X89335D03*
X82379Y66844D03*
Y71836D03*
X87335Y66844D03*
Y71836D03*
X91379Y75340D03*
X93379Y72844D03*
Y77836D03*
X86490Y200787D03*
Y208661D03*
X85960Y224409D03*
X85788Y240157D03*
X90700Y282762D03*
Y300262D03*
X87654Y376026D03*
X87520Y386502D03*
X94811Y510173D03*
X80460Y655672D03*
X83100Y649762D03*
X82735Y717949D03*
X87865Y714394D03*
X85165D03*
X81225Y715854D03*
X79635Y717949D03*
X85835Y718049D03*
X93295Y762019D03*
X92071Y1492888D03*
X80649Y1509944D03*
X93544Y1510099D03*
X88459Y1510107D03*
X90998Y1513037D03*
Y1521437D03*
X84048Y1578008D03*
X90713Y1585852D03*
Y1589852D03*
Y1593867D03*
X90788Y1611821D03*
Y1605867D03*
Y1623821D03*
X90698Y1638362D03*
Y1634362D03*
X86245Y1690362D03*
X81833Y1689162D03*
X94220Y1686622D03*
X109058Y3010D03*
X100325Y17042D03*
Y22034D03*
X109542Y17042D03*
Y22034D03*
X102325Y19538D03*
X107542D03*
X102437Y23978D03*
X107393D03*
X100437Y25974D03*
X109393D03*
X108453Y37106D03*
X101366D03*
X108453Y48720D03*
X101366D03*
X102379Y69340D03*
X111335D03*
X104379Y66844D03*
Y71836D03*
X109335Y66844D03*
Y71836D03*
X98335Y72844D03*
Y77836D03*
X100335Y75340D03*
X101317Y431727D03*
X102060Y493578D03*
X111087Y520052D03*
X98134Y722501D03*
X99716Y1567878D03*
X99750Y1559478D03*
X96251Y1577532D03*
X107451Y1574704D03*
X100451D03*
X104318Y1592304D03*
Y1603690D03*
X110200Y1605200D03*
X104318Y1622380D03*
Y1641075D03*
X99980Y1685362D03*
Y1696052D03*
X114498Y17042D03*
Y22034D03*
X123716Y17042D03*
Y22034D03*
X116498Y19538D03*
X121716D03*
X121567Y23978D03*
X116611D03*
X114611Y25974D03*
X123567D03*
X122626Y37106D03*
X115539D03*
X122626Y48720D03*
X115539D03*
X124379Y69340D03*
X126379Y66844D03*
Y71836D03*
X115379Y72844D03*
Y77836D03*
X120335Y72844D03*
Y77836D03*
X122335Y75340D03*
X113379D03*
X114087Y285495D03*
Y302854D03*
X127206Y480216D03*
X123257Y547506D03*
X119087D03*
X115060D03*
X120267Y1327697D03*
X127366Y1535855D03*
Y1541874D03*
Y1547935D03*
X116798Y1586288D03*
Y1598572D03*
Y1635303D03*
X127195Y1670362D03*
X117795Y1698862D03*
X127195Y1688362D03*
Y1692362D03*
Y1708362D03*
X117255Y1730422D03*
X129058Y3010D03*
X128672Y17042D03*
Y22034D03*
X130672Y19538D03*
X129713Y37106D03*
Y48720D03*
X133335Y69340D03*
X131335Y66844D03*
Y71836D03*
X137379Y72844D03*
Y77836D03*
X142335Y72844D03*
Y77836D03*
X135379Y75340D03*
X130057Y636103D03*
X129600Y669400D03*
X132967Y760525D03*
X141470Y1359100D03*
X140104Y1560136D03*
X139080Y1731398D03*
X149058Y3010D03*
X159582Y17042D03*
Y22034D03*
X157582Y19538D03*
X152477Y23978D03*
X157433D03*
X150477Y25974D03*
X159433D03*
X158492Y37106D03*
X151405D03*
X158492Y48720D03*
X151405D03*
X146379Y69340D03*
X155335D03*
X148379Y66844D03*
Y71836D03*
X153335Y66844D03*
Y71836D03*
X158583Y75340D03*
X144335D03*
X149371Y423383D03*
Y419383D03*
Y427383D03*
Y439383D03*
Y431383D03*
Y435383D03*
Y443383D03*
X147141Y698811D03*
X147435Y690807D03*
X149861Y698831D03*
X150155Y690807D03*
X156685Y706836D03*
X153965Y706816D03*
X153879Y721660D03*
X156469D03*
X147031Y706835D03*
X149621D03*
X149669Y721660D03*
X147079D03*
X154477Y1360797D03*
X148663Y1378607D03*
X151163D03*
Y1383807D03*
Y1381207D03*
X158318Y1384286D03*
X155718D03*
X158318Y1387393D03*
X155718D03*
X148663Y1386407D03*
X151163D03*
X148663Y1383807D03*
Y1381207D03*
X160201Y1399732D03*
X157731D03*
Y1394132D03*
X160201D03*
X152806Y1414175D03*
X144748Y1514878D03*
X149728D03*
X154581Y1520981D03*
X158570D03*
X150502Y1572021D03*
X145522D03*
X159107Y1571364D03*
X144854Y1702389D03*
X154803Y1708532D03*
X155100Y1723262D03*
X169058Y3010D03*
X164538Y17042D03*
Y22034D03*
X173755Y17042D03*
Y22034D03*
X166538Y19538D03*
X171755D03*
X166650Y23978D03*
X171606D03*
X164650Y25974D03*
X173606D03*
X172665Y37106D03*
X165579D03*
X172665Y48720D03*
X165579D03*
X169583Y69340D03*
X171583Y66844D03*
Y71836D03*
X176539Y66844D03*
Y71836D03*
X165539Y72844D03*
X160583D03*
Y77836D03*
X165539D03*
X167539Y75340D03*
X174327Y230928D03*
X171180Y401885D03*
X163900Y409362D03*
X163132Y493299D03*
X162750Y512502D03*
X172807Y1360797D03*
X160918Y1384286D03*
X163518D03*
Y1387393D03*
X160918D03*
X169318Y1384286D03*
X166118D03*
X172262Y1384302D03*
Y1387409D03*
X174932Y1378797D03*
Y1381397D03*
X163718Y1390500D03*
X161118D03*
X162631Y1399732D03*
Y1394132D03*
X172231Y1390532D03*
X162693Y1411529D03*
X171262Y1443390D03*
X168900Y1520510D03*
X163920D03*
X166476Y1572464D03*
X171456D03*
X166529Y1707678D03*
X166661Y1721211D03*
X189058Y3010D03*
X178711Y17042D03*
Y22034D03*
X180711Y19538D03*
X179752Y37106D03*
Y48720D03*
X191583Y69340D03*
X178539D03*
X182583Y72844D03*
Y77836D03*
X187539Y72844D03*
Y77836D03*
X189539Y75340D03*
X180583D03*
X186457Y393071D03*
Y385071D03*
Y389071D03*
Y405071D03*
X192220Y408662D03*
Y412162D03*
X177871Y421383D03*
Y425383D03*
Y430883D03*
Y443383D03*
X187490Y568752D03*
X190977Y669718D03*
X191976Y684326D03*
X184215Y1361072D03*
X181403Y1361115D03*
X192620Y1360797D03*
X188233Y1387027D03*
Y1379227D03*
Y1381827D03*
Y1384427D03*
X183283Y1387987D03*
X185633Y1387027D03*
X180672Y1387987D03*
X185633Y1379227D03*
X180672Y1380187D03*
X183283D03*
X177532Y1378797D03*
X185633Y1384427D03*
Y1381827D03*
X180672Y1382787D03*
Y1385387D03*
X183283Y1382787D03*
Y1385387D03*
X177421Y1383997D03*
X177532Y1381397D03*
X182653Y1404535D03*
X192767Y1413725D03*
X185643Y1413945D03*
X185895Y1535462D03*
Y1539723D03*
Y1544029D03*
Y1548487D03*
Y1552875D03*
X176793Y1585173D03*
X188119Y1580678D03*
Y1575686D03*
Y1592590D03*
Y1587598D03*
X192529Y1728947D03*
X183822Y1720517D03*
X209058Y3010D03*
X203716Y17042D03*
Y22034D03*
X208672Y17042D03*
Y22034D03*
X201716Y19538D03*
X201567Y23978D03*
X196611D03*
X194611Y25974D03*
X203567D03*
X208784D03*
X202626Y37106D03*
X195539D03*
X202626Y48720D03*
X195539D03*
X200539Y69340D03*
X193583Y66844D03*
Y71836D03*
X198539Y66844D03*
Y71836D03*
X204717Y72844D03*
Y77836D03*
X202717Y75340D03*
X195888Y581071D03*
X194515Y583433D03*
X195888Y615071D03*
X194515Y617433D03*
Y651433D03*
X195888Y649071D03*
X205320Y667562D03*
X207856Y686443D03*
X203043Y686483D03*
X207824Y681560D03*
X203044Y684036D03*
X207834Y684006D03*
X203237Y681549D03*
X199720Y732862D03*
X206720Y731862D03*
X199220Y739362D03*
X207602Y756855D03*
X199602D03*
X201661Y1384286D03*
X193861D03*
X196461D03*
X199061D03*
X201661Y1387393D03*
X193861D03*
X196461D03*
X199061D03*
X204261Y1384286D03*
X207461D03*
X201861Y1390500D03*
X199261D03*
X195874Y1399732D03*
X198344D03*
X200774D03*
X195874Y1394132D03*
X198344D03*
X200774D03*
X201071Y1412173D03*
X193075Y1580678D03*
Y1575686D03*
X200179D03*
X205135D03*
X200179Y1580678D03*
X205135D03*
X193075Y1592590D03*
Y1587598D03*
X200179Y1592590D03*
X205135D03*
X200179Y1587598D03*
X205135D03*
X198375Y1599884D03*
X193419D03*
X205479D03*
X193419Y1616788D03*
Y1611796D03*
X198375D03*
X193419Y1604876D03*
X198375D03*
Y1616788D03*
X205479Y1611796D03*
Y1604876D03*
Y1616788D03*
X207229Y1631181D03*
X193410Y1711606D03*
X205582Y1700867D03*
X196443Y1722197D03*
X217889Y17042D03*
Y22034D03*
X222845Y17042D03*
Y22034D03*
X210672Y19538D03*
X215889D03*
X224845D03*
X215740Y23978D03*
X210784D03*
X217740Y25974D03*
X223886Y37106D03*
X216799D03*
X209713D03*
X223886Y48720D03*
X216799D03*
X209713D03*
X215717Y66844D03*
Y71836D03*
X220673Y66844D03*
Y71836D03*
X213717Y69340D03*
X222673D03*
X209673Y72844D03*
Y77836D03*
X211673Y75340D03*
X224717D03*
X209579Y457222D03*
Y462235D03*
X211220Y740362D03*
X215824Y1361199D03*
X211350Y1360797D03*
X218960Y1388312D03*
X210405Y1384302D03*
Y1387409D03*
X213075Y1381558D03*
X217133Y1384055D03*
X214425Y1384058D03*
X215675Y1381558D03*
X218175D03*
X213075Y1378958D03*
X215675D03*
X218175D03*
X210374Y1390532D03*
X212239Y1580678D03*
X217195D03*
Y1575686D03*
X212239D03*
X224299D03*
Y1580678D03*
X212239Y1587598D03*
X217195D03*
X212239Y1592590D03*
X217195D03*
X224299Y1587598D03*
Y1592590D03*
X210435Y1599884D03*
X222495D03*
X217539D03*
X210435Y1611796D03*
Y1604876D03*
Y1616788D03*
X222495D03*
X217539D03*
X222495Y1604876D03*
Y1611796D03*
X217539Y1604876D03*
Y1611796D03*
X212684Y1720307D03*
X229058Y3010D03*
X238063Y37162D03*
X230972Y37106D03*
Y48720D03*
X226717Y72844D03*
Y77836D03*
X231673Y72844D03*
Y77836D03*
X233673Y75340D03*
X233800Y162692D03*
X237539Y174266D03*
X228550Y420412D03*
X229255Y1575686D03*
Y1580678D03*
X236359D03*
Y1575686D03*
X241315Y1580678D03*
Y1575686D03*
X229255Y1587598D03*
Y1592590D03*
X236359D03*
Y1587598D03*
X241315Y1592590D03*
Y1587598D03*
X229599Y1599884D03*
X234555D03*
X229599Y1604876D03*
Y1611796D03*
X234555Y1604876D03*
Y1611796D03*
X229599Y1616788D03*
X234555D03*
X249058Y3010D03*
X243490Y23002D03*
X247720Y71862D03*
X244300Y59762D03*
X247720Y75862D03*
X251797Y100843D03*
X249735Y152694D03*
X242255Y162512D03*
X249300Y510362D03*
X253800Y515362D03*
X249860Y518222D03*
X248419Y1575686D03*
X253375D03*
X248419Y1580678D03*
X253375D03*
X248419Y1587598D03*
X253375D03*
X248419Y1592590D03*
X253375D03*
X246615Y1599884D03*
X241659D03*
X253719D03*
X241659Y1616788D03*
X246615D03*
Y1604876D03*
X241659D03*
X246615Y1611796D03*
X241659D03*
X253719Y1604876D03*
Y1611796D03*
Y1616788D03*
X269058Y3010D03*
X263280Y35312D03*
X272600Y27182D03*
X271600Y40162D03*
X272361Y120243D03*
X270364Y118415D03*
X261387Y133783D03*
X258257D03*
X264578Y155203D03*
Y159203D03*
X260700Y218662D03*
X268940Y217982D03*
X270745Y207562D03*
X265343Y244460D03*
X272029Y443735D03*
X274270Y746602D03*
X260479Y1580678D03*
X265435D03*
X260479Y1575592D03*
X265435D03*
X272539Y1575686D03*
Y1580678D03*
X260479Y1592590D03*
X265435D03*
X260479Y1587598D03*
X265435D03*
X272539D03*
Y1592590D03*
X258675Y1599884D03*
X270735Y1599790D03*
X265779D03*
X258675Y1604876D03*
Y1611796D03*
Y1616788D03*
X270735D03*
X265779D03*
X270735Y1611796D03*
Y1604876D03*
X265779D03*
Y1611796D03*
X289058Y3010D03*
X285900Y23962D03*
X287952Y39984D03*
X286071Y48720D03*
X286500Y52462D03*
X278984Y48720D03*
X287800Y60062D03*
X283953Y152503D03*
X288520Y157062D03*
X279740Y205962D03*
X276890Y249022D03*
X289920Y248652D03*
X286920D03*
X282420D03*
X287819Y691097D03*
X287820Y727962D03*
X278520Y738072D03*
X290077Y739735D03*
X289047Y760245D03*
X277495Y1575686D03*
Y1580678D03*
X284599D03*
X289555D03*
Y1575686D03*
X284599D03*
X277495Y1587598D03*
Y1592590D03*
X284599D03*
X289555D03*
X284599Y1587598D03*
X289555D03*
X282795Y1599884D03*
X277839D03*
X289899D03*
X282795Y1604876D03*
Y1611796D03*
X277839D03*
Y1604876D03*
X282795Y1616788D03*
X277839D03*
X289899D03*
Y1604876D03*
Y1611796D03*
X291520Y12762D03*
X291660Y21642D03*
X298720Y40017D03*
X306720Y39982D03*
X292942Y67513D03*
X293447Y78573D03*
X293452Y82483D03*
Y85983D03*
X303047Y79373D03*
X299947Y79273D03*
X299657Y92503D03*
X299628Y149203D03*
Y158703D03*
X294553Y153819D03*
X306087Y569718D03*
X294658Y637809D03*
X290680Y745312D03*
X299427Y768265D03*
X303831Y1318566D03*
X303807Y1342225D03*
X303831Y1344866D03*
X304047Y1368565D03*
X296659Y1575686D03*
X301615D03*
X296659Y1580678D03*
X301615D03*
X296659Y1587598D03*
X301615D03*
X296659Y1592590D03*
X301615D03*
X294855Y1599884D03*
X301959D03*
X294855Y1616788D03*
Y1604876D03*
Y1611796D03*
X301959Y1604876D03*
Y1611796D03*
Y1616788D03*
X309058Y3010D03*
X320057Y85803D03*
Y88803D03*
X314200Y585282D03*
X316080Y578262D03*
X320691Y602448D03*
X311820Y598762D03*
X316397Y776125D03*
X312301Y1345539D03*
Y1342432D03*
X309701Y1345539D03*
Y1342432D03*
X316655Y1352295D03*
X314175D03*
X311695D03*
X320101Y1342432D03*
X317701Y1348646D03*
X315101D03*
X314901Y1345539D03*
X317501D03*
X314901Y1342432D03*
X317501D03*
X316655Y1357895D03*
X311695D03*
X314175D03*
X317979Y1371248D03*
X315221Y1372445D03*
X308719Y1580678D03*
X313675D03*
X308719Y1575686D03*
X313675D03*
X320779D03*
Y1580678D03*
X308719Y1592590D03*
X313675D03*
X308719Y1587598D03*
X313675D03*
X320779D03*
Y1592590D03*
X306915Y1599884D03*
X318975D03*
X314019D03*
X306915Y1604876D03*
Y1611796D03*
Y1616788D03*
X318975D03*
X314019D03*
X318975Y1604876D03*
Y1611796D03*
X314019Y1604876D03*
Y1611796D03*
X329535Y49388D03*
X336240Y150738D03*
X330674Y368261D03*
X331760Y705882D03*
X328915Y1337104D03*
X331515D03*
X328915Y1331904D03*
X331515D03*
X328915Y1329304D03*
X331515D03*
X328915Y1334504D03*
X331515D03*
X328915Y1339704D03*
X326145Y1348651D03*
X326245Y1345555D03*
Y1342448D03*
X323301Y1342432D03*
X338917Y1349488D03*
X336347Y1348353D03*
X325735Y1575686D03*
Y1580678D03*
X332839D03*
X337795D03*
X332839Y1575686D03*
X337795D03*
X325735Y1587598D03*
Y1592590D03*
X332839D03*
X337795D03*
X332839Y1587598D03*
X337795D03*
X326079Y1599884D03*
X331035D03*
X338139D03*
X326079Y1604876D03*
Y1611796D03*
X331035Y1604876D03*
Y1611796D03*
X326079Y1616788D03*
X331035D03*
X338139D03*
Y1604876D03*
Y1611796D03*
X349535Y49388D03*
X343040Y122522D03*
X345869Y192716D03*
X353145Y228362D03*
X345164Y314234D03*
X349187Y715485D03*
X344446Y739434D03*
X348000Y755362D03*
X344429Y1322741D03*
X347029D03*
X341829D03*
X347029Y1319634D03*
X344429D03*
X341829D03*
X349629Y1322741D03*
Y1319634D03*
X352229D03*
X355429D03*
X346303Y1335097D03*
X343823D03*
Y1329497D03*
X346303D03*
X347229Y1325848D03*
X348783Y1329497D03*
X349829Y1325848D03*
X348783Y1335097D03*
X348804Y1346877D03*
X350470Y1349030D03*
X344899Y1575686D03*
X349855D03*
X344899Y1580678D03*
X349855D03*
X344899Y1587598D03*
X349855D03*
X344899Y1592590D03*
X349855D03*
X343095Y1599884D03*
X355155D03*
X350199D03*
X343095Y1616788D03*
Y1604876D03*
Y1611796D03*
X355155Y1604876D03*
Y1611796D03*
X350199Y1604876D03*
Y1611796D03*
X355155Y1616788D03*
X350199D03*
X366775Y127662D03*
X356250Y216342D03*
X358209Y208169D03*
X357764Y314234D03*
X363750Y369362D03*
X371370Y373622D03*
X364014Y382304D03*
X359930Y732985D03*
X360927Y757665D03*
X361043Y1306506D03*
X363643D03*
X367939Y1303319D03*
Y1305919D03*
Y1308519D03*
X358373Y1322757D03*
Y1319650D03*
X361043Y1314306D03*
Y1316906D03*
X362393Y1319406D03*
X361043Y1309106D03*
Y1311706D03*
X363643Y1316906D03*
Y1314306D03*
Y1309106D03*
Y1311706D03*
X358273Y1325853D03*
X370874Y1335876D03*
X367490Y1332568D03*
X356959Y1580678D03*
X361915D03*
X356959Y1575592D03*
X361915D03*
X369019Y1575686D03*
Y1580678D03*
X356959Y1592590D03*
X361915D03*
X356959Y1587598D03*
X361915D03*
X367215Y1599790D03*
X362259D03*
X369019Y1587598D03*
Y1592590D03*
X367215Y1616788D03*
X362259D03*
X367215Y1604876D03*
Y1611796D03*
X362259Y1604876D03*
Y1611796D03*
X376245Y212862D03*
Y217362D03*
Y221362D03*
Y225362D03*
X386120Y220322D03*
X385720Y323761D03*
X376500Y362736D03*
X373957Y1306208D03*
X381757D03*
X379157D03*
X376557D03*
X384357D03*
X387557D03*
X375951Y1321671D03*
X380911Y1316071D03*
X378431D03*
Y1321671D03*
X380911D03*
X373957Y1309315D03*
X381957Y1312422D03*
X381757Y1309315D03*
X379357Y1312422D03*
X379157Y1309315D03*
X376557D03*
X375951Y1316071D03*
X380842Y1334095D03*
X383549Y1333998D03*
X383127Y1395610D03*
X381060Y1433622D03*
X380930Y1531402D03*
X384210Y1534152D03*
X387152Y1582659D03*
X373975Y1575686D03*
Y1580678D03*
Y1587598D03*
Y1592590D03*
X379275Y1599884D03*
X374319D03*
X379275Y1604876D03*
Y1611796D03*
X374319Y1604876D03*
Y1611796D03*
X379275Y1616788D03*
X374319D03*
X374690Y1631700D03*
X375550Y1662052D03*
X386824Y1682866D03*
X387760Y1671092D03*
X393830Y62062D03*
X399800Y59662D03*
X403800D03*
X390830Y155833D03*
X388965Y209949D03*
X398720Y318643D03*
X403675Y363081D03*
X391195Y368199D03*
X391101Y380939D03*
X403581Y375880D03*
X390730Y394852D03*
X403570Y388874D03*
X395771Y1303480D03*
X393171D03*
X395771Y1300880D03*
X393171D03*
X395771Y1295680D03*
X393171D03*
X395771Y1298280D03*
X393171D03*
X394521Y1305980D03*
X390501Y1306224D03*
X400067Y1303319D03*
Y1300719D03*
Y1295519D03*
Y1298119D03*
Y1305919D03*
Y1308519D03*
X390401Y1312427D03*
X390501Y1309331D03*
X399673Y1332653D03*
X403130Y1335963D03*
X400919Y1411231D03*
X391370Y1424782D03*
X392108Y1582659D03*
X401812Y1616456D03*
X394910Y1632364D03*
Y1637320D03*
X402246Y1671745D03*
X409535Y49388D03*
X412930Y62572D03*
X413459Y129061D03*
X411434Y163662D03*
X407490Y216912D03*
X412820Y231922D03*
X405478Y236726D03*
X410090Y241932D03*
X420710Y242482D03*
X419023Y381760D03*
X418982Y407847D03*
X416485Y1306208D03*
X419685D03*
X413885D03*
X406085D03*
X411285D03*
X408685D03*
X414085Y1312422D03*
X413885Y1309315D03*
X411485Y1312422D03*
X408685Y1309315D03*
X406085D03*
X411285D03*
X413039Y1316071D03*
X408079D03*
X410559D03*
X413039Y1321671D03*
X408079D03*
X410559D03*
X416099Y1335568D03*
X414617Y1333473D03*
X412465Y1393878D03*
X419974Y1405289D03*
Y1412789D03*
X420474Y1420289D03*
X407125Y1424978D03*
X404475Y1552452D03*
X419002Y1600306D03*
X406526Y1591212D03*
Y1596168D03*
X406768Y1616456D03*
X408700Y1603500D03*
Y1614300D03*
X411910Y1629170D03*
Y1624214D03*
X410232Y1670244D03*
X429535Y49388D03*
X430655Y58677D03*
X433695Y214862D03*
X429395Y232562D03*
X426295Y227862D03*
X422210Y221452D03*
X429395Y236562D03*
Y240562D03*
X425249Y338061D03*
X431503Y376642D03*
X431462Y402729D03*
X422629Y1306224D03*
X432195Y1303319D03*
Y1305919D03*
X425299Y1303480D03*
X426649Y1305980D03*
X427899Y1303480D03*
X425299Y1295680D03*
X427899D03*
X432195Y1295519D03*
Y1298119D03*
X427899Y1298280D03*
X425299D03*
X432195Y1300719D03*
X427899Y1300880D03*
X425299D03*
X432195Y1308519D03*
X422529Y1312427D03*
X422629Y1309331D03*
X434983Y1335924D03*
X431578Y1332560D03*
X427474Y1405289D03*
X434974D03*
Y1412789D03*
X427474Y1420289D03*
X434974D03*
X423958Y1600306D03*
X428099Y1586282D03*
X428941Y1606441D03*
X449535Y49388D03*
X443678Y145710D03*
X445964Y314234D03*
X450400Y338812D03*
X442853Y542519D03*
Y547519D03*
X448613Y1306208D03*
X446013D03*
X443413D03*
X440813D03*
X438213D03*
X451813D03*
X443613Y1312422D03*
X443413Y1309315D03*
X440813D03*
X438213D03*
X446213Y1312422D03*
X446013Y1309315D03*
X440207Y1316071D03*
X445167D03*
X442687D03*
X440207Y1321671D03*
X445167D03*
X442687D03*
X446944Y1335928D03*
X445153Y1334095D03*
X446258Y1441606D03*
X449778D03*
X451910Y1643282D03*
X437562Y1649770D03*
X442518D03*
X469535Y49388D03*
X454568Y78782D03*
X466992Y145888D03*
X458264Y254862D03*
X460300Y303662D03*
X468490Y340572D03*
X469830Y366158D03*
X460323Y510183D03*
X458327Y1303980D03*
X460927D03*
X464427Y1305380D03*
X454757Y1306224D03*
X460927Y1306580D03*
X458327D03*
Y1301380D03*
X460927D03*
X464427Y1300180D03*
Y1302780D03*
X458327Y1296180D03*
X460927D03*
X464427D03*
X458327Y1298780D03*
X460927D03*
X464423Y1308519D03*
X454657Y1312427D03*
X454757Y1309331D03*
X464738Y1333085D03*
X467644Y1335981D03*
X455576Y1409125D03*
Y1417125D03*
Y1420625D03*
Y1427632D03*
Y1424125D03*
X454450Y1433580D03*
X464160Y1587122D03*
X458414Y1624994D03*
Y1629950D03*
X468040Y1654807D03*
X478240Y55935D03*
Y66575D03*
Y61129D03*
X484396Y161364D03*
X475500Y212685D03*
X472800Y299462D03*
X484800Y307362D03*
X476740Y309272D03*
X479740Y300202D03*
X482920Y398060D03*
X479379Y452445D03*
X480741Y1306208D03*
X478141D03*
X475541D03*
X472941D03*
X470341D03*
X483941D03*
X472941Y1309315D03*
X478141D03*
X470341D03*
X478341Y1312422D03*
X475741D03*
X475541Y1309315D03*
X472335Y1316071D03*
X477295D03*
X474815D03*
X472335Y1321671D03*
X477295D03*
X474815D03*
X477162Y1334095D03*
X478909Y1336038D03*
X485236Y1417844D03*
X482741Y1438698D03*
X482742Y1441312D03*
X484333Y1575686D03*
Y1580678D03*
X477229D03*
X472273D03*
Y1575686D03*
X477229D03*
X482529Y1599884D03*
X477573D03*
X484333Y1587598D03*
Y1592590D03*
X472273D03*
X477229D03*
Y1587598D03*
X472273D03*
X482529Y1616788D03*
X477573D03*
Y1611796D03*
X482529D03*
X477573Y1604876D03*
X482529D03*
X472210Y1618626D03*
X485150Y1624942D03*
X477905Y1667242D03*
X489535Y49347D03*
X497002Y88167D03*
X501540Y105152D03*
X498630Y140492D03*
X489980Y250512D03*
X492074Y300306D03*
X497568Y397632D03*
X494193Y550447D03*
X486885Y1306224D03*
X496451Y1306345D03*
X489555Y1303480D03*
X492155D03*
X490905Y1305980D03*
X492155Y1300880D03*
X489555D03*
X486785Y1312427D03*
X486885Y1309331D03*
X496220Y1322440D03*
X496451Y1316745D03*
Y1308945D03*
Y1314145D03*
Y1311545D03*
X499458Y1349468D03*
X499818Y1385027D03*
X499859Y1393027D03*
X490307Y1421499D03*
X491156Y1438713D03*
X499541Y1438698D03*
X491142Y1441312D03*
X499542D03*
X501349Y1580678D03*
X496393D03*
Y1575686D03*
X501349D03*
X489289D03*
Y1580678D03*
X501693Y1599884D03*
X494589D03*
X489633D03*
X501349Y1592590D03*
X496393D03*
X501349Y1587598D03*
X496393D03*
X489289D03*
Y1592590D03*
X501693Y1611796D03*
Y1604876D03*
Y1616788D03*
X489633Y1611796D03*
X494589Y1604876D03*
X489633D03*
X494589Y1611796D03*
X489633Y1616788D03*
X494589D03*
X487340Y1641352D03*
X517902Y69508D03*
X510815D03*
X503100Y78402D03*
X510030Y78412D03*
X504980Y101752D03*
X503290Y140492D03*
X507360D03*
X514850Y168443D03*
X504075Y231262D03*
X508000Y237862D03*
X505900Y311562D03*
X510740Y332592D03*
X513173Y408740D03*
X514425Y489112D03*
Y495112D03*
X509493Y539819D03*
X513025Y615742D03*
X516069Y1319634D03*
X502469D03*
Y1322741D03*
X512869Y1319634D03*
X510269D03*
X507669D03*
X505069D03*
X507669Y1322741D03*
X505069D03*
X510269D03*
X504463Y1329497D03*
Y1335097D03*
X509423Y1329497D03*
X506943D03*
X509423Y1335097D03*
X506943D03*
X510469Y1325848D03*
X507869D03*
X509382Y1347521D03*
X511149Y1349468D03*
X505018Y1385027D03*
X502418D03*
X505059Y1393027D03*
X502459D03*
X508001Y1438669D03*
X507942Y1441312D03*
X508453Y1575686D03*
X513409D03*
X508453Y1580678D03*
X513409D03*
X513753Y1599884D03*
X506649D03*
X508453Y1587598D03*
X513409D03*
X508453Y1592590D03*
X513409D03*
X513753Y1616788D03*
Y1604876D03*
Y1611796D03*
X506649D03*
Y1604876D03*
Y1616788D03*
X518606Y23797D03*
X532075Y69508D03*
Y57894D03*
X524988Y69508D03*
X529239Y99997D03*
Y92911D03*
X528400Y104225D03*
Y114275D03*
X527823Y131802D03*
Y149802D03*
X527278Y164726D03*
X529480Y183921D03*
X536127Y247652D03*
X523660Y323222D03*
X535220Y383552D03*
X528145Y408705D03*
X518735Y452442D03*
X526852Y511331D03*
X527042Y505830D03*
X526853Y516817D03*
X523033Y1319406D03*
X519013Y1319650D03*
Y1322757D03*
X527645Y1326076D03*
X528579Y1329143D03*
X528377Y1335982D03*
X518913Y1325853D03*
X528579Y1342143D03*
Y1344743D03*
X534597Y1345539D03*
Y1342432D03*
X528975Y1369724D03*
X532573Y1575686D03*
Y1580678D03*
X520513D03*
X525469D03*
X520513Y1575686D03*
X525469D03*
X525813Y1599884D03*
X530769D03*
X518709D03*
X532573Y1587598D03*
Y1592590D03*
X525469D03*
X520513D03*
Y1587598D03*
X525469D03*
X525813Y1611796D03*
X530769D03*
X525813Y1604876D03*
X530769D03*
Y1616788D03*
X525813D03*
X518709D03*
Y1604876D03*
Y1611796D03*
X548609Y32500D03*
X546248Y69508D03*
X539161D03*
Y57894D03*
X546234Y77443D03*
X542620Y103352D03*
X537360Y120522D03*
X550545Y147302D03*
X542798Y202646D03*
X535630Y306602D03*
X543035Y441005D03*
X538120Y463137D03*
X544813Y1322668D03*
X542213D03*
X538293D03*
X535693D03*
X548197Y1342432D03*
X539997Y1348646D03*
X542397Y1345539D03*
X542597Y1348646D03*
X537197Y1342432D03*
X539797D03*
X542397D03*
X544997D03*
X537197Y1345539D03*
X539797D03*
X539071Y1352295D03*
X536591D03*
X541551D03*
Y1357895D03*
X542256Y1369935D03*
X536591Y1357895D03*
X539071D03*
X549589Y1580678D03*
X544633D03*
X549589Y1575592D03*
X544633D03*
X537529Y1575686D03*
Y1580678D03*
X549933Y1599790D03*
X537873Y1599884D03*
X542829D03*
X549589Y1592590D03*
X544633D03*
X549589Y1587598D03*
X544633D03*
X537529D03*
Y1592590D03*
X549933Y1611796D03*
Y1604876D03*
Y1616788D03*
X542829D03*
X537873D03*
Y1604876D03*
X542829D03*
X537873Y1611796D03*
X542829D03*
X560421Y69508D03*
X553335D03*
X553320Y77443D03*
X564988Y118670D03*
X555545Y134340D03*
X565500Y145252D03*
X555220Y167937D03*
X553657Y193862D03*
X564944Y252173D03*
X553536Y307527D03*
X569080Y414002D03*
X559300Y422732D03*
X558933Y1323658D03*
Y1326258D03*
X556563Y1337918D03*
X553963D03*
X558933Y1328938D03*
X556563Y1335318D03*
Y1332718D03*
X558933Y1331538D03*
X553963Y1335318D03*
Y1332718D03*
X555313Y1340418D03*
X551141Y1345555D03*
X551041Y1348651D03*
X551141Y1342448D03*
X555372Y1343037D03*
X561070Y1346174D03*
X556693Y1575686D03*
X561649D03*
X556693Y1580678D03*
X561649D03*
X561993Y1599884D03*
X554889Y1599790D03*
X556693Y1587598D03*
X561649D03*
Y1592590D03*
X556693D03*
X561993Y1616788D03*
Y1604876D03*
Y1611796D03*
X554889D03*
Y1604876D03*
Y1616788D03*
X567673Y130542D03*
X581175Y164717D03*
X569965Y161232D03*
X579481Y202378D03*
Y210378D03*
X568149Y217916D03*
X580712Y215877D03*
X581645Y233362D03*
X569668Y229812D03*
X578711Y230109D03*
X578509Y265132D03*
X569880Y300992D03*
X580400Y302402D03*
X582436Y361032D03*
X570200Y372229D03*
X570760Y451710D03*
X571990Y501046D03*
X571700Y552200D03*
X580813Y1575686D03*
Y1580678D03*
X573709D03*
X568753D03*
Y1575686D03*
X573709D03*
X579009Y1599884D03*
X574053D03*
X566949D03*
X580813Y1587598D03*
Y1592590D03*
X573709D03*
X568753D03*
X573709Y1587598D03*
X568753D03*
X574053Y1616788D03*
X579009D03*
Y1611796D03*
X574053D03*
X579009Y1604876D03*
X574053D03*
X566949Y1616788D03*
Y1604876D03*
Y1611796D03*
X591395Y132142D03*
X595220Y140922D03*
X588000D03*
X592710Y156342D03*
X593248Y159480D03*
X598295Y171862D03*
X596581Y184849D03*
X590337Y177604D03*
X598760Y203712D03*
X593966Y229965D03*
X592039Y252202D03*
X588577Y285862D03*
X586820Y314662D03*
X597820Y317062D03*
X592920Y326362D03*
X591720Y430787D03*
X599220Y444362D03*
X593545Y488212D03*
X594090Y505107D03*
X589260Y519421D03*
X594240Y511953D03*
X593675Y534702D03*
X589989Y745475D03*
X597829Y1580678D03*
X592873D03*
X597829Y1575686D03*
X592873D03*
X585769D03*
Y1580678D03*
X598173Y1599884D03*
X586113D03*
X591069D03*
X597829Y1592590D03*
X592873D03*
X597829Y1587598D03*
X592873D03*
X585769D03*
Y1592590D03*
X598173Y1616788D03*
Y1611796D03*
Y1604876D03*
X586113D03*
X591069D03*
X586113Y1611796D03*
X591069D03*
Y1616788D03*
X586113D03*
X615185Y69508D03*
X603374D03*
X601050Y100008D03*
X610104Y119342D03*
X602306Y143077D03*
X602430Y153862D03*
X606260Y161652D03*
X615572Y173942D03*
X615573Y181984D03*
X614531Y200378D03*
X611030Y188372D03*
X603340Y208142D03*
X614531Y209878D03*
X609456Y204994D03*
X606719Y254966D03*
X609844Y330407D03*
X608830Y374302D03*
X605830Y402782D03*
X604779Y423862D03*
X600351Y461862D03*
X614220Y452862D03*
X610820Y472862D03*
X603779Y486922D03*
X606200Y514862D03*
X609520Y515162D03*
X614086Y537624D03*
X614000Y550800D03*
X603317Y738415D03*
X614660Y739553D03*
X602027Y761445D03*
X612407Y769485D03*
X609889Y1575686D03*
X604933D03*
X609889Y1580678D03*
X604933D03*
X615189Y1599884D03*
X610233D03*
X603129D03*
X609889Y1587598D03*
X604933D03*
X609889Y1592590D03*
X604933D03*
X615189Y1604876D03*
X610233D03*
X615189Y1611796D03*
X610233D03*
X615189Y1616788D03*
X610233D03*
X603129D03*
Y1611796D03*
Y1604876D03*
X631546Y85024D03*
X618460Y119342D03*
X631300Y167872D03*
X628195Y178414D03*
X628194Y170372D03*
X630818Y191248D03*
X625862D03*
X620030Y188782D03*
X627645Y236862D03*
X629564Y256277D03*
X623150Y273172D03*
X625800Y311912D03*
X628294Y317007D03*
X623580Y336429D03*
X629248Y436972D03*
X629220Y472862D03*
Y477862D03*
Y467862D03*
Y482862D03*
X626207Y747585D03*
X618114Y1258470D03*
X629053Y1575686D03*
Y1580678D03*
X621949D03*
X616993D03*
X621949Y1575686D03*
X616993D03*
X622293Y1599884D03*
X627249D03*
X629053Y1587598D03*
Y1592590D03*
X621949D03*
X616993D03*
X621949Y1587598D03*
X616993D03*
X627249Y1616788D03*
X622293D03*
Y1611796D03*
X627249D03*
X622293Y1604876D03*
X627249D03*
X646440Y43632D03*
X632463Y43302D03*
X645150Y69508D03*
X645350Y60612D03*
X632640Y107532D03*
X637500Y110362D03*
X642480Y184862D03*
X645876Y296231D03*
X633138Y296766D03*
X645528Y308623D03*
X645807Y304291D03*
X647200Y354300D03*
X643736Y457214D03*
X644245Y472862D03*
X644220Y467862D03*
X644245Y482862D03*
X636960Y516002D03*
X646069Y1580678D03*
X641113D03*
X646069Y1575592D03*
X641113D03*
X634009Y1575686D03*
Y1580678D03*
X646413Y1599790D03*
X639309Y1599884D03*
X634353D03*
X646069Y1592590D03*
X641113D03*
X646069Y1587598D03*
X641113D03*
X634009D03*
Y1592590D03*
X646413Y1616788D03*
Y1611796D03*
Y1604876D03*
X639309D03*
X634353D03*
X639309Y1611796D03*
X634353D03*
Y1616788D03*
X639309D03*
X641057Y1648659D03*
X645407Y1660425D03*
X639745Y1714362D03*
X648290Y1720052D03*
X639745Y1726362D03*
X661550Y45133D03*
X654464D03*
X652153Y98105D03*
X652680Y89712D03*
X651579Y102703D03*
X659000Y89262D03*
X651980Y133822D03*
X650790Y144982D03*
X660690Y408162D03*
X660720Y404362D03*
X653800Y498740D03*
X662282Y1386432D03*
X654606Y1431203D03*
X653173Y1575686D03*
X658129D03*
X653173Y1580678D03*
X658129D03*
X663429Y1599884D03*
X658473D03*
X651369Y1599790D03*
X653173Y1587598D03*
X658129D03*
X653173Y1592590D03*
X658129D03*
X663429Y1604876D03*
X658473D03*
X663429Y1611796D03*
X658473D03*
Y1616788D03*
X663429D03*
X651369D03*
Y1611796D03*
Y1604876D03*
X663043Y1647557D03*
X655307Y1647436D03*
X663118Y1659557D03*
X663145Y1664862D03*
Y1676862D03*
X656973Y1698727D03*
X652712Y1686275D03*
X672005Y44119D03*
X668800Y45262D03*
X666406Y69508D03*
X675225Y58108D03*
X673750Y77692D03*
X673690Y200672D03*
X673300Y211332D03*
X667020Y225762D03*
X680600Y375462D03*
X668329Y411714D03*
X677295Y404362D03*
X677195Y408262D03*
X674628Y414864D03*
Y443210D03*
X671479Y430612D03*
Y462108D03*
X668329Y481006D03*
X675220Y503837D03*
X680220D03*
X675220Y516852D03*
X671607Y742835D03*
X668096Y1360822D03*
X677137Y1384311D03*
X674537D03*
X671937D03*
X669337D03*
X677137Y1387418D03*
X674537D03*
X671937D03*
X669337D03*
X664782Y1383832D03*
Y1381232D03*
Y1378632D03*
Y1386432D03*
X679737Y1384311D03*
X677337Y1390525D03*
X674737D03*
X676250Y1399757D03*
X673820D03*
X671350D03*
X676250Y1394157D03*
X673820D03*
X671350D03*
X666425Y1414200D03*
X676312Y1411554D03*
X667926Y1547018D03*
X679192Y1564252D03*
X678515Y1573910D03*
X676648Y1657380D03*
X671620Y1670862D03*
X674195Y1708362D03*
X669120Y1718862D03*
X674195Y1732362D03*
X696838Y45112D03*
X686854Y43701D03*
X692380Y43532D03*
X682941Y69982D03*
X687050Y79212D03*
X685230Y76952D03*
X683820Y79192D03*
X682890Y72642D03*
X684953Y104968D03*
X694390Y133682D03*
X684520Y152482D03*
X688520D03*
X692520D03*
X686760Y222912D03*
X685600Y375462D03*
X690600D03*
X695600D03*
X688220Y388362D03*
X697220Y404362D03*
X697120Y408262D03*
X684077Y414864D03*
X680928Y424313D03*
X696676Y436911D03*
X693526Y443210D03*
Y440061D03*
Y436911D03*
X690376Y440061D03*
Y433761D03*
X693526Y452659D03*
Y449510D03*
X696676Y455809D03*
X693526D03*
X690376Y452659D03*
Y458959D03*
X696676Y477856D03*
X684077D03*
X680928Y468407D03*
X690220Y516852D03*
X684357Y742345D03*
X692784Y1298845D03*
X686426Y1360822D03*
X695022Y1361990D03*
X696462Y1386122D03*
X682937Y1384311D03*
X685881Y1384327D03*
Y1387434D03*
X691351Y1380922D03*
X688751D03*
X691240Y1383522D03*
X693851D03*
Y1378322D03*
Y1380922D03*
X691351Y1378322D03*
X688751D03*
X693851Y1386122D03*
X696462Y1378322D03*
Y1383522D03*
Y1380922D03*
X696272Y1404560D03*
X685850Y1390557D03*
X685015Y1438475D03*
X696940Y1437955D03*
X689875Y1577913D03*
X689128Y1652262D03*
X692595Y1670862D03*
X701838Y45112D03*
X700610Y57782D03*
X700741Y83050D03*
X706673Y122762D03*
X703520Y122540D03*
X704880Y133643D03*
X701926Y166535D03*
Y178346D03*
Y184252D03*
Y172441D03*
Y190157D03*
Y196063D03*
Y201968D03*
Y207874D03*
Y213779D03*
Y219685D03*
X700600Y375462D03*
X705600D03*
X706125Y421163D03*
X709274Y436911D03*
X706125Y440061D03*
Y436911D03*
X699825Y440061D03*
Y436911D03*
X712424Y443210D03*
Y440061D03*
Y436911D03*
Y455809D03*
X709274D03*
X706125D03*
Y452659D03*
X699825Y455809D03*
Y452659D03*
X712424D03*
Y449510D03*
X709274Y477856D03*
X699825Y468407D03*
X711220Y516852D03*
X705220D03*
X698600Y530700D03*
X701917Y742865D03*
X703755Y1290545D03*
X708795Y1303701D03*
X698094Y1361947D03*
X706239Y1360822D03*
X699062Y1380922D03*
Y1383522D03*
Y1378322D03*
X707480Y1384311D03*
X710080D03*
X707480Y1387418D03*
X710080D03*
X701662Y1380922D03*
Y1383522D03*
Y1378322D03*
X699062Y1386122D03*
X701662D03*
X712680Y1384311D03*
Y1387418D03*
X709493Y1399757D03*
Y1394157D03*
X712880Y1390525D03*
X711963Y1399757D03*
Y1394157D03*
X699262Y1413970D03*
X704568Y1414119D03*
X706680Y1437535D03*
X701730Y1437855D03*
X711440Y1436905D03*
X702112Y1583683D03*
X709111Y1618842D03*
X697595Y1658862D03*
X704433Y1657964D03*
X697770Y1680810D03*
X714015Y-27612D03*
X720308Y-26403D03*
X714015Y-21457D03*
Y-17583D03*
X714030Y-15068D03*
X714015Y-11428D03*
X714030Y-25097D03*
X720308Y-16374D03*
X714015Y-7554D03*
X714030Y-5039D03*
X720308Y-6345D03*
X728980Y39872D03*
X728028Y101968D03*
X728023Y98058D03*
X728028Y105468D03*
X727720Y356362D03*
X725220Y380787D03*
X715600Y375462D03*
X718220Y388362D03*
X715220Y404362D03*
X715120Y408262D03*
X725022Y414864D03*
X715574Y433761D03*
Y458959D03*
X728172Y449510D03*
X725022Y477856D03*
X722720Y521362D03*
X729200Y588952D03*
X713836Y1283689D03*
X724969Y1360822D03*
X729443Y1361224D03*
X726694Y1381583D03*
Y1378983D03*
X715280Y1384311D03*
X717880D03*
X715280Y1387418D03*
X721080Y1384311D03*
X724024Y1384327D03*
Y1387434D03*
X728044Y1384083D03*
X729294Y1381583D03*
Y1378983D03*
X715480Y1390525D03*
X723993Y1390557D03*
X714393Y1399757D03*
Y1394157D03*
X714455Y1411554D03*
X718230Y1600372D03*
X725378Y1614503D03*
X719770Y1614590D03*
X715780D03*
X722040Y1623970D03*
X713791Y1629816D03*
X721345Y1647300D03*
X716140Y1649895D03*
X726830Y1655380D03*
X724500Y1676500D03*
X744987Y49062D03*
X742840Y39832D03*
X736790D03*
X745130Y69508D03*
X738043D03*
X730957D03*
X731330Y60712D03*
X730820Y84062D03*
X737623Y98858D03*
X734523Y98758D03*
X735733Y111988D03*
X733220Y388362D03*
X737621Y411714D03*
X743720Y404362D03*
X743820Y408262D03*
X731322Y430612D03*
Y462108D03*
X737621Y481006D03*
X730070Y506212D03*
X744630Y506529D03*
X745220Y530362D03*
X737299Y766887D03*
X737784Y1360017D03*
X730752Y1384080D03*
X731794Y1381583D03*
Y1378983D03*
X732238Y1388343D03*
X738810Y1396665D03*
X741540Y1396585D03*
X739170Y1405655D03*
X741670Y1405675D03*
X738170Y1414185D03*
X740760Y1414165D03*
X758606Y23797D03*
X747487Y49062D03*
X752720Y59002D03*
X754219Y75707D03*
X754633Y108288D03*
Y105288D03*
X762172Y123898D03*
X754290Y286632D03*
X755200Y296062D03*
X759940Y438232D03*
X758420Y447662D03*
X751220Y530362D03*
X753137Y766625D03*
X757779Y1390645D03*
X757542Y1420684D03*
X761770Y1695347D03*
X765606Y44894D03*
X769474Y75360D03*
X765858Y87340D03*
X762368Y84088D03*
X769284Y103895D03*
X767061Y99959D03*
X767045Y95960D03*
X767028Y91490D03*
X776730Y117479D03*
X773943Y114633D03*
X771131Y111788D03*
X769775Y107977D03*
X766769Y140138D03*
X771774Y167518D03*
X773220Y296262D03*
X772866Y311558D03*
X776100Y375100D03*
X766195Y418212D03*
X765315Y464862D03*
Y488862D03*
X772220Y530362D03*
X775317Y764025D03*
X763747Y764335D03*
X768520Y1379962D03*
X768620Y1392762D03*
X767820Y1410262D03*
X785095Y49388D03*
X780617Y296345D03*
X779120Y306162D03*
X794600Y360600D03*
X787925Y387900D03*
X781195Y418212D03*
X791590Y417050D03*
X780020Y438287D03*
X781410Y431822D03*
X780340Y468982D03*
Y474862D03*
X793673Y512862D03*
X792720Y589862D03*
X789720Y581862D03*
X783100Y593582D03*
X788225Y1388683D03*
X805095Y49388D03*
X797443Y271469D03*
X806300Y279662D03*
X809700Y273562D03*
X795190Y298572D03*
X798620Y312773D03*
X809800Y360600D03*
X802200D03*
X806588Y351097D03*
X799800Y368700D03*
X802220Y393727D03*
X803150Y408512D03*
X795600Y402500D03*
X799458Y431217D03*
X795370Y474862D03*
X801567Y512942D03*
X798720Y585362D03*
X798220Y597362D03*
X808860Y603802D03*
X797720Y617862D03*
X799637Y763625D03*
X825095Y49388D03*
X821118Y134632D03*
X825698Y139062D03*
X813900Y269698D03*
X827403Y286625D03*
X816420Y287062D03*
X813855Y354008D03*
X820936Y356956D03*
X824980Y405260D03*
Y409260D03*
X821720Y428437D03*
X818500Y451700D03*
X816500Y476800D03*
X821720Y519082D03*
X815040Y590772D03*
X814800Y760922D03*
X822442Y762369D03*
X814234Y1340465D03*
X830975Y2388D03*
X830990Y4903D03*
X837268Y3597D03*
X830975Y22446D03*
Y8543D03*
Y12417D03*
X830990Y14932D03*
X830975Y18572D03*
X837268Y13626D03*
X830990Y24961D03*
X837268Y23655D03*
X836126Y62681D03*
X837791Y85186D03*
X831297Y104206D03*
X842864Y110296D03*
X830339Y228143D03*
X829680Y264580D03*
X836210Y272452D03*
X829720Y277562D03*
X829800Y271562D03*
X829320Y296762D03*
X834400Y283862D03*
X834900Y293462D03*
X828222Y359960D03*
X835471Y363003D03*
X843133Y366158D03*
X833300Y386500D03*
X838784Y392880D03*
X839200Y434300D03*
X841300Y446800D03*
X842600Y477200D03*
X842341Y474241D03*
X841795Y492862D03*
X829745Y498082D03*
X834635Y515447D03*
X830480Y527817D03*
X831700Y596962D03*
X836847Y762495D03*
X828799Y1336870D03*
X828910Y1331756D03*
Y1341725D03*
X845095Y49388D03*
X854107Y91232D03*
X850280Y113852D03*
X853828Y265057D03*
X854333Y276117D03*
X854338Y280027D03*
Y283527D03*
X852800Y288562D03*
X853200Y297462D03*
X856700Y304862D03*
X848000Y374622D03*
X851396Y369614D03*
X859734Y373032D03*
X857560Y417762D03*
X844200Y418800D03*
X847830Y443892D03*
X843810Y453322D03*
X846700Y473000D03*
X848710Y505641D03*
X860345Y522162D03*
X856698Y594011D03*
X853200Y751062D03*
X854687Y761685D03*
X865095Y49388D03*
X868187Y72006D03*
X860937Y71877D03*
X861350Y61672D03*
X871980Y199500D03*
X860833Y276817D03*
X863933Y276917D03*
X862043Y290047D03*
X867922Y376450D03*
X875922Y379793D03*
X870700Y382415D03*
Y390620D03*
Y394620D03*
X871320Y416752D03*
X862620Y503162D03*
Y499062D03*
X860345Y513062D03*
X892214Y141891D03*
X878220Y192055D03*
X880943Y283347D03*
Y286347D03*
X880473Y329370D03*
X883472Y382910D03*
X886362Y534380D03*
X886500Y739162D03*
X878152Y876760D03*
X889439Y1437938D03*
X903930Y202885D03*
X903980Y210355D03*
X903930Y217059D03*
X903980Y224529D03*
X893500Y339062D03*
X900061Y510962D03*
X906127Y496343D03*
X900061Y517898D03*
X893298Y534380D03*
X899462Y533380D03*
X906398D03*
X897000Y891895D03*
X894375Y913692D03*
X912214Y141891D03*
X917680Y174999D03*
Y177999D03*
Y171999D03*
X909386Y195925D03*
Y203011D03*
Y210098D03*
Y217185D03*
Y224271D03*
Y231358D03*
X919279Y461244D03*
X920682Y494586D03*
X920980Y503393D03*
X911720Y511662D03*
X911626Y523430D03*
X918562D03*
X924647Y526808D03*
Y533744D03*
X924600Y824262D03*
X922320Y1660953D03*
X932214Y141891D03*
X927133Y189386D03*
X925320Y203399D03*
X940709Y460438D03*
X938437Y455454D03*
X932724Y455538D03*
X926215Y461244D03*
X929234Y494915D03*
X938588Y485197D03*
X929698Y503595D03*
X928231Y530479D03*
X936273Y530478D03*
X927200Y811462D03*
X931496Y962082D03*
X929221Y1014664D03*
X927122Y1661380D03*
X938220Y1661062D03*
X952214Y141891D03*
X949710Y198289D03*
X941634Y199051D03*
Y193451D03*
X951354Y209437D03*
Y203837D03*
X944880Y210959D03*
Y216559D03*
Y230697D03*
Y225097D03*
X954874Y232071D03*
X954904Y225741D03*
X942827Y422743D03*
Y429679D03*
X945800Y432463D03*
Y439399D03*
X946492Y460410D03*
X956188Y495384D03*
Y502320D03*
X948495Y502784D03*
X948693Y509497D03*
X956188Y509484D03*
Y516420D03*
X952622Y529364D03*
X956700Y786862D03*
X941400Y810062D03*
X946100Y1661100D03*
X972214Y141891D03*
X963520Y214699D03*
X960703Y212668D03*
X971471Y242358D03*
X965792Y350959D03*
X965420Y365719D03*
X963856Y394202D03*
X960059Y387004D03*
X972986Y393171D03*
X970054Y478773D03*
Y485709D03*
X966720Y511362D03*
X960620Y509462D03*
X972379Y509303D03*
X959558Y529364D03*
X962162Y535130D03*
X969098D03*
X958755Y657078D03*
X963520Y665062D03*
X958866Y662378D03*
X959100Y789862D03*
X975688Y152950D03*
Y149950D03*
X985016Y344659D03*
X974791Y339990D03*
X986182Y361062D03*
X979380Y373082D03*
X988159Y409068D03*
X983760Y424292D03*
X980092Y421289D03*
X983720Y512362D03*
X976283Y534226D03*
X994553Y365711D03*
X997598Y382952D03*
X997612Y391804D03*
X1006221Y382945D03*
X997900Y400720D03*
X993387Y429827D03*
X999720Y512862D03*
X991097Y529902D03*
X996675Y1286985D03*
X1012214Y141826D03*
X1022002Y267342D03*
Y270142D03*
X1013500Y344900D03*
X1015638Y382968D03*
X1015637Y391334D03*
X1006589Y392017D03*
X1006750Y401010D03*
X1015657Y401013D03*
X1021259Y420548D03*
X1007249Y422682D03*
X1017511Y430038D03*
X1008720Y498362D03*
X1019145Y503823D03*
X1011720Y589362D03*
X1018720Y592362D03*
X1021720Y601862D03*
X1010630Y748741D03*
X1023407Y-27681D03*
X1029700Y-26472D03*
X1023407Y-32055D03*
X1029700Y-37001D03*
X1023407Y-17652D03*
X1023422Y-15137D03*
X1023407Y-11497D03*
X1029700Y-16443D03*
X1023422Y-25166D03*
X1023407Y-21526D03*
X1029700Y3615D03*
X1023422Y4921D03*
X1023407Y2406D03*
X1023422Y-5108D03*
X1023407Y-7623D03*
Y-1468D03*
X1029700Y-6414D03*
X1023407Y22464D03*
Y18590D03*
Y8561D03*
X1023422Y14950D03*
X1023407Y12435D03*
X1029700Y13644D03*
Y23673D03*
X1023422Y24979D03*
X1038609Y49388D03*
X1027520Y122732D03*
X1037650Y128842D03*
X1023220Y187574D03*
X1031502Y267342D03*
X1028202D03*
X1025102D03*
X1033133Y272564D03*
X1031502Y270142D03*
X1029833Y272564D03*
X1026733D03*
X1023633D03*
X1028202Y270142D03*
X1025102D03*
X1029094Y383070D03*
Y387872D03*
X1033860Y400802D03*
X1038294Y506504D03*
X1027190Y510672D03*
X1029220Y520032D03*
X1043629Y375078D03*
Y372578D03*
X1049100Y390162D03*
X1046156Y442699D03*
X1058609Y49388D03*
X1066820Y151632D03*
X1072310Y364422D03*
X1078609Y49388D03*
X1075100Y55682D03*
X1084146Y67102D03*
X1078270Y93462D03*
X1077270Y369061D03*
Y374131D03*
Y379251D03*
X1073724Y476867D03*
X1081906Y472577D03*
X1076739Y506461D03*
X1077751Y522235D03*
X1098609Y49388D03*
X1097794Y67881D03*
X1102480Y133722D03*
X1105553Y356475D03*
X1096477Y744385D03*
X1102930Y1668690D03*
X1092072Y1734244D03*
X1118609Y49388D03*
X1118110Y1398010D03*
X1109118Y1526046D03*
X1116338Y1711380D03*
X1113055Y1718338D03*
X1132856Y52926D03*
X1129948Y66786D03*
X1127788Y1397126D03*
X1131629Y1420615D03*
X1129029D03*
X1134229D03*
X1123674Y1414936D03*
X1121174D03*
X1123674Y1417536D03*
Y1420136D03*
X1121174Y1417536D03*
Y1420136D03*
X1131629Y1423722D03*
X1129029D03*
X1134229D03*
X1123674Y1422736D03*
X1121174D03*
X1131042Y1436061D03*
X1135942D03*
X1133512D03*
X1131042Y1430461D03*
X1135942D03*
X1133512D03*
X1134429Y1426829D03*
X1136004Y1447858D03*
X1126117Y1450504D03*
X1127008Y1550285D03*
X1133780Y1550301D03*
X1138609Y49388D03*
X1145603Y73679D03*
X1140465Y379592D03*
X1142302Y366532D03*
X1142790Y611122D03*
X1146118Y1397126D03*
X1150843Y1415126D03*
X1148243D03*
X1150843Y1417726D03*
X1148243D03*
X1150732Y1420326D03*
X1142629Y1420615D03*
X1145573Y1420631D03*
X1139429Y1420615D03*
X1136829D03*
X1145573Y1423738D03*
X1136829Y1423722D03*
X1145542Y1426861D03*
X1137029Y1426829D03*
X1145108Y1476732D03*
X1158609Y49388D03*
X1156790Y373231D03*
X1153467Y586462D03*
X1153490Y610322D03*
X1165931Y1397126D03*
X1154714Y1398295D03*
X1157786Y1398252D03*
X1167172Y1420615D03*
X1153913Y1420606D03*
Y1415406D03*
Y1418006D03*
X1159124D03*
Y1420606D03*
Y1415406D03*
X1161724D03*
Y1420606D03*
Y1418006D03*
X1156524Y1415406D03*
Y1420606D03*
Y1418006D03*
X1167172Y1423722D03*
X1153913Y1423206D03*
X1159124D03*
X1161724D03*
X1156524D03*
X1155964Y1440864D03*
X1164260Y1450423D03*
X1158954Y1450274D03*
X1168192Y1604130D03*
X1152950Y1616470D03*
X1165950Y1617729D03*
X1152930Y1633880D03*
X1174980Y585632D03*
X1174880Y592652D03*
X1173990Y602192D03*
X1183230Y739102D03*
X1184661Y1397126D03*
X1183716Y1420631D03*
X1180772Y1420615D03*
X1174972D03*
X1177572D03*
X1172372D03*
X1169772D03*
X1183716Y1423738D03*
X1174972Y1423722D03*
X1172372D03*
X1169772D03*
X1174085Y1436061D03*
Y1430461D03*
X1171655Y1436061D03*
X1169185D03*
X1171655Y1430461D03*
X1169185D03*
X1183685Y1426861D03*
X1175172Y1426829D03*
X1172572D03*
X1174147Y1447858D03*
X1179922Y1550285D03*
X1184501Y1606521D03*
X1185030Y1633010D03*
X1182470Y1618914D03*
X1172530Y1623020D03*
X1176900Y1627510D03*
X1198609Y49388D03*
X1188720Y56755D03*
X1191700Y56822D03*
X1185500Y101400D03*
X1190700Y99000D03*
X1197627Y132859D03*
X1196100Y188962D03*
X1193500D03*
X1192600Y217662D03*
X1193000Y204486D03*
X1195500D03*
X1195100Y217662D03*
X1194840Y240672D03*
X1199027Y588714D03*
X1189135Y1397529D03*
X1187736Y1420387D03*
X1188986Y1415287D03*
Y1417887D03*
X1186386Y1415287D03*
Y1417887D03*
X1191486Y1415287D03*
Y1417887D03*
X1190444Y1420384D03*
X1194750Y1424672D03*
X1197700Y1432672D03*
X1191930Y1424647D03*
X1198010Y1441902D03*
X1198880Y1457162D03*
X1197181Y1563587D03*
X1195994Y1580678D03*
Y1575686D03*
X1200950Y1580678D03*
Y1575686D03*
X1201294Y1599884D03*
X1195994Y1592590D03*
Y1587598D03*
X1200950Y1592590D03*
Y1587598D03*
X1201294Y1604876D03*
Y1611796D03*
Y1616788D03*
X1213026Y56742D03*
X1201800Y94600D03*
X1204800Y108900D03*
X1206900Y115900D03*
X1214573Y148909D03*
X1204420Y195362D03*
X1210084Y224362D03*
X1207220Y247148D03*
X1217720Y249862D03*
X1204880Y754032D03*
X1213010Y1575686D03*
X1208054D03*
X1213010Y1580678D03*
X1208054D03*
X1206250Y1599884D03*
X1213354D03*
X1213010Y1587598D03*
X1208054D03*
X1213010Y1592590D03*
X1208054D03*
X1206250Y1604876D03*
Y1611796D03*
Y1616788D03*
X1213354D03*
Y1604876D03*
Y1611796D03*
X1213980Y1676500D03*
X1218609Y49388D03*
X1228420Y58862D03*
X1230250Y89450D03*
X1223720Y217862D03*
Y205862D03*
X1232000Y244332D03*
Y248332D03*
X1225070Y1580678D03*
Y1575686D03*
X1220114D03*
Y1580678D03*
X1232174D03*
Y1575686D03*
X1218310Y1599884D03*
X1225414D03*
X1230370D03*
X1225070Y1592590D03*
X1220114D03*
X1225070Y1587598D03*
X1220114D03*
X1232174D03*
Y1592590D03*
X1218310Y1616788D03*
Y1604876D03*
Y1611796D03*
X1225414D03*
Y1604876D03*
X1230370Y1611796D03*
Y1604876D03*
X1225414Y1616788D03*
X1230370D03*
X1238609Y49388D03*
X1239907Y95008D03*
X1243808Y116832D03*
X1247333Y121999D03*
X1236520Y213462D03*
X1246444Y256098D03*
X1252040Y306480D03*
X1237130Y1575686D03*
Y1580678D03*
X1244234D03*
X1249190D03*
X1244234Y1575686D03*
X1249190D03*
X1242430Y1599884D03*
X1237474D03*
X1249534D03*
X1237130Y1587598D03*
Y1592590D03*
X1249190D03*
X1244234D03*
Y1587598D03*
X1249190D03*
X1242430Y1616788D03*
X1237474D03*
X1242430Y1611796D03*
Y1604876D03*
X1237474Y1611796D03*
Y1604876D03*
X1249534Y1611796D03*
Y1604876D03*
Y1616788D03*
X1258609Y49388D03*
X1262800Y101100D03*
X1264620Y92724D03*
X1252961Y111903D03*
X1267150Y305998D03*
X1256787Y749605D03*
X1261250Y1575686D03*
X1256294D03*
X1261250Y1580678D03*
X1256294D03*
X1254490Y1599884D03*
X1261594D03*
X1261250Y1587598D03*
X1256294D03*
X1261250Y1592590D03*
X1256294D03*
X1254490Y1611796D03*
Y1604876D03*
Y1616788D03*
X1261594D03*
Y1611796D03*
Y1604876D03*
X1278300Y81232D03*
X1280135Y1340002D03*
Y1337402D03*
Y1345202D03*
Y1342602D03*
X1280312Y1365689D03*
X1273310Y1580678D03*
Y1575592D03*
X1268354D03*
Y1580678D03*
X1280414Y1575686D03*
Y1580678D03*
X1266550Y1599884D03*
X1273654Y1599790D03*
X1278610D03*
X1273310Y1592590D03*
X1268354D03*
X1273310Y1587598D03*
X1268354D03*
X1280414D03*
Y1592590D03*
X1266550Y1616788D03*
Y1611796D03*
Y1604876D03*
X1273654Y1611796D03*
Y1604876D03*
X1278610Y1611796D03*
Y1604876D03*
X1273654Y1616788D03*
X1278610D03*
X1295278Y297056D03*
X1290322D03*
X1294937Y746965D03*
X1292904Y782048D03*
X1292614Y789910D03*
X1291205Y1345875D03*
X1286005Y1342768D03*
Y1345875D03*
X1296405Y1342768D03*
X1293805D03*
X1288605D03*
X1291205D03*
X1288605Y1345875D03*
X1293805D03*
X1291405Y1348982D03*
X1294005D03*
X1292916Y1352531D03*
X1290436D03*
X1287956D03*
X1292916Y1358131D03*
X1290436D03*
X1287956D03*
X1283280Y1372301D03*
X1293887Y1370043D03*
X1294477Y1372651D03*
X1285370Y1575686D03*
Y1580678D03*
X1297430D03*
X1292474D03*
Y1575686D03*
X1297430D03*
X1285714Y1599884D03*
X1290670D03*
X1297774D03*
X1285370Y1587598D03*
Y1592590D03*
X1297430D03*
X1292474D03*
X1297430Y1587598D03*
X1292474D03*
X1290670Y1616788D03*
X1285714D03*
Y1611796D03*
X1290670D03*
X1285714Y1604876D03*
X1290670D03*
X1297774Y1611796D03*
Y1604876D03*
Y1616788D03*
X1311960Y49672D03*
X1314450Y319841D03*
X1312845Y324764D03*
X1305909D03*
X1303017Y785837D03*
X1311952Y1321945D03*
X1307656Y1337104D03*
X1305056D03*
X1307656Y1334504D03*
Y1329304D03*
Y1331904D03*
X1305056Y1334504D03*
Y1329304D03*
Y1331904D03*
Y1339704D03*
X1312488Y1348353D03*
X1299605Y1342768D03*
X1302549Y1345891D03*
X1302520Y1348762D03*
X1315058Y1349488D03*
X1302549Y1342784D03*
X1309490Y1575686D03*
X1304534D03*
X1309490Y1580678D03*
X1304534D03*
X1302730Y1599884D03*
X1309834D03*
X1314790D03*
X1309490Y1587598D03*
X1304534D03*
X1309490Y1592590D03*
X1304534D03*
X1302730Y1611796D03*
Y1604876D03*
Y1616788D03*
X1309834D03*
Y1611796D03*
Y1604876D03*
X1314790Y1616788D03*
Y1611796D03*
Y1604876D03*
X1318609Y49388D03*
X1319125Y296540D03*
X1324081D03*
X1324636Y290920D03*
X1329592D03*
X1330248Y325670D03*
X1323312D03*
X1321386Y319841D03*
X1329977Y334384D03*
X1327601Y540049D03*
X1317970Y1322741D03*
Y1319634D03*
X1325770Y1322741D03*
X1323170D03*
X1331570Y1319634D03*
X1323170D03*
X1325770D03*
X1328370D03*
X1320570Y1322741D03*
Y1319634D03*
X1322444Y1329497D03*
X1324924D03*
X1319964D03*
X1322444Y1335097D03*
X1324924D03*
X1319964D03*
X1323370Y1325848D03*
X1325970D03*
X1324945Y1346877D03*
X1327196Y1349068D03*
X1321550Y1580678D03*
X1316594D03*
X1321550Y1575686D03*
X1316594D03*
X1328654D03*
Y1580678D03*
X1321894Y1599884D03*
X1326850D03*
X1321550Y1592590D03*
X1316594D03*
X1321550Y1587598D03*
X1316594D03*
X1328654D03*
Y1592590D03*
X1321894Y1611796D03*
Y1604876D03*
X1326850Y1611796D03*
Y1604876D03*
X1321894Y1616788D03*
X1326850D03*
X1332726Y-27681D03*
X1339019Y-26472D03*
X1332726Y-32055D03*
X1339019Y-37001D03*
X1332726Y-11497D03*
X1339019Y-16443D03*
X1332741Y-15137D03*
X1332726Y-17652D03*
Y-21526D03*
X1332741Y-25166D03*
X1332726Y2406D03*
X1332741Y4921D03*
X1339019Y3615D03*
X1332726Y-1468D03*
X1339019Y-6414D03*
X1332726Y-7623D03*
X1332741Y-5108D03*
X1332726Y18590D03*
Y22464D03*
X1339019Y13644D03*
X1332726Y12435D03*
X1332741Y14950D03*
X1332726Y8561D03*
X1332741Y24979D03*
X1339019Y23673D03*
X1338609Y49388D03*
X1346720Y82912D03*
X1343362Y283155D03*
X1335947Y290755D03*
X1340903D03*
X1343656Y330749D03*
X1343199Y324461D03*
X1336263D03*
X1336913Y334384D03*
X1335643Y540048D03*
X1336187Y755635D03*
X1339784Y1306506D03*
X1337184D03*
X1344080Y1305919D03*
X1343968Y1300579D03*
X1344080Y1308519D03*
X1334514Y1322757D03*
Y1319650D03*
X1337184Y1309106D03*
X1339784D03*
X1338534Y1319406D03*
X1339784Y1316906D03*
Y1314306D03*
Y1311706D03*
X1337184Y1314306D03*
Y1316906D03*
Y1311706D03*
X1334414Y1325853D03*
X1347015Y1335876D03*
X1343631Y1332568D03*
X1333610Y1575686D03*
Y1580678D03*
X1345670D03*
X1340714D03*
X1345670Y1575686D03*
X1340714D03*
X1338910Y1599884D03*
X1333954D03*
X1346014D03*
X1333610Y1587598D03*
Y1592590D03*
X1345670D03*
X1340714D03*
X1345670Y1587598D03*
X1340714D03*
X1338910Y1616788D03*
Y1611796D03*
Y1604876D03*
X1333954Y1616788D03*
Y1611796D03*
Y1604876D03*
X1346014Y1611796D03*
Y1604876D03*
Y1616788D03*
X1350550Y101632D03*
X1363846Y279848D03*
X1349362Y283155D03*
X1353902Y287540D03*
X1359902D03*
X1350592Y330749D03*
X1356968Y339611D03*
X1350032D03*
X1363539Y334043D03*
X1356603D03*
X1350098Y1306208D03*
X1352698D03*
X1355298D03*
X1360498D03*
X1363698D03*
X1357898D03*
X1352698Y1309315D03*
X1350098D03*
X1355498Y1312422D03*
X1358098D03*
X1355298Y1309315D03*
X1357898D03*
X1352092Y1316071D03*
Y1321671D03*
X1357052Y1316071D03*
X1354572D03*
X1357052Y1321671D03*
X1354572D03*
X1356983Y1334095D03*
X1359516Y1334058D03*
X1355357Y1396020D03*
X1357730Y1575686D03*
X1352774D03*
X1357730Y1580678D03*
X1352774D03*
X1350970Y1599884D03*
X1363030D03*
X1358074D03*
X1357730Y1587598D03*
X1352774D03*
X1357730Y1592590D03*
X1352774D03*
X1350970Y1611796D03*
Y1604876D03*
Y1616788D03*
X1363030D03*
Y1611796D03*
Y1604876D03*
X1358074Y1616788D03*
Y1611796D03*
Y1604876D03*
X1378550Y110692D03*
X1377742Y244372D03*
Y250372D03*
X1377626Y258914D03*
Y264914D03*
X1369846Y279848D03*
X1372381Y661428D03*
X1371931Y672978D03*
Y685278D03*
X1372243Y697108D03*
Y709108D03*
Y721108D03*
X1370662Y1305980D03*
X1371912Y1303480D03*
X1376208Y1305919D03*
Y1303319D03*
X1371912Y1300880D03*
X1376208Y1300719D03*
Y1295586D03*
X1371912Y1295747D03*
Y1298280D03*
X1376208Y1298119D03*
X1369312Y1303480D03*
X1366642Y1306224D03*
X1369312Y1300880D03*
Y1295747D03*
Y1298280D03*
X1376208Y1308519D03*
X1366542Y1312427D03*
X1366642Y1309331D03*
X1379271Y1335963D03*
X1375814Y1332653D03*
X1377060Y1411231D03*
X1371960Y1436172D03*
X1365040Y1431142D03*
X1369790Y1580678D03*
X1364834D03*
X1369790Y1575592D03*
X1364834D03*
X1376894Y1575686D03*
Y1580678D03*
X1375090Y1599790D03*
X1370134D03*
X1369790Y1592590D03*
X1364834D03*
X1369790Y1587598D03*
X1364834D03*
X1376894D03*
Y1592590D03*
X1375090Y1611796D03*
Y1604876D03*
Y1616788D03*
X1370134Y1611796D03*
Y1604876D03*
Y1616788D03*
X1383480Y88932D03*
X1383734Y243329D03*
Y237329D03*
X1388778Y250661D03*
X1388908Y260301D03*
X1386237Y265620D03*
Y275200D03*
X1385190Y501242D03*
X1390220Y497742D03*
X1381131Y656378D03*
Y668378D03*
X1395831Y666278D03*
X1386931Y660978D03*
X1381131Y680278D03*
X1396031Y680678D03*
X1386931Y675478D03*
X1387143Y690208D03*
X1380731Y692208D03*
X1395631Y695108D03*
X1380731Y704208D03*
X1387143Y704708D03*
X1380731Y716208D03*
X1395631Y709608D03*
X1387143Y719235D03*
X1395631Y724135D03*
X1382920Y733725D03*
X1391408Y738625D03*
X1382226Y1306208D03*
X1384826D03*
X1387426D03*
X1390026D03*
X1392626D03*
X1395826D03*
X1386700Y1321671D03*
X1389180D03*
X1382226Y1309315D03*
X1384826D03*
X1390226Y1312422D03*
X1387626D03*
X1390026Y1309315D03*
X1387426D03*
X1384220Y1316071D03*
Y1321671D03*
X1389180Y1316071D03*
X1386700D03*
X1390758Y1333473D03*
X1392076Y1335658D03*
X1388813Y1393160D03*
X1396115Y1405289D03*
Y1412789D03*
X1396615Y1420289D03*
X1384695Y1425047D03*
X1392475Y1576097D03*
X1381850Y1575686D03*
Y1580678D03*
X1396600Y1582500D03*
X1387150Y1599884D03*
X1382194D03*
X1381850Y1587598D03*
Y1592590D03*
X1396600Y1594000D03*
X1387150Y1616788D03*
X1382194D03*
X1387150Y1611796D03*
Y1604876D03*
X1382194Y1611796D03*
Y1604876D03*
X1404630Y220018D03*
X1412270Y230952D03*
X1405436Y238378D03*
X1400207Y238257D03*
X1398770Y1306224D03*
X1404040Y1303480D03*
X1408336Y1305919D03*
Y1303319D03*
X1404040Y1300880D03*
X1408336Y1300719D03*
Y1295586D03*
X1404040Y1295747D03*
Y1298280D03*
X1408336Y1298119D03*
X1401440Y1303480D03*
X1402790Y1305980D03*
X1401440Y1300880D03*
Y1295747D03*
Y1298280D03*
X1408336Y1308519D03*
X1398670Y1312427D03*
X1398770Y1309331D03*
X1411124Y1335924D03*
X1407719Y1332560D03*
X1403615Y1405289D03*
X1411115D03*
Y1412789D03*
X1403615Y1420289D03*
X1411115D03*
X1403350Y1516435D03*
X1403590Y1532255D03*
X1403350Y1521335D03*
X1403740Y1548375D03*
X1403590Y1537155D03*
X1403740Y1543475D03*
X1407200Y1591400D03*
X1411070Y1603282D03*
X1400000Y1630362D03*
Y1642362D03*
X1413350Y220018D03*
X1416020D03*
X1424690D03*
X1424520Y225002D03*
X1416810Y225422D03*
X1428640Y230022D03*
X1431430Y251265D03*
X1428940Y269292D03*
X1414354Y1306208D03*
X1416954D03*
X1419554D03*
X1422154D03*
X1424754D03*
X1427954D03*
X1418828Y1316071D03*
X1416348D03*
X1418828Y1321671D03*
X1416348D03*
X1421308Y1316071D03*
Y1321671D03*
X1414354Y1309315D03*
X1416954D03*
X1419554D03*
X1422354Y1312422D03*
X1419754D03*
X1422154Y1309315D03*
X1421294Y1334095D03*
X1423656Y1335468D03*
X1429345Y1433695D03*
X1427349Y1442776D03*
X1414264Y1439494D03*
X1419256Y1440258D03*
X1423829Y1442776D03*
X1416800Y1564862D03*
X1428403Y1581378D03*
X1418241Y1583441D03*
X1422145Y1575362D03*
X1426680Y1603262D03*
X1425770Y1633772D03*
X1413230Y1641042D03*
X1438609Y49388D03*
X1441125Y57362D03*
X1438680Y64412D03*
X1441490Y224062D03*
X1438720Y220018D03*
X1430130Y259342D03*
X1437177Y720965D03*
X1437182Y1298991D03*
X1430898Y1306224D03*
X1434582Y1304191D03*
Y1306791D03*
Y1301591D03*
Y1296458D03*
Y1298991D03*
X1440507Y1305430D03*
Y1302830D03*
Y1300230D03*
X1440536Y1296455D03*
X1440464Y1308519D03*
X1437182Y1304191D03*
Y1306791D03*
Y1301591D03*
Y1296458D03*
X1430798Y1312427D03*
X1430898Y1309331D03*
X1443785Y1335981D03*
X1440879Y1333085D03*
X1439155Y1399064D03*
X1431717Y1420625D03*
Y1417125D03*
Y1409125D03*
Y1427632D03*
X1436330Y1521152D03*
X1436570Y1536972D03*
X1436720Y1548192D03*
X1437140Y1576012D03*
X1438300Y1598400D03*
X1430250Y1608442D03*
X1438300Y1611000D03*
X1438273Y1671103D03*
X1458609Y49388D03*
X1458720Y153362D03*
Y149362D03*
Y169862D03*
Y165862D03*
Y161862D03*
Y157862D03*
Y181862D03*
Y177862D03*
Y173862D03*
X1446830Y236232D03*
X1453670Y278170D03*
X1459312Y341130D03*
X1460600Y352742D03*
X1456700Y369642D03*
X1454889Y658712D03*
X1454439Y670262D03*
Y682562D03*
X1454751Y694392D03*
Y706392D03*
X1454439Y718362D03*
X1459057Y733545D03*
X1457597Y739035D03*
X1446482Y1306208D03*
X1449082D03*
X1451682D03*
X1456882D03*
X1460082D03*
X1454282D03*
X1450956Y1321671D03*
X1448476D03*
X1453436Y1316071D03*
Y1321671D03*
X1446482Y1309315D03*
X1451882Y1312422D03*
X1449082Y1309315D03*
X1451682D03*
X1454482Y1312422D03*
X1454282Y1309315D03*
X1450956Y1316071D03*
X1448476D03*
X1453303Y1334095D03*
X1455436Y1335598D03*
X1461377Y1417844D03*
X1459135Y1439627D03*
X1459136Y1442241D03*
X1461517Y1575686D03*
Y1580678D03*
X1446600Y1595400D03*
X1461517Y1587598D03*
Y1592590D03*
X1460441Y1602441D03*
X1446786Y1610639D03*
X1452757Y1671399D03*
X1446380Y1676291D03*
X1464200Y67802D03*
X1470220Y145362D03*
X1470101Y207751D03*
X1476858Y225448D03*
X1466940Y230272D03*
X1466958Y244948D03*
X1468620Y258857D03*
X1467230Y252472D03*
X1466660Y273878D03*
X1475790Y404842D03*
X1473310Y418502D03*
X1463639Y653662D03*
X1469651Y655992D03*
X1462010Y645842D03*
X1463639Y665662D03*
X1478139Y660892D03*
X1469439Y670262D03*
X1463639Y677562D03*
X1463239Y689492D03*
X1478139Y689892D03*
X1469651Y684992D03*
X1463239Y701492D03*
X1478139Y704392D03*
X1469477Y699475D03*
X1463239Y713492D03*
X1478139Y718892D03*
X1469651Y713992D03*
X1474100Y735662D03*
X1466451Y726992D03*
X1474939Y731892D03*
X1472592Y1306345D03*
X1463026Y1306224D03*
X1465696Y1303480D03*
X1467046Y1305980D03*
X1468296Y1303480D03*
X1465696Y1300880D03*
X1468296D03*
X1472361Y1322440D03*
X1472592Y1308945D03*
Y1316745D03*
Y1314145D03*
Y1311545D03*
X1462926Y1312427D03*
X1463026Y1309331D03*
X1475599Y1349468D03*
X1475959Y1385027D03*
X1476000Y1393027D03*
X1465747Y1401405D03*
X1466448Y1421499D03*
X1475935Y1439627D03*
X1475936Y1442241D03*
X1467550Y1439642D03*
X1467536Y1442241D03*
X1473577Y1580678D03*
Y1575686D03*
X1466473D03*
Y1580678D03*
X1471773Y1599884D03*
X1466817D03*
X1473577Y1592590D03*
Y1587598D03*
X1466473D03*
Y1592590D03*
X1466817Y1611796D03*
X1471773D03*
X1466817Y1604876D03*
X1471773D03*
Y1616788D03*
X1466817D03*
X1478609Y49388D03*
X1481360Y358792D03*
X1488500Y410152D03*
X1478539Y675462D03*
X1486410Y1322741D03*
X1483810D03*
X1486410Y1319634D03*
X1483810D03*
X1481210Y1322741D03*
Y1319634D03*
X1492210D03*
X1489010D03*
X1478610Y1322741D03*
Y1319634D03*
X1484010Y1325848D03*
X1486610D03*
X1485564Y1335097D03*
X1483084D03*
X1485564Y1329497D03*
X1483084D03*
X1480604Y1335097D03*
Y1329497D03*
X1485523Y1347521D03*
X1487386Y1349258D03*
X1478559Y1385027D03*
X1481159Y1384727D03*
X1478600Y1393027D03*
X1481107Y1393095D03*
X1484395Y1439598D03*
X1484336Y1442241D03*
X1490593Y1580678D03*
Y1575686D03*
X1485637D03*
Y1580678D03*
X1478533D03*
Y1575686D03*
X1490937Y1599884D03*
X1478877D03*
X1483833D03*
X1490593Y1587598D03*
X1485637D03*
Y1592590D03*
X1490593D03*
X1478533D03*
Y1587598D03*
X1490937Y1604876D03*
Y1611796D03*
Y1616788D03*
X1483833D03*
X1478877D03*
Y1611796D03*
X1483833D03*
X1478877Y1604876D03*
X1483833D03*
X1498609Y49388D03*
X1496200Y359522D03*
X1497880Y373062D03*
X1503450Y382693D03*
X1497770Y732502D03*
X1495154Y1322757D03*
Y1319650D03*
X1499048Y1319946D03*
X1504720Y1329143D03*
X1495054Y1325853D03*
X1503786Y1326076D03*
X1504518Y1335982D03*
X1504720Y1342143D03*
Y1344743D03*
X1505116Y1369724D03*
X1509757Y1575686D03*
Y1580678D03*
X1502653D03*
X1497697D03*
X1502653Y1575686D03*
X1497697D03*
X1502997Y1599884D03*
X1507953D03*
X1495893D03*
X1509757Y1587598D03*
Y1592590D03*
X1502653D03*
X1497697D03*
X1502653Y1587598D03*
X1497697D03*
X1502997Y1616788D03*
X1507953D03*
X1502997Y1604876D03*
Y1611796D03*
X1507953Y1604876D03*
Y1611796D03*
X1495893Y1604876D03*
Y1611796D03*
Y1616788D03*
X1518608Y49377D03*
X1522920Y113030D03*
X1526675Y140117D03*
X1526083Y146225D03*
X1513759Y263676D03*
X1516683Y278437D03*
X1511624Y291175D03*
X1519336Y303426D03*
X1520094Y306543D03*
X1514369Y308467D03*
X1524505Y748912D03*
X1522066Y1312808D03*
X1526066D03*
X1518066D03*
X1515066D03*
X1511066D03*
X1510738Y1345539D03*
Y1342432D03*
X1518538Y1345539D03*
Y1342432D03*
X1515938Y1345539D03*
Y1342432D03*
X1513338Y1345539D03*
Y1342432D03*
X1521138D03*
X1524338D03*
X1518738Y1348646D03*
X1516138D03*
X1515212Y1352295D03*
X1512732D03*
X1517692D03*
X1515212Y1357895D03*
X1512732D03*
X1517692D03*
X1518451Y1369919D03*
X1521817Y1580678D03*
Y1575686D03*
X1514713D03*
Y1580678D03*
X1520013Y1599884D03*
X1515057D03*
X1521817Y1592590D03*
Y1587598D03*
X1514713D03*
Y1592590D03*
X1520013Y1604876D03*
X1515057D03*
X1520013Y1611796D03*
X1515057D03*
Y1616788D03*
X1520013D03*
X1534818Y66801D03*
Y71793D03*
X1539774Y66801D03*
Y71793D03*
X1541774Y69297D03*
X1532818D03*
X1534774Y103093D03*
X1529818D03*
X1535320Y113062D03*
X1529500Y129602D03*
X1545447Y156035D03*
X1537262Y197834D03*
X1540989Y616587D03*
X1535052Y1325904D03*
X1532552Y1334504D03*
X1535052D03*
X1529952D03*
X1532552Y1339704D03*
X1529952D03*
X1537652Y1325904D03*
Y1334504D03*
X1532552Y1337104D03*
X1529952D03*
X1538510Y1346392D03*
X1531302Y1342204D03*
X1535892Y1346354D03*
Y1343754D03*
X1527282Y1345555D03*
Y1342448D03*
X1538757Y1356355D03*
X1527182Y1348651D03*
X1538757Y1360855D03*
Y1365355D03*
X1533877Y1575592D03*
X1538833D03*
X1533877Y1580678D03*
X1538833D03*
X1526773D03*
Y1575686D03*
X1539177Y1599790D03*
X1527117Y1599884D03*
X1532073D03*
X1533877Y1587598D03*
X1538833D03*
X1533877Y1592590D03*
X1538833D03*
X1526773D03*
Y1587598D03*
X1539177Y1611796D03*
Y1604876D03*
Y1616788D03*
X1527117D03*
Y1604876D03*
Y1611796D03*
X1532073Y1616788D03*
Y1604876D03*
Y1611796D03*
X1547768Y3010D03*
X1555635Y16999D03*
Y21991D03*
X1553635Y19495D03*
X1553486Y23935D03*
X1548530D03*
X1546530Y25931D03*
X1555486D03*
X1547429Y37106D03*
X1554515D03*
Y48720D03*
X1547429D03*
X1554818Y69297D03*
X1556818Y66801D03*
Y71793D03*
X1543818Y75297D03*
X1552774D03*
X1550774Y77793D03*
Y72801D03*
X1545818Y77793D03*
Y72801D03*
X1554239Y138263D03*
X1554723Y200375D03*
X1557560Y196912D03*
X1554723Y224529D03*
Y248945D03*
X1554727Y631527D03*
X1550417Y677045D03*
X1550057Y693485D03*
X1548479Y706088D03*
X1557997Y1575686D03*
Y1580678D03*
X1550893D03*
X1545937D03*
X1550893Y1575686D03*
X1545937D03*
X1556193Y1599884D03*
X1551237D03*
X1544133Y1599790D03*
X1557997Y1587598D03*
Y1592590D03*
X1545937D03*
X1550893D03*
Y1587598D03*
X1545937D03*
X1551237Y1616788D03*
X1556193D03*
Y1604876D03*
X1551237D03*
X1556193Y1611796D03*
X1551237D03*
X1544133Y1604876D03*
Y1611796D03*
Y1616788D03*
X1567768Y3010D03*
X1560591Y16999D03*
Y21991D03*
X1569808Y16999D03*
Y21991D03*
X1574764Y16999D03*
Y21991D03*
X1562591Y19495D03*
X1567808D03*
X1567659Y23935D03*
X1562703D03*
X1560703Y25931D03*
X1569659D03*
X1574876D03*
X1561602Y37106D03*
X1568688D03*
Y48720D03*
X1561602D03*
X1563774Y69297D03*
X1561774Y66801D03*
Y71793D03*
X1565818Y75297D03*
X1574774D03*
X1572774Y77793D03*
Y72801D03*
X1567818Y77793D03*
Y72801D03*
X1559860Y240002D03*
X1575169Y303929D03*
X1560717Y648522D03*
X1570720Y729362D03*
X1570057Y1580678D03*
X1575013D03*
X1570057Y1575686D03*
X1575013D03*
X1562953D03*
Y1580678D03*
X1575357Y1599884D03*
X1563297D03*
X1568253D03*
X1570057Y1592590D03*
X1575013D03*
X1570057Y1587598D03*
X1575013D03*
X1562953D03*
Y1592590D03*
X1575357Y1616788D03*
Y1604876D03*
Y1611796D03*
X1563297Y1604876D03*
Y1611796D03*
X1568253Y1604876D03*
Y1611796D03*
X1563297Y1616788D03*
X1568253D03*
X1587768Y3010D03*
X1583981Y16999D03*
Y21991D03*
X1588937Y16999D03*
Y21991D03*
X1576764Y19495D03*
X1581981D03*
X1590937D03*
X1576876Y23935D03*
X1581832D03*
X1591050D03*
X1583832Y25931D03*
X1589050D03*
X1575775Y37106D03*
X1582862D03*
X1589948D03*
Y48720D03*
X1582862D03*
X1575775D03*
X1576818Y69297D03*
X1585774D03*
X1578818Y66801D03*
Y71793D03*
X1583774Y66801D03*
Y71793D03*
X1587818Y75297D03*
X1589818Y77793D03*
Y72801D03*
X1582117Y1575686D03*
X1587073D03*
X1582117Y1580678D03*
X1587073D03*
X1587417Y1599884D03*
X1580313D03*
X1582117Y1587598D03*
X1587073D03*
X1582117Y1592590D03*
X1587073D03*
X1587417Y1604876D03*
Y1611796D03*
Y1616788D03*
X1580313D03*
Y1604876D03*
Y1611796D03*
X1607768Y3010D03*
X1598155Y16999D03*
Y21991D03*
X1603111Y16999D03*
Y21991D03*
X1596155Y19495D03*
X1605111D03*
X1596006Y23935D03*
X1598006Y25931D03*
X1597035Y37106D03*
X1604122D03*
Y48720D03*
X1597035D03*
X1598818Y69297D03*
X1607774D03*
X1600818Y66801D03*
Y71793D03*
X1605774Y66801D03*
Y71793D03*
X1596774Y75297D03*
X1594774Y77793D03*
Y72801D03*
X1603778Y189943D03*
X1603726Y198061D03*
X1596444Y215526D03*
X1598030Y251002D03*
X1606980Y1449922D03*
X1606237Y1575686D03*
Y1580678D03*
X1594177D03*
X1599133D03*
X1594177Y1575686D03*
X1599133D03*
X1599477Y1599884D03*
X1604433D03*
X1592373D03*
X1606237Y1587598D03*
Y1592590D03*
X1594177D03*
X1599133D03*
X1594177Y1587598D03*
X1599133D03*
X1599477Y1616788D03*
X1604433D03*
X1599477Y1604876D03*
Y1611796D03*
X1604433Y1604876D03*
Y1611796D03*
X1592373Y1604876D03*
Y1611796D03*
Y1616788D03*
X1620818Y69297D03*
X1622818Y66801D03*
Y71793D03*
X1609818Y75297D03*
X1618774D03*
X1616774Y77793D03*
Y72801D03*
X1611818Y77793D03*
Y72801D03*
X1623448Y1420028D03*
Y1417428D03*
Y1414828D03*
Y1412228D03*
X1612630Y1418842D03*
X1615597Y1433669D03*
X1618297Y1580678D03*
X1623253D03*
X1618297Y1575686D03*
X1623253D03*
X1611193D03*
Y1580678D03*
X1623597Y1599884D03*
X1611537D03*
X1616493D03*
X1618297Y1592590D03*
X1623253D03*
X1618297Y1587598D03*
X1623253D03*
X1611193D03*
Y1592590D03*
X1623597Y1616788D03*
Y1604876D03*
Y1611796D03*
X1611537Y1604876D03*
Y1611796D03*
X1616493Y1604876D03*
Y1611796D03*
X1611537Y1616788D03*
X1616493D03*
X1634021Y16999D03*
Y21991D03*
X1638977Y16999D03*
Y21991D03*
X1632021Y19495D03*
X1631872Y23935D03*
X1626916D03*
X1624916Y25931D03*
X1633872D03*
X1639089D03*
X1625814Y37106D03*
X1632901D03*
X1639988D03*
X1625814Y48720D03*
X1632901D03*
X1639988D03*
X1629774Y69297D03*
X1627774Y66801D03*
Y71793D03*
X1633022Y75297D03*
X1635022Y77793D03*
X1639978D03*
Y72801D03*
X1635022D03*
X1635032Y196188D03*
X1642135Y414202D03*
X1629262Y1394418D03*
X1625948Y1417428D03*
Y1412228D03*
X1633103Y1417907D03*
X1630503D03*
X1635703D03*
X1633103Y1421014D03*
X1630503D03*
X1635703D03*
X1638303Y1417907D03*
Y1421014D03*
X1625948Y1414828D03*
Y1420028D03*
X1635903Y1424121D03*
X1638503D03*
X1632516Y1427753D03*
Y1433353D03*
X1634986Y1427753D03*
Y1433353D03*
X1637416Y1427753D03*
Y1433353D03*
X1627591Y1447796D03*
X1637478Y1445150D03*
X1630357Y1575592D03*
X1635313D03*
X1630357Y1580678D03*
X1635313D03*
X1640613Y1599790D03*
X1635657D03*
X1628553Y1599884D03*
X1630357Y1587598D03*
X1635313D03*
X1630357Y1592590D03*
X1635313D03*
X1640613Y1604876D03*
Y1611796D03*
X1635657Y1604876D03*
Y1611796D03*
X1640613Y1616788D03*
X1635657D03*
X1628553D03*
Y1604876D03*
Y1611796D03*
X1648194Y16999D03*
Y21991D03*
X1653150Y16999D03*
Y21991D03*
X1640977Y19495D03*
X1646194D03*
X1655150D03*
X1641089Y23935D03*
X1646045D03*
X1648045Y25931D03*
X1654161Y37106D03*
X1647074D03*
Y48720D03*
X1654161D03*
X1644022Y69297D03*
X1652978D03*
X1646022Y66801D03*
Y71793D03*
X1650978Y66801D03*
Y71793D03*
X1655022Y75297D03*
X1641978D03*
X1657022Y77793D03*
Y72801D03*
X1652610Y394727D03*
X1652810Y407402D03*
X1647110Y434177D03*
X1651890Y520540D03*
X1649220Y620662D03*
X1656188Y1394736D03*
X1647592Y1394418D03*
X1655779Y1417618D03*
Y1412418D03*
Y1415018D03*
X1644103Y1417907D03*
X1647047Y1417923D03*
Y1421030D03*
X1653279Y1412418D03*
X1650679D03*
X1653279Y1415018D03*
X1650679D03*
X1653168Y1417618D03*
X1650557D03*
X1640903Y1417907D03*
X1647016Y1424153D03*
X1648947Y1476695D03*
X1647373Y1580678D03*
X1642417D03*
X1647373Y1575686D03*
X1642417D03*
X1647717Y1599884D03*
X1652673D03*
X1647373Y1592590D03*
X1642417D03*
X1647373Y1587598D03*
X1642417D03*
X1647717Y1616788D03*
X1652673D03*
X1647717Y1604876D03*
Y1611796D03*
X1652673Y1604876D03*
Y1611796D03*
X1671050Y23935D03*
X1669050Y25931D03*
X1669948Y37106D03*
Y48720D03*
X1666022Y69297D03*
X1668022Y66801D03*
Y71793D03*
X1672978Y66801D03*
Y71793D03*
X1663978Y75297D03*
X1661978Y77793D03*
Y72801D03*
X1668030Y200580D03*
X1666074Y229710D03*
X1660176Y231100D03*
X1670400Y229462D03*
X1659610Y394727D03*
X1663610D03*
X1661110Y434177D03*
X1660866Y546749D03*
X1664040Y569642D03*
X1668040D03*
X1672040D03*
X1662120Y604782D03*
X1657220Y620662D03*
X1667405Y1394418D03*
X1659260Y1394693D03*
X1658390Y1420218D03*
Y1415018D03*
Y1412418D03*
Y1417618D03*
X1663590Y1420218D03*
X1660990D03*
Y1415018D03*
Y1417618D03*
Y1412418D03*
X1663590Y1415018D03*
Y1417618D03*
Y1412418D03*
X1668646Y1417907D03*
Y1421014D03*
X1671246Y1417907D03*
Y1421014D03*
X1670659Y1427753D03*
X1673129D03*
X1670659Y1433353D03*
X1673129D03*
X1657438Y1438156D03*
X1660428Y1447566D03*
X1667577Y1447545D03*
X1666123Y1497362D03*
X1665940Y1512862D03*
X1666110Y1504662D03*
X1666123Y1524862D03*
Y1537862D03*
Y1541862D03*
Y1553557D03*
X1666198Y1565557D03*
Y1585321D03*
X1678155Y16999D03*
Y21991D03*
X1683111Y16999D03*
Y21991D03*
X1676155Y19495D03*
X1685111D03*
X1676006Y23935D03*
X1685223D03*
X1678006Y25931D03*
X1683223D03*
X1677035Y37106D03*
X1684122D03*
X1677035Y48720D03*
X1684122D03*
X1688156Y69297D03*
X1674978D03*
X1677156Y75297D03*
X1686112D03*
X1684112Y77793D03*
Y72801D03*
X1679156Y77793D03*
Y72801D03*
X1676300Y219762D03*
X1681900Y227962D03*
X1682810Y465940D03*
X1676040Y569627D03*
X1688301Y722158D03*
X1683121D03*
X1680401D03*
X1686135Y1394418D03*
X1687860Y1415179D03*
X1689210Y1417679D03*
X1687860Y1412579D03*
X1685190Y1417923D03*
X1676446Y1417907D03*
X1679046D03*
X1682246D03*
X1676446Y1421014D03*
X1685190Y1421030D03*
X1673846Y1417907D03*
Y1421014D03*
X1676646Y1424121D03*
X1685159Y1424153D03*
X1675559Y1427753D03*
Y1433353D03*
X1674046Y1424121D03*
X1675621Y1445150D03*
X1679508Y1503421D03*
Y1522921D03*
Y1543921D03*
Y1563380D03*
Y1583880D03*
X1692328Y16999D03*
Y21991D03*
X1697284Y16999D03*
Y21991D03*
X1690328Y19495D03*
X1699284D03*
X1690179Y23935D03*
X1692179Y25931D03*
X1691208Y37106D03*
X1698295D03*
X1705381D03*
X1698295Y48720D03*
X1691208D03*
X1705381D03*
X1697112Y69297D03*
X1690156Y66801D03*
Y71793D03*
X1695112Y66801D03*
Y71793D03*
X1699156Y75297D03*
X1701156Y77793D03*
Y72801D03*
X1695950Y96437D03*
X1697725Y205120D03*
X1700846Y455894D03*
X1702760Y478207D03*
X1696760D03*
X1702760Y490207D03*
X1696760D03*
Y484207D03*
X1696120Y506937D03*
X1703720Y509362D03*
X1696851Y515607D03*
X1693701D03*
X1702270Y552742D03*
X1698920Y698562D03*
X1695227Y722325D03*
X1699307Y722465D03*
X1698137Y718345D03*
X1701087Y719055D03*
X1695367Y719345D03*
X1691021Y722158D03*
X1698537Y766015D03*
X1690809Y1393970D03*
X1699150Y1393613D03*
X1690460Y1415179D03*
Y1412579D03*
X1691918Y1417676D03*
X1692960Y1415179D03*
Y1412579D03*
X1693404Y1421939D03*
X1699593Y1428384D03*
X1697820Y1423616D03*
X1699545Y1425868D03*
X1699437Y1431295D03*
X1699457Y1439185D03*
Y1447805D03*
X1691988Y1498303D03*
Y1517803D03*
Y1538803D03*
Y1558262D03*
X1714520Y37162D03*
X1710920Y82162D03*
X1708112Y75297D03*
X1706112Y77793D03*
Y72801D03*
X1708000Y99122D03*
X1714180Y154790D03*
X1721400Y374462D03*
X1711477Y465229D03*
Y468379D03*
X1708760Y478031D03*
Y490207D03*
Y484207D03*
X1710500Y538162D03*
X1706720Y703762D03*
X1709107Y728449D03*
X1718149Y1496270D03*
X1717149Y1505895D03*
X1720174D03*
X1717988Y1520951D03*
X1711988D03*
X1717149Y1513945D03*
X1720174D03*
X1714988Y1520951D03*
X1708988D03*
X1717988Y1530445D03*
X1714988D03*
X1708988D03*
X1711988D03*
X1727768Y3010D03*
X1732320Y28162D03*
X1728820D03*
X1725320D03*
X1729520Y61762D03*
X1729620Y57262D03*
X1730820Y76362D03*
X1726918Y101967D03*
X1733378Y134907D03*
X1736508D03*
X1723240Y185200D03*
X1737704Y183139D03*
X1737260Y368132D03*
X1732660Y372692D03*
X1725400Y372062D03*
X1725500Y383662D03*
X1737434Y398990D03*
X1727760Y420415D03*
X1747768Y3010D03*
X1754090Y16302D03*
X1748400Y37262D03*
X1753398Y48720D03*
X1745485Y119539D03*
X1747482Y121367D03*
X1741222Y151527D03*
X1747591Y171733D03*
X1751084Y190928D03*
X1745000Y299862D03*
X1746970Y1451872D03*
X1750970Y1459172D03*
Y1456172D03*
X1767768Y3010D03*
X1769900Y37732D03*
X1760485Y48720D03*
X1759700Y57662D03*
X1764400Y57462D03*
X1758063Y68637D03*
X1758573Y87107D03*
Y83607D03*
X1768168Y80497D03*
X1758568Y79697D03*
X1765068Y80397D03*
X1766278Y93627D03*
X1768483Y166260D03*
X1763731Y283817D03*
X1766725Y282981D03*
X1763731Y279517D03*
X1760398Y279548D03*
X1766765Y279433D03*
X1757439Y279611D03*
X1760398Y283848D03*
X1759509Y292434D03*
X1762549Y286704D03*
X1757439Y283911D03*
X1768045Y295238D03*
X1765053Y295188D03*
X1762285Y295137D03*
X1759629Y295164D03*
X1767309Y290994D03*
X1763045Y289691D03*
X1759529Y289864D03*
X1766655Y286531D03*
X1767455Y302651D03*
X1758563Y310478D03*
X1754963D03*
X1770520Y364148D03*
Y368148D03*
X1767300Y461393D03*
X1765670Y458012D03*
X1767300Y465893D03*
X1764112Y703948D03*
X1761612D03*
X1764112Y695648D03*
X1763570Y693192D03*
X1761612Y695648D03*
X1764072Y720508D03*
X1761572D03*
X1764112Y712248D03*
X1761612D03*
X1760160Y1476032D03*
X1763730Y1483712D03*
Y1480712D03*
X1763830Y1490782D03*
Y1487782D03*
X1785178Y86927D03*
Y89927D03*
X1784238Y150744D03*
X1786690Y234782D03*
Y231782D03*
X1771029Y295164D03*
X1771229Y291064D03*
X1772863Y310478D03*
X1782420Y443987D03*
X1773870Y438222D03*
X1776160Y592792D03*
X1787768Y3010D03*
X1794910Y44573D03*
X1797324Y161465D03*
X1803129Y362293D03*
X1802929Y385293D03*
X1795479Y408056D03*
X1795468Y421334D03*
X1800107Y1256426D03*
X1795484Y1496401D03*
X1792645Y1511423D03*
X1798450Y1524830D03*
X1801450D03*
Y1527830D03*
X1814322Y49388D03*
X1807549Y56415D03*
X1807580Y59397D03*
X1810835Y163986D03*
X1806365Y154032D03*
X1819939Y177243D03*
X1820307Y373829D03*
X1820144Y398052D03*
X1819374Y410432D03*
X1818874Y423932D03*
X1818816Y468872D03*
X1803517Y1495567D03*
X1818410Y1525815D03*
X1812250Y1521830D03*
X1811250Y1524830D03*
Y1527830D03*
X1807850D03*
X1804650D03*
Y1524830D03*
X1807850D03*
X1814370Y1528900D03*
X1814210Y1525815D03*
X1818524Y1528991D03*
X1834322Y49388D03*
X1823508Y158868D03*
X1829026Y367701D03*
X1823426Y1507916D03*
X1831994Y1525977D03*
X1835334Y1520921D03*
X1828510Y1525915D03*
X1821710D03*
X1830466Y1606658D03*
X1838910Y185772D03*
X1843134Y244362D03*
X1836750Y373632D03*
X1838020Y459121D03*
X1854096Y52383D03*
G54D42*
X335349Y985939D03*
X549278Y949619D03*
X1300207Y177799D03*
X1311491Y985939D03*
X1355761Y177798D03*
X1525420Y949619D03*
X1879155Y592848D03*
Y840748D03*
X1889155Y592848D03*
Y840748D03*
X1900275Y964708D03*
X1910275D03*
X1931395Y592868D03*
X1921395D03*
X1952395Y1205248D03*
X1942395D03*
X1963362Y593010D03*
X1973362D03*
X1984482Y1205220D03*
X1994482D03*
X2015452Y593020D03*
X2005452D03*
X2026452Y1205400D03*
X2047419Y593162D03*
X2036452Y1205400D03*
X2057419Y593162D03*
X2078539Y1205372D03*
X2068539D03*
G54D56*
X828780Y1694890D03*
Y1684890D03*
X818780Y1694890D03*
Y1684890D03*
X828780Y1704890D03*
X818780D03*
X828780Y1714890D03*
X818780D03*
X853780Y1694890D03*
Y1684890D03*
Y1704890D03*
Y1714890D03*
X863780Y1694890D03*
Y1684890D03*
Y1704890D03*
Y1714890D03*
X888780Y1684890D03*
Y1694890D03*
Y1704890D03*
Y1714890D03*
X898780Y1684890D03*
Y1694890D03*
Y1704890D03*
Y1714890D03*
X918780Y1704890D03*
X958780Y1694890D03*
Y1684890D03*
Y1704890D03*
Y1714890D03*
X968780Y1694890D03*
Y1684890D03*
Y1704890D03*
Y1714890D03*
X993780Y1684890D03*
Y1694890D03*
X1003780Y1684890D03*
Y1694890D03*
X993780Y1704890D03*
Y1714890D03*
X1003780Y1704890D03*
Y1714890D03*
X1028780Y1684890D03*
Y1694890D03*
X1038780Y1684890D03*
Y1694890D03*
X1028780Y1704890D03*
Y1714890D03*
X1038780Y1704890D03*
Y1714890D03*
G54D16*
X27699Y770144D03*
Y783530D03*
Y776837D03*
Y800263D03*
Y793570D03*
Y820341D03*
Y813648D03*
Y806955D03*
Y830381D03*
Y850459D03*
Y843766D03*
Y837074D03*
Y867192D03*
Y857152D03*
Y880577D03*
Y873885D03*
Y893963D03*
Y887270D03*
Y917389D03*
Y910696D03*
Y904003D03*
Y930774D03*
Y924081D03*
Y947507D03*
Y940814D03*
Y964239D03*
Y954200D03*
Y977625D03*
Y970932D03*
Y991011D03*
Y984318D03*
Y1031168D03*
Y1024475D03*
Y1017782D03*
Y1044554D03*
Y1037861D03*
Y1057940D03*
Y1051247D03*
Y1078018D03*
Y1071326D03*
Y1064633D03*
Y1094751D03*
Y1088058D03*
Y1108137D03*
Y1101444D03*
Y1124869D03*
Y1114829D03*
Y1144948D03*
Y1138255D03*
Y1131562D03*
Y1161680D03*
Y1151641D03*
Y1175066D03*
Y1168373D03*
Y1188452D03*
Y1181759D03*
Y1205184D03*
Y1198491D03*
Y1225263D03*
Y1218570D03*
Y1211877D03*
Y1241995D03*
Y1235302D03*
Y1248688D03*
X43841Y766798D03*
X36399Y770144D03*
X43841Y780184D03*
Y773491D03*
X36399Y783530D03*
Y776837D03*
X43841Y803609D03*
Y796916D03*
Y790223D03*
X36399Y800263D03*
Y793570D03*
X43841Y816995D03*
Y810302D03*
X36399Y820341D03*
Y813648D03*
Y806955D03*
X43841Y833727D03*
Y827034D03*
X36399Y830381D03*
X43841Y847113D03*
Y840420D03*
X36399Y850459D03*
Y843766D03*
Y837074D03*
X43841Y863845D03*
Y853806D03*
X36399Y867192D03*
Y857152D03*
X43841Y883924D03*
Y877231D03*
Y870538D03*
X36399Y880577D03*
Y873885D03*
X43841Y900656D03*
Y890617D03*
X36399Y893963D03*
Y887270D03*
X43841Y914042D03*
Y907349D03*
X36399Y917389D03*
Y910696D03*
Y904003D03*
X43841Y927428D03*
Y920735D03*
X36399Y930774D03*
Y924081D03*
X43841Y944160D03*
Y937467D03*
X36399Y947507D03*
Y940814D03*
X43841Y960892D03*
Y950853D03*
X36399Y964239D03*
Y954200D03*
X43841Y980971D03*
Y974278D03*
Y967585D03*
X36399Y977625D03*
Y970932D03*
X43841Y987664D03*
X36399Y991011D03*
Y984318D03*
X43841Y1027822D03*
Y1017782D03*
X36399Y1031168D03*
Y1024475D03*
Y1017782D03*
X43841Y1047900D03*
Y1041207D03*
Y1034515D03*
X36399Y1044554D03*
Y1037861D03*
X43841Y1061286D03*
Y1054593D03*
X36399Y1057940D03*
Y1051247D03*
X43841Y1074672D03*
Y1067979D03*
X36399Y1078018D03*
Y1071326D03*
Y1064633D03*
X43841Y1091404D03*
Y1084711D03*
X36399Y1094751D03*
Y1088058D03*
X43841Y1111483D03*
Y1104790D03*
Y1098097D03*
X36399Y1108137D03*
Y1101444D03*
X43841Y1128215D03*
Y1121522D03*
X36399Y1124869D03*
Y1114829D03*
X43841Y1141601D03*
Y1134908D03*
X36399Y1144948D03*
Y1138255D03*
Y1131562D03*
X43841Y1158333D03*
Y1148294D03*
X36399Y1161680D03*
Y1151641D03*
X43841Y1171719D03*
Y1165026D03*
X36399Y1175066D03*
Y1168373D03*
X43841Y1185105D03*
Y1178412D03*
X36399Y1188452D03*
Y1181759D03*
X43841Y1208530D03*
Y1201837D03*
Y1195144D03*
X36399Y1205184D03*
Y1198491D03*
X43841Y1221916D03*
Y1215223D03*
X36399Y1225263D03*
Y1218570D03*
Y1211877D03*
X43841Y1238648D03*
Y1231955D03*
X36399Y1241995D03*
Y1235302D03*
X43841Y1245341D03*
X36399Y1248688D03*
X36449Y1257262D03*
X33546Y1273364D03*
X30746D03*
X57399Y770144D03*
X52541Y766798D03*
X57399Y783530D03*
Y776837D03*
X52541Y780184D03*
Y773491D03*
X57399Y800263D03*
Y793570D03*
X52541Y803609D03*
Y796916D03*
Y790223D03*
X57399Y820341D03*
Y813648D03*
Y806955D03*
X52541Y816995D03*
Y810302D03*
X57399Y830381D03*
X52541Y833727D03*
Y827034D03*
X57399Y850459D03*
Y843766D03*
Y837074D03*
X52541Y847113D03*
Y840420D03*
X57399Y867192D03*
Y857152D03*
X52541Y863845D03*
Y853806D03*
X57399Y880577D03*
Y873885D03*
X52541Y883924D03*
Y877231D03*
Y870538D03*
X57399Y893963D03*
Y887270D03*
X52541Y900656D03*
Y890617D03*
X57399Y917389D03*
Y910696D03*
Y904003D03*
X52541Y914042D03*
Y907349D03*
X57399Y930774D03*
Y924081D03*
X52541Y927428D03*
Y920735D03*
X57399Y947507D03*
Y940814D03*
X52541Y944160D03*
Y937467D03*
X57399Y964239D03*
Y954200D03*
X52541Y960892D03*
Y950853D03*
X57399Y977625D03*
Y970932D03*
X52541Y980971D03*
Y974278D03*
Y967585D03*
X57399Y991011D03*
Y984318D03*
X52541Y987664D03*
X57399Y1031168D03*
Y1024475D03*
Y1017782D03*
X52541Y1027822D03*
Y1017782D03*
X57399Y1044554D03*
Y1037861D03*
X52541Y1047900D03*
Y1041207D03*
Y1034515D03*
X57399Y1057940D03*
Y1051247D03*
X52541Y1061286D03*
Y1054593D03*
X57399Y1078018D03*
Y1071326D03*
Y1064633D03*
X52541Y1074672D03*
Y1067979D03*
X57399Y1094751D03*
Y1088058D03*
X52541Y1091404D03*
Y1084711D03*
X57399Y1108137D03*
Y1101444D03*
X52541Y1111483D03*
Y1104790D03*
Y1098097D03*
X57399Y1124869D03*
Y1114829D03*
X52541Y1128215D03*
Y1121522D03*
X57399Y1144948D03*
Y1138255D03*
Y1131562D03*
X52541Y1141601D03*
Y1134908D03*
X57399Y1161680D03*
Y1151641D03*
X52541Y1158333D03*
Y1148294D03*
X57399Y1175066D03*
Y1168373D03*
X52541Y1171719D03*
Y1165026D03*
X57399Y1188452D03*
Y1181759D03*
X52541Y1185105D03*
Y1178412D03*
X57399Y1205184D03*
Y1198491D03*
X52541Y1208530D03*
Y1201837D03*
Y1195144D03*
X57399Y1225263D03*
Y1218570D03*
Y1211877D03*
X52541Y1221916D03*
Y1215223D03*
X57399Y1241995D03*
Y1235302D03*
X52541Y1238648D03*
Y1231955D03*
Y1248688D03*
X57399D03*
X52541Y1245341D03*
X60446Y1273364D03*
X49546D03*
X46746D03*
X73541Y766798D03*
X66099Y770144D03*
X73541Y780184D03*
Y773491D03*
X66099Y783530D03*
Y776837D03*
X73541Y803609D03*
Y796916D03*
Y790223D03*
X66099Y800263D03*
Y793570D03*
X73541Y816995D03*
Y810302D03*
X66099Y820341D03*
Y813648D03*
Y806955D03*
X73541Y833727D03*
Y827034D03*
X66099Y830381D03*
X73541Y847113D03*
Y840420D03*
X66099Y850459D03*
Y843766D03*
Y837074D03*
X73541Y863845D03*
Y853806D03*
X66099Y867192D03*
Y857152D03*
X73541Y883924D03*
Y877231D03*
Y870538D03*
X66099Y880577D03*
Y873885D03*
X73541Y900656D03*
Y890617D03*
X66099Y893963D03*
Y887270D03*
X73541Y914042D03*
Y907349D03*
X66099Y917389D03*
Y910696D03*
Y904003D03*
X73541Y927428D03*
Y920735D03*
X66099Y930774D03*
Y924081D03*
X73541Y944160D03*
Y937467D03*
X66099Y947507D03*
Y940814D03*
X73541Y960892D03*
Y950853D03*
X66099Y964239D03*
Y954200D03*
X73541Y980971D03*
Y974278D03*
Y967585D03*
X66099Y977625D03*
Y970932D03*
X73541Y987664D03*
X66099Y991011D03*
Y984318D03*
X73541Y1027822D03*
Y1017782D03*
X66099Y1031168D03*
Y1024475D03*
Y1017782D03*
X73541Y1047900D03*
Y1041207D03*
Y1034515D03*
X66099Y1044554D03*
Y1037861D03*
X73541Y1061286D03*
Y1054593D03*
X66099Y1057940D03*
Y1051247D03*
X73541Y1074672D03*
Y1067979D03*
X66099Y1078018D03*
Y1071326D03*
Y1064633D03*
X73541Y1091404D03*
Y1084711D03*
X66099Y1094751D03*
Y1088058D03*
X73541Y1111483D03*
Y1104790D03*
Y1098097D03*
X66099Y1108137D03*
Y1101444D03*
X73541Y1128215D03*
Y1121522D03*
X66099Y1124869D03*
Y1114829D03*
X73541Y1141601D03*
Y1134908D03*
X66099Y1144948D03*
Y1138255D03*
Y1131562D03*
X73541Y1158333D03*
Y1148294D03*
X66099Y1161680D03*
Y1151641D03*
X73541Y1171719D03*
Y1165026D03*
X66099Y1175066D03*
Y1168373D03*
X73541Y1185105D03*
Y1178412D03*
X66099Y1188452D03*
Y1181759D03*
X73541Y1208530D03*
Y1201837D03*
Y1195144D03*
X66099Y1205184D03*
Y1198491D03*
X73541Y1221916D03*
Y1215223D03*
X66099Y1225263D03*
Y1218570D03*
Y1211877D03*
X73541Y1238648D03*
Y1231955D03*
X66099Y1241995D03*
Y1235302D03*
X66189Y1257488D03*
X73541Y1245341D03*
X66099Y1248688D03*
X76446Y1273364D03*
X63246D03*
X87099Y770144D03*
X82241Y766798D03*
X87099Y783530D03*
Y776837D03*
X82241Y780184D03*
Y773491D03*
X87099Y800263D03*
Y793570D03*
X82241Y803609D03*
Y796916D03*
Y790223D03*
X87099Y820341D03*
Y813648D03*
Y806955D03*
X82241Y816995D03*
Y810302D03*
X87099Y830381D03*
X82241Y833727D03*
Y827034D03*
X87099Y850459D03*
Y843766D03*
Y837074D03*
X82241Y847113D03*
Y840420D03*
X87099Y867192D03*
Y857152D03*
X82241Y863845D03*
Y853806D03*
X87099Y880577D03*
Y873885D03*
X82241Y883924D03*
Y877231D03*
Y870538D03*
X87099Y893963D03*
Y887270D03*
X82241Y900656D03*
Y890617D03*
X87099Y917389D03*
Y910696D03*
Y904003D03*
X82241Y914042D03*
Y907349D03*
X87099Y930774D03*
Y924081D03*
X82241Y927428D03*
Y920735D03*
X87099Y947507D03*
Y940814D03*
X82241Y944160D03*
Y937467D03*
X87099Y964239D03*
Y954200D03*
X82241Y960892D03*
Y950853D03*
X87099Y977625D03*
Y970932D03*
X82241Y980971D03*
Y974278D03*
Y967585D03*
X87099Y991011D03*
Y984318D03*
X82241Y987664D03*
X87099Y1031168D03*
Y1024475D03*
Y1017782D03*
X82241Y1027822D03*
Y1017782D03*
X87099Y1044554D03*
Y1037861D03*
X82241Y1047900D03*
Y1041207D03*
Y1034515D03*
X87099Y1057940D03*
Y1051247D03*
X82241Y1061286D03*
Y1054593D03*
X87099Y1078018D03*
Y1071326D03*
Y1064633D03*
X82241Y1074672D03*
Y1067979D03*
X87099Y1094751D03*
Y1088058D03*
X82241Y1091404D03*
Y1084711D03*
X87099Y1108137D03*
Y1101444D03*
X82241Y1111483D03*
Y1104790D03*
Y1098097D03*
X87099Y1124869D03*
Y1114829D03*
X82241Y1128215D03*
Y1121522D03*
X87099Y1144948D03*
Y1138255D03*
Y1131562D03*
X82241Y1141601D03*
Y1134908D03*
X87099Y1161680D03*
Y1151641D03*
X82241Y1158333D03*
Y1148294D03*
X87099Y1175066D03*
Y1168373D03*
X82241Y1171719D03*
Y1165026D03*
X87099Y1188452D03*
Y1181759D03*
X82241Y1185105D03*
Y1178412D03*
X87099Y1205184D03*
Y1198491D03*
X82241Y1208530D03*
Y1201837D03*
Y1195144D03*
X87099Y1225263D03*
Y1218570D03*
Y1211877D03*
X82241Y1221916D03*
Y1215223D03*
X87099Y1241995D03*
Y1235302D03*
X82241Y1238648D03*
Y1231955D03*
X87099Y1248688D03*
X82241Y1245341D03*
X92946Y1273364D03*
X90146D03*
X79246D03*
X103241Y766798D03*
X95799Y770144D03*
X103241Y780184D03*
Y773491D03*
X95799Y783530D03*
Y776837D03*
X103241Y803609D03*
Y796916D03*
Y790223D03*
X95799Y800263D03*
Y793570D03*
X103241Y816995D03*
Y810302D03*
X95799Y820341D03*
Y813648D03*
Y806955D03*
X103241Y833727D03*
Y827034D03*
X95799Y830381D03*
X103241Y847113D03*
Y840420D03*
X95799Y850459D03*
Y843766D03*
Y837074D03*
X103241Y863845D03*
Y853806D03*
X95799Y867192D03*
Y857152D03*
X103241Y883924D03*
Y877231D03*
Y870538D03*
X95799Y880577D03*
Y873885D03*
X103241Y900656D03*
Y890617D03*
X95799Y893963D03*
Y887270D03*
X103241Y914042D03*
Y907349D03*
X95799Y917389D03*
Y910696D03*
Y904003D03*
X103241Y927428D03*
Y920735D03*
X95799Y930774D03*
Y924081D03*
X103241Y944160D03*
Y937467D03*
X95799Y947507D03*
Y940814D03*
X103241Y960892D03*
Y950853D03*
X95799Y964239D03*
Y954200D03*
X103241Y980971D03*
Y974278D03*
Y967585D03*
X95799Y977625D03*
Y970932D03*
X103241Y987664D03*
X95799Y991011D03*
Y984318D03*
X103241Y1027822D03*
Y1017782D03*
X95799Y1031168D03*
Y1024475D03*
Y1017782D03*
X103241Y1047900D03*
Y1041207D03*
Y1034515D03*
X95799Y1044554D03*
Y1037861D03*
X103241Y1061286D03*
Y1054593D03*
X95799Y1057940D03*
Y1051247D03*
X103241Y1074672D03*
Y1067979D03*
X95799Y1078018D03*
Y1071326D03*
Y1064633D03*
X103241Y1091404D03*
Y1084711D03*
X95799Y1094751D03*
Y1088058D03*
X103241Y1111483D03*
Y1104790D03*
Y1098097D03*
X95799Y1108137D03*
Y1101444D03*
X103241Y1128215D03*
Y1121522D03*
X95799Y1124869D03*
Y1114829D03*
X103241Y1141601D03*
Y1134908D03*
X95799Y1144948D03*
Y1138255D03*
Y1131562D03*
X103241Y1158333D03*
Y1148294D03*
X95799Y1161680D03*
Y1151641D03*
X103241Y1171719D03*
Y1165026D03*
X95799Y1175066D03*
Y1168373D03*
X103241Y1185105D03*
Y1178412D03*
X95799Y1188452D03*
Y1181759D03*
X103241Y1208530D03*
Y1201837D03*
Y1195144D03*
X95799Y1205184D03*
Y1198491D03*
X103241Y1221916D03*
Y1215223D03*
X95799Y1225263D03*
Y1218570D03*
Y1211877D03*
X103241Y1238648D03*
Y1231955D03*
X95799Y1241995D03*
Y1235302D03*
X95849Y1257262D03*
X103241Y1245341D03*
X95799Y1248688D03*
X108946Y1273364D03*
X106146D03*
X125499Y770144D03*
X116799D03*
X111941Y766798D03*
X125499Y783530D03*
X116799D03*
X125499Y776837D03*
X116799D03*
X111941Y780184D03*
Y773491D03*
X125499Y800263D03*
X116799D03*
X125499Y793570D03*
X116799D03*
X111941Y803609D03*
Y796916D03*
Y790223D03*
X125499Y820341D03*
X116799D03*
X125499Y813648D03*
X116799D03*
X125499Y806955D03*
X116799D03*
X111941Y816995D03*
Y810302D03*
X125499Y830381D03*
X116799D03*
X111941Y833727D03*
Y827034D03*
X125499Y850459D03*
X116799D03*
X125499Y843766D03*
X116799D03*
X125499Y837074D03*
X116799D03*
X111941Y847113D03*
Y840420D03*
X125499Y867192D03*
X116799D03*
X125499Y857152D03*
X116799D03*
X111941Y863845D03*
Y853806D03*
X125499Y880577D03*
X116799D03*
X125499Y873885D03*
X116799D03*
X111941Y883924D03*
Y877231D03*
Y870538D03*
X125499Y893963D03*
X116799D03*
X125499Y887270D03*
X116799D03*
X111941Y900656D03*
Y890617D03*
X125499Y917389D03*
X116799D03*
X125499Y910696D03*
X116799D03*
X125499Y904003D03*
X116799D03*
X111941Y914042D03*
Y907349D03*
X125499Y930774D03*
X116799D03*
X125499Y924081D03*
X116799D03*
X111941Y927428D03*
Y920735D03*
X125499Y947507D03*
X116799D03*
X125499Y940814D03*
X116799D03*
X111941Y944160D03*
Y937467D03*
X125499Y964239D03*
X116799D03*
X125499Y954200D03*
X116799D03*
X111941Y960892D03*
Y950853D03*
X125499Y977625D03*
X116799D03*
X125499Y970932D03*
X116799D03*
X111941Y980971D03*
Y974278D03*
Y967585D03*
X125499Y991011D03*
X116799D03*
X125499Y984318D03*
X116799D03*
X111941Y987664D03*
X125499Y1031168D03*
X116799D03*
X125499Y1024475D03*
X116799D03*
X125499Y1017782D03*
X116799D03*
X111941Y1027822D03*
Y1017782D03*
X125499Y1044554D03*
X116799D03*
X125499Y1037861D03*
X116799D03*
X111941Y1047900D03*
Y1041207D03*
Y1034515D03*
X125499Y1057940D03*
X116799D03*
X125499Y1051247D03*
X116799D03*
X111941Y1061286D03*
Y1054593D03*
X125499Y1078018D03*
X116799D03*
X125499Y1071326D03*
X116799D03*
X125499Y1064633D03*
X116799D03*
X111941Y1074672D03*
Y1067979D03*
X125499Y1094751D03*
X116799D03*
X125499Y1088058D03*
X116799D03*
X111941Y1091404D03*
Y1084711D03*
X125499Y1108137D03*
X116799D03*
X125499Y1101444D03*
X116799D03*
X111941Y1111483D03*
Y1104790D03*
Y1098097D03*
X125499Y1124869D03*
X116799D03*
X125499Y1114829D03*
X116799D03*
X111941Y1128215D03*
Y1121522D03*
X125499Y1144948D03*
X116799D03*
X125499Y1138255D03*
X116799D03*
X125499Y1131562D03*
X116799D03*
X111941Y1141601D03*
Y1134908D03*
X125499Y1161680D03*
X116799D03*
X125499Y1151641D03*
X116799D03*
X111941Y1158333D03*
Y1148294D03*
X125499Y1175066D03*
X116799D03*
X125499Y1168373D03*
X116799D03*
X111941Y1171719D03*
Y1165026D03*
X125499Y1188452D03*
X116799D03*
X125499Y1181759D03*
X116799D03*
X111941Y1185105D03*
Y1178412D03*
X125499Y1205184D03*
X116799D03*
X125499Y1198491D03*
X116799D03*
X111941Y1208530D03*
Y1201837D03*
Y1195144D03*
X125499Y1225263D03*
X116799D03*
X125499Y1218570D03*
X116799D03*
X125499Y1211877D03*
X116799D03*
X111941Y1221916D03*
Y1215223D03*
X125499Y1241995D03*
X116799D03*
X125499Y1235302D03*
X116799D03*
X111941Y1238648D03*
Y1231955D03*
X125412Y1257102D03*
X125499Y1248688D03*
X116799D03*
X111941Y1245341D03*
X119846Y1273364D03*
X122646D03*
X141641Y766798D03*
X132941D03*
X141641Y773491D03*
X132941D03*
X141641Y780184D03*
X132941D03*
X141641Y803609D03*
X132941D03*
X141641Y790223D03*
X132941D03*
X141641Y796916D03*
X132941D03*
X141641Y816995D03*
X132941D03*
X141641Y810302D03*
X132941D03*
X141641Y833727D03*
X132941D03*
X141641Y827034D03*
X132941D03*
X141641Y840420D03*
X132941D03*
X141641Y847113D03*
X132941D03*
Y863845D03*
X141641D03*
Y853806D03*
X132941D03*
Y883924D03*
X141641D03*
X132941Y870538D03*
X141641D03*
X132941Y877231D03*
X141641D03*
X132941Y900656D03*
X141641D03*
X132941Y890617D03*
X141641D03*
X132941Y907349D03*
X141641D03*
X132941Y914042D03*
X141641D03*
X132941Y920735D03*
X141641D03*
X132941Y927428D03*
X141641D03*
X132941Y937467D03*
X141641D03*
X132941Y944160D03*
X141641D03*
X132941Y960892D03*
X141641D03*
X132941Y950853D03*
X141641D03*
X132941Y980971D03*
X141641D03*
X132941Y974278D03*
X141641D03*
X132941Y967585D03*
X141641D03*
X132941Y987664D03*
X141641D03*
X132941Y1027822D03*
X141641D03*
X132941Y1017782D03*
X141641D03*
X132941Y1047900D03*
X141641D03*
X132941Y1041207D03*
X141641D03*
X132941Y1034515D03*
X141641D03*
Y1061286D03*
X132941D03*
X141641Y1054593D03*
X132941D03*
X141641Y1074672D03*
X132941D03*
X141641Y1067979D03*
X132941D03*
X141641Y1091404D03*
X132941D03*
X141641Y1084711D03*
X132941D03*
X141641Y1111483D03*
X132941D03*
X141641Y1104790D03*
X132941D03*
X141641Y1098097D03*
X132941D03*
X141641Y1128215D03*
X132941D03*
X141641Y1121522D03*
X132941D03*
X141641Y1141601D03*
X132941D03*
X141641Y1134908D03*
X132941D03*
X141641Y1158333D03*
X132941D03*
X141641Y1148294D03*
X132941D03*
X141641Y1171719D03*
X132941D03*
X141641Y1165026D03*
X132941D03*
X141641Y1185105D03*
X132941D03*
X141641Y1178412D03*
X132941D03*
X141641Y1208530D03*
X132941D03*
X141641Y1201837D03*
X132941D03*
X141641Y1195144D03*
X132941D03*
Y1221916D03*
X141641D03*
X132941Y1215223D03*
X141641D03*
X132941Y1238648D03*
X141641D03*
X132941Y1231955D03*
X141641D03*
X132941Y1245341D03*
X141641D03*
X135846Y1273364D03*
X138646D03*
X146499Y770144D03*
X155199D03*
X146499Y783530D03*
X155199D03*
X146499Y776837D03*
X155199D03*
X146499Y800263D03*
X155199D03*
X146499Y793570D03*
X155199D03*
X146499Y820341D03*
X155199D03*
X146499Y813648D03*
X155199D03*
X146499Y806955D03*
X155199D03*
X146499Y830381D03*
X155199D03*
X146499Y850459D03*
X155199D03*
X146499Y843766D03*
X155199D03*
X146499Y837074D03*
X155199D03*
Y867192D03*
X146499D03*
Y857152D03*
X155199D03*
Y880577D03*
X146499D03*
X155199Y873885D03*
X146499D03*
X155199Y893963D03*
X146499D03*
X155199Y887270D03*
X146499D03*
X155199Y917389D03*
X146499D03*
X155199Y910696D03*
X146499D03*
X155199Y904003D03*
X146499D03*
X155199Y930774D03*
X146499D03*
X155199Y924081D03*
X146499D03*
X155199Y947507D03*
X146499D03*
X155199Y940814D03*
X146499D03*
X155199Y964239D03*
X146499D03*
X155199Y954200D03*
X146499D03*
X155199Y977625D03*
X146499D03*
X155199Y970932D03*
X146499D03*
X155199Y991011D03*
X146499D03*
X155199Y984318D03*
X146499D03*
X155199Y1031168D03*
X146499D03*
X155199Y1024475D03*
X146499D03*
X155199Y1017782D03*
X146499D03*
X155199Y1044554D03*
X146499D03*
X155199Y1037861D03*
X146499D03*
X155199Y1057940D03*
X146499D03*
X155199Y1051247D03*
X146499D03*
X155199Y1078018D03*
X146499D03*
X155199Y1071326D03*
X146499D03*
X155199Y1064633D03*
X146499D03*
X155199Y1094751D03*
X146499D03*
X155199Y1088058D03*
X146499D03*
X155199Y1108137D03*
X146499D03*
X155199Y1101444D03*
X146499D03*
X155199Y1124869D03*
X146499D03*
X155199Y1114829D03*
X146499D03*
X155199Y1144948D03*
X146499D03*
X155199Y1138255D03*
X146499D03*
X155199Y1131562D03*
X146499D03*
X155199Y1161680D03*
X146499D03*
X155199Y1151641D03*
X146499D03*
X155199Y1175066D03*
X146499D03*
X155199Y1168373D03*
X146499D03*
X155199Y1188452D03*
X146499D03*
X155199Y1181759D03*
X146499D03*
X155199Y1205184D03*
X146499D03*
X155199Y1198491D03*
X146499D03*
X155199Y1225263D03*
X146499D03*
X155199Y1218570D03*
X146499D03*
X155199Y1211877D03*
X146499D03*
X155199Y1241995D03*
X146499D03*
X155199Y1235302D03*
X146499D03*
X155135Y1257134D03*
X155199Y1248688D03*
X146499D03*
X149546Y1273364D03*
X152346D03*
X176199Y770144D03*
X162641Y766798D03*
X171341D03*
X176199Y783530D03*
Y776837D03*
X162641Y780184D03*
X171341D03*
Y773491D03*
X162641D03*
X176199Y800263D03*
X162641Y803609D03*
X171341D03*
X176199Y793570D03*
X162641Y796916D03*
X171341D03*
X162641Y790223D03*
X171341D03*
X176199Y820341D03*
X162641Y816995D03*
X171341D03*
X176199Y813648D03*
Y806955D03*
X162641Y810302D03*
X171341D03*
X162641Y833727D03*
X171341D03*
X176199Y830381D03*
X162641Y827034D03*
X171341D03*
X176199Y850459D03*
Y843766D03*
Y837074D03*
X162641Y847113D03*
X171341D03*
X162641Y840420D03*
X171341D03*
X176199Y867192D03*
X171341Y863845D03*
X162641D03*
X176199Y857152D03*
X162641Y853806D03*
X171341D03*
Y883924D03*
X162641D03*
X176199Y880577D03*
Y873885D03*
X171341Y877231D03*
X162641D03*
X171341Y870538D03*
X162641D03*
X171341Y900656D03*
X162641D03*
X176199Y893963D03*
Y887270D03*
X171341Y890617D03*
X162641D03*
X176199Y917389D03*
Y910696D03*
Y904003D03*
X171341Y914042D03*
X162641D03*
X171341Y907349D03*
X162641D03*
X176199Y930774D03*
Y924081D03*
X171341Y927428D03*
X162641D03*
X171341Y920735D03*
X162641D03*
X176199Y947507D03*
Y940814D03*
X171341Y944160D03*
X162641D03*
X171341Y937467D03*
X162641D03*
X176199Y964239D03*
Y954200D03*
X171341Y960892D03*
X162641D03*
X171341Y950853D03*
X162641D03*
X171341Y980971D03*
X162641D03*
X176199Y977625D03*
Y970932D03*
X171341Y974278D03*
X162641D03*
X171341Y967585D03*
X162641D03*
X176199Y991011D03*
Y984318D03*
X171341Y987664D03*
X162641D03*
X176199Y1031168D03*
Y1024475D03*
Y1017782D03*
X171341Y1027822D03*
X162641D03*
X171341Y1017782D03*
X162641D03*
X171341Y1047900D03*
X162641D03*
X176199Y1044554D03*
Y1037861D03*
X171341Y1041207D03*
X162641D03*
X171341Y1034515D03*
X162641D03*
X176199Y1057940D03*
Y1051247D03*
X171341Y1061286D03*
X162641D03*
X171341Y1054593D03*
X162641D03*
X176199Y1078018D03*
Y1071326D03*
Y1064633D03*
X171341Y1074672D03*
X162641D03*
X171341Y1067979D03*
X162641D03*
X176199Y1094751D03*
Y1088058D03*
X171341Y1091404D03*
X162641D03*
X171341Y1084711D03*
X162641D03*
X171341Y1111483D03*
X162641D03*
X176199Y1108137D03*
Y1101444D03*
X171341Y1104790D03*
X162641D03*
X171341Y1098097D03*
X162641D03*
X171341Y1128215D03*
X162641D03*
X176199Y1124869D03*
Y1114829D03*
X171341Y1121522D03*
X162641D03*
X176199Y1144948D03*
Y1138255D03*
Y1131562D03*
X171341Y1141601D03*
X162641D03*
X171341Y1134908D03*
X162641D03*
X176199Y1161680D03*
Y1151641D03*
X171341Y1158333D03*
X162641D03*
X171341Y1148294D03*
X162641D03*
X176199Y1175066D03*
Y1168373D03*
X171341Y1171719D03*
X162641D03*
X171341Y1165026D03*
X162641D03*
X176199Y1188452D03*
Y1181759D03*
X171341Y1185105D03*
X162641D03*
X171341Y1178412D03*
X162641D03*
X176199Y1205184D03*
Y1198491D03*
X171341Y1208530D03*
X162641D03*
X171341Y1201837D03*
X162641D03*
X171341Y1195144D03*
X162641D03*
X176199Y1225263D03*
Y1218570D03*
Y1211877D03*
X162641Y1221916D03*
X171341D03*
Y1215223D03*
X162641D03*
X176199Y1241995D03*
Y1235302D03*
X171341Y1238648D03*
X162641D03*
X171341Y1231955D03*
X162641D03*
X176199Y1248688D03*
X171341Y1245341D03*
X162641D03*
X165546Y1273364D03*
X168346D03*
X192341Y766798D03*
X184899Y770144D03*
X192341Y780184D03*
Y773491D03*
X184899Y783530D03*
Y776837D03*
X192341Y803609D03*
Y796916D03*
Y790223D03*
X184899Y800263D03*
Y793570D03*
X192341Y816995D03*
Y810302D03*
X184899Y820341D03*
Y813648D03*
Y806955D03*
X192341Y833727D03*
X191491Y827034D03*
X184899Y830381D03*
X192341Y847113D03*
Y840420D03*
X184899Y850459D03*
Y843766D03*
Y837074D03*
X191491Y863845D03*
X184899Y867192D03*
X192341Y853806D03*
X184899Y857152D03*
X192341Y883924D03*
Y877231D03*
Y870538D03*
X184899Y880577D03*
Y873885D03*
X192341Y900656D03*
Y890617D03*
X184899Y893963D03*
Y887270D03*
X192341Y914042D03*
Y907349D03*
X184899Y917389D03*
Y910696D03*
Y904003D03*
X191491Y927428D03*
X192341Y920735D03*
X184899Y930774D03*
Y924081D03*
X192341Y937467D03*
Y944160D03*
X184899Y947507D03*
Y940814D03*
X192341Y960892D03*
Y950853D03*
X184899Y964239D03*
Y954200D03*
X192341Y974278D03*
Y980971D03*
Y967585D03*
X184899Y977625D03*
Y970932D03*
X192341Y987664D03*
X184899Y991011D03*
Y984318D03*
X192341Y1027822D03*
Y1017782D03*
X184899Y1031168D03*
Y1024475D03*
Y1017782D03*
X192341Y1047900D03*
Y1041207D03*
Y1034515D03*
X184899Y1044554D03*
Y1037861D03*
X192341Y1054593D03*
Y1061286D03*
X184899Y1057940D03*
Y1051247D03*
X192341Y1074672D03*
Y1067979D03*
X184899Y1078018D03*
Y1071326D03*
Y1064633D03*
X192341Y1091404D03*
X191491Y1084711D03*
X184899Y1094751D03*
Y1088058D03*
X192341Y1111483D03*
Y1104790D03*
Y1098097D03*
X184899Y1108137D03*
Y1101444D03*
X192341Y1128215D03*
Y1121522D03*
X184899Y1124869D03*
Y1114829D03*
X192341Y1141601D03*
Y1134908D03*
X184899Y1144948D03*
Y1138255D03*
Y1131562D03*
X191491Y1158333D03*
X192341Y1148294D03*
X184899Y1161680D03*
Y1151641D03*
X192341Y1171719D03*
Y1165026D03*
X184899Y1175066D03*
Y1168373D03*
X192341Y1185105D03*
Y1178412D03*
X184899Y1188452D03*
Y1181759D03*
X192341Y1208530D03*
Y1201837D03*
Y1195144D03*
X184899Y1205184D03*
Y1198491D03*
X192341Y1221916D03*
Y1215223D03*
X184899Y1225263D03*
Y1218570D03*
Y1211877D03*
X192341Y1238648D03*
X191491Y1231955D03*
X184899Y1241995D03*
Y1235302D03*
X184923Y1258871D03*
X192341Y1245341D03*
X184899Y1248688D03*
X192594Y1271262D03*
X192605Y1268774D03*
X182046Y1273364D03*
X179246D03*
X186697Y1578182D03*
Y1590094D03*
X191997Y1602380D03*
Y1614292D03*
X205899Y770144D03*
X201041Y766798D03*
X205899Y783530D03*
Y776837D03*
X201041Y780184D03*
Y773491D03*
X205899Y800263D03*
Y793570D03*
X201041Y803609D03*
Y796916D03*
Y790223D03*
X205899Y813648D03*
Y806955D03*
X205049Y820341D03*
X201041Y816995D03*
Y810302D03*
X205049Y830381D03*
X201041Y833727D03*
Y827034D03*
X205899Y850459D03*
Y837074D03*
Y843766D03*
X201041Y847113D03*
Y840420D03*
X205049Y867192D03*
X201041Y863845D03*
X205049Y857152D03*
X201041Y853806D03*
X205899Y873885D03*
Y880577D03*
X201041Y883924D03*
Y877231D03*
Y870538D03*
X205899Y893963D03*
Y887270D03*
X201041Y900656D03*
Y890617D03*
X205899Y917389D03*
Y910696D03*
Y904003D03*
X201041Y914042D03*
Y907349D03*
X205049Y930774D03*
Y924081D03*
X201041Y927428D03*
Y920735D03*
X205899Y940814D03*
Y947507D03*
X201041Y937467D03*
Y944160D03*
X205899Y964239D03*
Y954200D03*
X201041Y960892D03*
Y950853D03*
X205899Y970932D03*
Y977625D03*
X201041Y974278D03*
Y980971D03*
Y967585D03*
X205899Y991011D03*
Y984318D03*
X201041Y987664D03*
X205899Y1031168D03*
Y1017782D03*
Y1024475D03*
X201041Y1027822D03*
Y1017782D03*
X205899Y1044554D03*
Y1037861D03*
X201041Y1047900D03*
Y1041207D03*
Y1034515D03*
X205899Y1057940D03*
Y1051247D03*
X201041Y1054593D03*
Y1061286D03*
X205049Y1078018D03*
X205899Y1071326D03*
Y1064633D03*
X201041Y1074672D03*
Y1067979D03*
X205899Y1094751D03*
X205049Y1088058D03*
X201041Y1091404D03*
Y1084711D03*
X205899Y1101444D03*
Y1108137D03*
X201041Y1111483D03*
Y1104790D03*
Y1098097D03*
X205899Y1114829D03*
Y1124869D03*
X201041Y1128215D03*
Y1121522D03*
X205899Y1144948D03*
Y1138255D03*
Y1131562D03*
X201041Y1141601D03*
Y1134908D03*
X205049Y1161680D03*
Y1151641D03*
X201041Y1158333D03*
Y1148294D03*
X205899Y1168373D03*
Y1175066D03*
X201041Y1171719D03*
Y1165026D03*
X205899Y1188452D03*
Y1181759D03*
X201041Y1185105D03*
Y1178412D03*
X205899Y1205184D03*
Y1198491D03*
X201041Y1208530D03*
Y1201837D03*
Y1195144D03*
X205049Y1225263D03*
X205899Y1211877D03*
Y1218570D03*
X201041Y1221916D03*
Y1215223D03*
X205899Y1241995D03*
X205049Y1235302D03*
X201041Y1238648D03*
Y1231955D03*
X205899Y1248688D03*
X201041Y1245341D03*
X206268Y1271348D03*
X206337Y1268720D03*
X194497Y1578182D03*
X206557D03*
X198757D03*
X194497Y1590094D03*
X206557D03*
X198757D03*
X199797Y1614292D03*
Y1602380D03*
X204057Y1614292D03*
Y1602380D03*
X222041Y766798D03*
X214599Y770144D03*
X222041Y780184D03*
Y773491D03*
X214599Y783530D03*
Y776837D03*
X222041Y803609D03*
Y796916D03*
Y790223D03*
X214599Y800263D03*
Y793570D03*
X222041Y810302D03*
X221191Y816995D03*
X214599Y813648D03*
Y806955D03*
X215449Y820341D03*
X222041Y833727D03*
X221191Y827034D03*
X215449Y830381D03*
X222041Y847113D03*
Y840420D03*
X214599Y850459D03*
Y837074D03*
Y843766D03*
X221191Y863845D03*
X215449Y867192D03*
X222041Y853806D03*
X215449Y857152D03*
X222041Y877231D03*
X221191Y870538D03*
X222041Y883924D03*
X214599Y873885D03*
Y880577D03*
X222041Y900656D03*
Y890617D03*
X214599Y893963D03*
Y887270D03*
X222041Y914042D03*
Y907349D03*
X214599Y917389D03*
Y910696D03*
Y904003D03*
X221241Y927428D03*
X222041Y920735D03*
X215449Y930774D03*
Y924081D03*
X222041Y944160D03*
X221191Y937467D03*
X214599Y940814D03*
Y947507D03*
X222041Y960892D03*
Y950853D03*
X214599Y964239D03*
Y954200D03*
X222041Y980971D03*
Y974278D03*
Y967585D03*
X214599Y970932D03*
Y977625D03*
Y991011D03*
Y984318D03*
X222041Y987664D03*
Y1027822D03*
Y1017782D03*
X214599Y1031168D03*
Y1017782D03*
Y1024475D03*
X222041Y1047900D03*
Y1041207D03*
Y1034515D03*
X214599Y1044554D03*
Y1037861D03*
X222041Y1054593D03*
Y1061286D03*
X214599Y1057940D03*
Y1051247D03*
X222041Y1067979D03*
X221191Y1074672D03*
X215449Y1078018D03*
X214599Y1071326D03*
Y1064633D03*
X222041Y1091404D03*
X221191Y1084711D03*
X214599Y1094751D03*
X215449Y1088058D03*
X222041Y1111483D03*
Y1098097D03*
Y1104790D03*
X214599Y1101444D03*
Y1108137D03*
X222041Y1128215D03*
Y1121522D03*
X214599Y1114829D03*
Y1124869D03*
X222041Y1141601D03*
X221191Y1134908D03*
X214599Y1144948D03*
Y1138255D03*
Y1131562D03*
X222041Y1158333D03*
X221191Y1148294D03*
X215449Y1161680D03*
Y1151641D03*
X222041Y1165026D03*
Y1171719D03*
X214599Y1168373D03*
Y1175066D03*
X222041Y1185105D03*
Y1178412D03*
X214599Y1188452D03*
Y1181759D03*
X222041Y1208530D03*
Y1201837D03*
Y1195144D03*
X214599Y1205184D03*
Y1198491D03*
X222041Y1221916D03*
Y1215223D03*
X215449Y1225263D03*
X214599Y1211877D03*
Y1218570D03*
X221191Y1231955D03*
Y1238648D03*
X214599Y1241995D03*
X215449Y1235302D03*
X222041Y1245341D03*
X214824Y1258711D03*
X214599Y1248688D03*
X224987Y1273535D03*
X218617Y1578182D03*
X210817D03*
X222877D03*
X218617Y1590094D03*
X210817D03*
X222877D03*
X211857Y1614292D03*
Y1602380D03*
X223917Y1614292D03*
X216117D03*
X223917Y1602380D03*
X216117D03*
X235599Y770144D03*
X230741Y766798D03*
X235599Y783530D03*
Y776837D03*
X230741Y780184D03*
Y773491D03*
X235599Y800263D03*
Y793570D03*
X230741Y803609D03*
Y796916D03*
Y790223D03*
X234749Y820341D03*
Y813648D03*
X235599Y806955D03*
X230741Y810302D03*
X231006Y817554D03*
X235599Y830381D03*
X230741Y833727D03*
X231591Y827034D03*
X235599Y850459D03*
Y837074D03*
Y843766D03*
X230741Y847113D03*
Y840420D03*
X234749Y867492D03*
X231591Y863845D03*
X234749Y857152D03*
X230741Y853806D03*
X235599Y874185D03*
Y880577D03*
X230741Y877231D03*
X231059Y871084D03*
X230741Y883924D03*
X235599Y893963D03*
Y887270D03*
X230741Y900656D03*
Y890617D03*
X235599Y917389D03*
Y910696D03*
Y904003D03*
X230741Y914042D03*
Y907349D03*
X235599Y930774D03*
Y924081D03*
X231541Y927428D03*
X230741Y920735D03*
X235599Y947507D03*
X234859Y940814D03*
X230741Y944660D03*
X231591Y937467D03*
X235599Y964239D03*
Y954200D03*
X230741Y960892D03*
Y950853D03*
X235599Y977625D03*
Y970932D03*
X230741Y980971D03*
Y974278D03*
Y967585D03*
X235599Y991011D03*
X230741Y987664D03*
X235599Y984318D03*
Y1031168D03*
X230741Y1027822D03*
Y1017782D03*
X235599D03*
Y1024475D03*
Y1044554D03*
Y1037861D03*
X230741Y1047900D03*
Y1041207D03*
Y1034515D03*
X235599Y1051247D03*
Y1057940D03*
X230741Y1054593D03*
Y1061286D03*
X234749Y1078018D03*
X235599Y1071326D03*
Y1064633D03*
X230741Y1067979D03*
X231591Y1074672D03*
X235599Y1094751D03*
X234749Y1088058D03*
X230741Y1091404D03*
Y1084711D03*
X235599Y1108137D03*
Y1101444D03*
X230741Y1111483D03*
Y1098097D03*
Y1104790D03*
X234749Y1124869D03*
X235599Y1114829D03*
X230741Y1128215D03*
Y1121522D03*
X235599Y1144948D03*
Y1138255D03*
X234749Y1131562D03*
X230741Y1141601D03*
X231591Y1134908D03*
X235599Y1151641D03*
Y1161680D03*
X230741Y1158333D03*
X231591Y1148294D03*
X235599Y1175066D03*
Y1168373D03*
X230741Y1165026D03*
Y1171719D03*
X235599Y1188452D03*
Y1181759D03*
X230741Y1185105D03*
Y1178412D03*
X235599Y1205184D03*
Y1198491D03*
X230741Y1208530D03*
Y1201837D03*
Y1195144D03*
X234749Y1225263D03*
X235599Y1218570D03*
Y1211877D03*
X230741Y1221916D03*
Y1215223D03*
X235599Y1241995D03*
X235186Y1234977D03*
X231591Y1231955D03*
Y1238648D03*
X235599Y1248688D03*
X230741Y1245341D03*
X227746Y1273364D03*
X240966Y1273143D03*
X238971Y1274353D03*
X230677Y1578182D03*
X234937D03*
X230677Y1590094D03*
X234937D03*
X228177Y1614292D03*
X235977D03*
X228177Y1602380D03*
X235977D03*
X240237D03*
Y1614292D03*
X233268Y1679920D03*
Y1675383D03*
X241142Y1679320D03*
X233268Y1698627D03*
Y1694093D03*
Y1689556D03*
Y1684454D03*
X241142Y1683857D03*
Y1688391D03*
Y1693493D03*
Y1698030D03*
X233268Y1712800D03*
Y1708266D03*
Y1703729D03*
X241142Y1702564D03*
Y1707666D03*
Y1712203D03*
X233268Y1717903D03*
Y1722440D03*
Y1726974D03*
X241142Y1716737D03*
Y1730911D03*
Y1726377D03*
Y1721840D03*
X251741Y766798D03*
X244299Y770144D03*
X251741Y780184D03*
Y773491D03*
X244299Y783530D03*
Y776837D03*
X251741Y803609D03*
Y796916D03*
Y790223D03*
X244299Y800263D03*
Y793570D03*
X250891Y816995D03*
X251741Y810302D03*
X245149Y820341D03*
Y813648D03*
X244299Y806955D03*
X251741Y833727D03*
X250891Y827034D03*
X244299Y830381D03*
X251741Y847113D03*
Y840420D03*
X244299Y850459D03*
Y837074D03*
Y843766D03*
X250891Y863845D03*
Y853806D03*
X245149Y867192D03*
Y857152D03*
X251741Y870538D03*
Y883924D03*
Y877231D03*
X244299Y873885D03*
Y880577D03*
X250891Y900656D03*
X251741Y890617D03*
X244299Y893963D03*
Y887270D03*
X251741Y914042D03*
Y907349D03*
X244299Y917389D03*
Y910696D03*
Y904003D03*
X250891Y927428D03*
X251741Y920735D03*
X245149Y930774D03*
X244299Y924081D03*
X251741Y944160D03*
X250891Y937467D03*
X244299Y947507D03*
X245149Y940814D03*
X251741Y960892D03*
Y950853D03*
X244299Y964239D03*
Y954200D03*
X251741Y980971D03*
Y974278D03*
Y967585D03*
X244299Y977625D03*
Y970932D03*
X251741Y987664D03*
X244299Y991011D03*
Y984318D03*
Y1031168D03*
X251741Y1027822D03*
Y1017782D03*
X244299D03*
Y1024475D03*
X251741Y1047900D03*
Y1041207D03*
Y1034515D03*
X244299Y1044554D03*
Y1037861D03*
X251741Y1061286D03*
Y1054593D03*
X244299Y1051247D03*
Y1057940D03*
X250891Y1074672D03*
Y1067979D03*
X245149Y1078018D03*
X244299Y1071326D03*
Y1064633D03*
X251741Y1091404D03*
Y1084711D03*
X244299Y1094751D03*
X245149Y1088058D03*
X251741Y1104790D03*
X250891Y1111483D03*
X251741Y1098097D03*
X244299Y1108137D03*
Y1101444D03*
X251741Y1128215D03*
X250891Y1121522D03*
X245149Y1124869D03*
X244299Y1114829D03*
X251741Y1134908D03*
Y1141601D03*
X244299Y1144948D03*
Y1138255D03*
X245149Y1131562D03*
X251741Y1158333D03*
Y1148294D03*
X244299Y1151641D03*
Y1161680D03*
X251741Y1171719D03*
Y1165026D03*
X244299Y1175066D03*
Y1168373D03*
X251741Y1185105D03*
Y1178412D03*
X244299Y1188452D03*
Y1181759D03*
X251741Y1208530D03*
Y1201837D03*
X250891Y1195144D03*
X244299Y1205184D03*
Y1198491D03*
X250891Y1221916D03*
X251741Y1215223D03*
X245149Y1225263D03*
X244299Y1218570D03*
Y1211877D03*
X250891Y1231955D03*
X244299Y1241995D03*
X245149Y1235302D03*
X251741Y1238648D03*
X244299Y1248688D03*
X251741Y1245341D03*
X244789Y1260093D03*
X254897Y1274040D03*
X257197Y1273640D03*
X242737Y1578182D03*
X246997D03*
X254797D03*
X242737Y1590094D03*
X246997D03*
X254797D03*
X248037Y1602380D03*
Y1614292D03*
X252297Y1602380D03*
Y1614292D03*
X249016Y1675383D03*
Y1679920D03*
X256890Y1679320D03*
X249016Y1684454D03*
Y1689556D03*
Y1694093D03*
Y1698627D03*
X256890Y1683857D03*
Y1688391D03*
Y1693493D03*
Y1698030D03*
X249016Y1703729D03*
Y1708266D03*
Y1712800D03*
X256890Y1702564D03*
Y1707666D03*
Y1712203D03*
X249016Y1726974D03*
Y1722440D03*
Y1717903D03*
X256890Y1716737D03*
Y1730911D03*
Y1726377D03*
Y1721840D03*
X260441Y766798D03*
Y780184D03*
Y773491D03*
Y803609D03*
Y796916D03*
Y790223D03*
X261291Y816995D03*
X260441Y810302D03*
Y833727D03*
X261291Y827034D03*
X260441Y847113D03*
Y840420D03*
X261291Y863845D03*
Y853806D03*
X260441Y870538D03*
Y883924D03*
Y877231D03*
Y900656D03*
Y890617D03*
Y914042D03*
Y907349D03*
X261291Y927428D03*
X260441Y920735D03*
Y944160D03*
X261291Y937467D03*
X260441Y960892D03*
Y950853D03*
Y980971D03*
Y974278D03*
Y967585D03*
Y987664D03*
Y1027822D03*
Y1017782D03*
Y1047900D03*
Y1041207D03*
Y1034515D03*
Y1061286D03*
Y1054593D03*
X261291Y1074672D03*
Y1067979D03*
X260441Y1091404D03*
Y1084711D03*
Y1104790D03*
X261291Y1111483D03*
X260441Y1098097D03*
Y1128215D03*
X261291Y1121522D03*
X260441Y1134908D03*
Y1141601D03*
Y1158333D03*
Y1148294D03*
Y1171719D03*
Y1165026D03*
Y1185105D03*
Y1178412D03*
Y1208530D03*
Y1201837D03*
Y1195144D03*
X261291Y1221916D03*
X260441Y1215223D03*
X261291Y1231955D03*
X260441Y1238648D03*
Y1245341D03*
X266857Y1578182D03*
X259057D03*
X271117D03*
X266857Y1590094D03*
X259057D03*
X271117D03*
X260097Y1602380D03*
Y1614292D03*
X272157Y1602380D03*
Y1614292D03*
X264357D03*
Y1602380D03*
X264764Y1675383D03*
Y1679920D03*
X272638Y1679320D03*
X264764Y1684454D03*
Y1689556D03*
Y1694093D03*
Y1698627D03*
X272638Y1683857D03*
Y1688391D03*
Y1693493D03*
Y1698030D03*
X264764Y1703729D03*
Y1708266D03*
Y1712800D03*
X272638Y1702564D03*
Y1707666D03*
Y1712203D03*
X264764Y1726974D03*
Y1722440D03*
Y1717903D03*
X272638Y1716737D03*
Y1730911D03*
Y1726377D03*
Y1721840D03*
X278917Y1578182D03*
X283177D03*
X278917Y1590094D03*
X283177D03*
X284217Y1602380D03*
Y1614292D03*
X276417D03*
Y1602380D03*
X288477Y1614292D03*
Y1602380D03*
X280512Y1675383D03*
Y1679920D03*
Y1684454D03*
Y1689556D03*
Y1694093D03*
Y1698627D03*
Y1703729D03*
Y1708266D03*
Y1712800D03*
Y1726974D03*
Y1722440D03*
Y1717903D03*
X290977Y1578182D03*
X295237D03*
X303037D03*
X290977Y1590094D03*
X295237D03*
X303037D03*
X296277Y1614292D03*
Y1602380D03*
X300537D03*
Y1614292D03*
X300197Y1679920D03*
Y1675383D03*
Y1698627D03*
Y1694093D03*
Y1689556D03*
Y1684454D03*
Y1712800D03*
Y1708266D03*
Y1703729D03*
Y1717903D03*
Y1722440D03*
Y1726974D03*
X315097Y1578182D03*
X307297D03*
X319357D03*
X315097Y1590094D03*
X307297D03*
X319357D03*
X308337Y1602380D03*
Y1614292D03*
X320397D03*
X312597D03*
X320397Y1602380D03*
X312597D03*
X308071Y1679320D03*
X315945Y1679920D03*
Y1675383D03*
X308071Y1683857D03*
Y1698030D03*
Y1693493D03*
Y1688391D03*
X315945Y1698627D03*
Y1694093D03*
Y1689556D03*
Y1684454D03*
X308071Y1702564D03*
Y1712203D03*
Y1707666D03*
X315945Y1712800D03*
Y1708266D03*
Y1703729D03*
X308071Y1716737D03*
Y1721840D03*
Y1726377D03*
Y1730911D03*
X315945Y1717903D03*
Y1722440D03*
Y1726974D03*
X327157Y1578182D03*
X331417D03*
X327157Y1590094D03*
X331417D03*
X324657Y1602380D03*
X332457D03*
X324657Y1614292D03*
X332457D03*
X336717Y1602380D03*
Y1614292D03*
X323819Y1679320D03*
X331693Y1679920D03*
Y1675383D03*
X323819Y1683857D03*
Y1698030D03*
Y1693493D03*
Y1688391D03*
X331693Y1698627D03*
Y1694093D03*
Y1689556D03*
Y1684454D03*
X323819Y1702564D03*
Y1712203D03*
Y1707666D03*
X331693Y1712800D03*
Y1708266D03*
Y1703729D03*
X323819Y1716737D03*
Y1721840D03*
Y1726377D03*
Y1730911D03*
X331693Y1717903D03*
Y1722440D03*
Y1726974D03*
X352579Y854584D03*
X347029Y870606D03*
Y889832D03*
X343707Y1091513D03*
X339217Y1578182D03*
X343477D03*
X351277D03*
X339217Y1590094D03*
X343477D03*
X351277D03*
X344517Y1602380D03*
Y1614292D03*
X348777Y1602380D03*
Y1614292D03*
X339567Y1679320D03*
X347441Y1679920D03*
Y1675383D03*
X355315Y1679320D03*
X339567Y1683857D03*
Y1698030D03*
Y1693493D03*
Y1688391D03*
X347441Y1698627D03*
Y1694093D03*
Y1689556D03*
Y1684454D03*
X355315Y1683857D03*
Y1698030D03*
Y1693493D03*
Y1688391D03*
X339567Y1702564D03*
Y1712203D03*
Y1707666D03*
X347441Y1712800D03*
Y1708266D03*
Y1703729D03*
X355315Y1702564D03*
Y1712203D03*
Y1707666D03*
X339567Y1716737D03*
Y1721840D03*
Y1726377D03*
Y1730911D03*
X347441Y1717903D03*
Y1722440D03*
Y1726974D03*
X355315Y1716737D03*
Y1721840D03*
Y1726377D03*
Y1730911D03*
X359979Y841467D03*
X367379D03*
X365529Y851380D03*
X369229D03*
X359979Y880219D03*
Y899445D03*
X371078D03*
X359979Y918670D03*
X365529Y941100D03*
X359979Y937896D03*
X371078D03*
X369662Y1006093D03*
X365962Y1076587D03*
X363337Y1578088D03*
X355537Y1578182D03*
X367597D03*
X363337Y1590094D03*
X355537D03*
X367597D03*
X356577Y1602380D03*
Y1614292D03*
X368637D03*
X360837D03*
X368637Y1602286D03*
X360837Y1602380D03*
X382179Y841467D03*
X374779D03*
X380329Y851380D03*
X376629D03*
X372929D03*
X384029D03*
X387729D03*
X378478Y931488D03*
X378911Y1060565D03*
X375397Y1578182D03*
Y1590094D03*
X372897Y1602380D03*
X380697D03*
X372897Y1614292D03*
X380697D03*
X389579Y841467D03*
X396978Y899445D03*
Y937896D03*
X415185Y985580D03*
X417575D03*
X415185Y1014540D03*
X417575D03*
X435829Y851380D03*
Y864197D03*
Y877014D03*
Y889832D03*
Y902649D03*
X428429Y921875D03*
X430279Y937897D03*
X433979D03*
X433980Y944305D03*
Y957123D03*
Y950714D03*
Y963531D03*
Y976348D03*
Y969940D03*
Y982757D03*
X434411Y1009298D03*
X434412Y1002889D03*
X434411Y1028524D03*
Y1022115D03*
X434412Y1015706D03*
Y1034932D03*
X434411Y1092608D03*
X450629Y851380D03*
Y877014D03*
X437678Y912262D03*
X441379Y937897D03*
X445079D03*
X437679D03*
X446929Y941101D03*
X446930Y947510D03*
Y960327D03*
Y953918D03*
Y966736D03*
Y979553D03*
Y973144D03*
X447362Y1006094D03*
Y999685D03*
Y1012502D03*
Y1025319D03*
Y1018911D03*
Y1031728D03*
X456178Y912262D03*
X461729Y921875D03*
X462261Y942152D03*
X464561D03*
X466861D03*
X454423Y949139D03*
X454393Y963829D03*
Y966129D03*
X463874Y956540D03*
X466272D03*
X454423Y951439D03*
X466272Y971100D03*
X463874Y971140D03*
X454263Y981209D03*
Y978909D03*
X454463Y995299D03*
Y992999D03*
X466272Y985580D03*
X463874D03*
X466272Y1014540D03*
X463874D03*
X454443Y1009409D03*
Y1007109D03*
X466272Y1000060D03*
X463874D03*
X468895Y1014550D03*
X465862Y1057361D03*
X458462Y1063770D03*
X465862D03*
X456611Y1073383D03*
X454762Y1070178D03*
X467711Y1073383D03*
Y1066974D03*
X474678Y899445D03*
Y912262D03*
X480229Y921875D03*
X471204Y1014540D03*
X475111Y1060565D03*
X484361Y1057361D03*
X475111Y1066974D03*
X473262Y1070178D03*
X478811Y1073383D03*
X484361Y1076587D03*
X482512Y1066974D03*
X478812Y1079791D03*
X475111D03*
X482911Y1578182D03*
X478651D03*
X470851D03*
X482911Y1590094D03*
X478651D03*
X470851D03*
X483951Y1614292D03*
Y1602380D03*
X476151D03*
Y1614292D03*
X489478Y912262D03*
X495462Y1057361D03*
X499162Y1063770D03*
X495462Y1076587D03*
X493612Y1073383D03*
X486211D03*
X497311Y1066974D03*
X495462Y1108630D03*
X493611Y1111834D03*
X494971Y1578182D03*
X490711D03*
X494971Y1590094D03*
X490711D03*
X500271Y1614292D03*
Y1602380D03*
X488211Y1614292D03*
Y1602380D03*
X496011D03*
Y1614292D03*
X497441Y1675383D03*
Y1679920D03*
Y1684454D03*
Y1689556D03*
Y1694093D03*
Y1698627D03*
Y1703729D03*
Y1708266D03*
Y1712800D03*
Y1726974D03*
Y1722440D03*
Y1717903D03*
X507978Y937896D03*
X509829Y947509D03*
X510262Y1057361D03*
X506562Y1063770D03*
X510262Y1076587D03*
X512111Y1073383D03*
X508411Y1066974D03*
X515811D03*
X508411Y1079791D03*
X515811Y1086200D03*
X507031Y1578182D03*
X514831D03*
X502771D03*
X507031Y1590094D03*
X514831D03*
X502771D03*
X512331Y1614292D03*
Y1602380D03*
X508071Y1614292D03*
Y1602380D03*
X513189Y1675383D03*
Y1679920D03*
X505315Y1679320D03*
X513189Y1684454D03*
Y1689556D03*
Y1694093D03*
Y1698627D03*
X505315Y1688391D03*
Y1693493D03*
Y1698030D03*
Y1683857D03*
X513189Y1703729D03*
Y1708266D03*
Y1712800D03*
X505315Y1707666D03*
Y1712203D03*
Y1702564D03*
X513189Y1726974D03*
Y1722440D03*
Y1717903D03*
X505315Y1730911D03*
Y1726377D03*
Y1721840D03*
Y1716737D03*
X521362Y1057361D03*
X525061Y1063770D03*
X532462D03*
X521362Y1076587D03*
X519512Y1073383D03*
X523211Y1066974D03*
X534311D03*
X531151Y1578182D03*
X519091D03*
X526891D03*
X531151Y1590094D03*
X519091D03*
X526891D03*
X532191Y1614292D03*
Y1602380D03*
X524391Y1614292D03*
Y1602380D03*
X520131D03*
Y1614292D03*
X528937Y1675383D03*
Y1679920D03*
X521063Y1679320D03*
X528937Y1684454D03*
Y1689556D03*
Y1694093D03*
Y1698627D03*
X521063Y1688391D03*
Y1693493D03*
Y1698030D03*
Y1683857D03*
X528937Y1703729D03*
Y1708266D03*
Y1712800D03*
X521063Y1707666D03*
Y1712203D03*
Y1702564D03*
X528937Y1726974D03*
Y1722440D03*
Y1717903D03*
X521063Y1730911D03*
Y1726377D03*
Y1721840D03*
Y1716737D03*
X543129Y928283D03*
X539429D03*
X537578Y925079D03*
X535729Y928283D03*
X548678Y925079D03*
X537578Y944304D03*
X548678D03*
X536161Y1057361D03*
X549422Y1064850D03*
X541711Y1073383D03*
X545411Y1066974D03*
X536161Y1076587D03*
X536162Y1070178D03*
X538011Y1073383D03*
X547262Y1070178D03*
X543211Y1578182D03*
X538951D03*
X543211Y1590094D03*
X538951D03*
X548511Y1614292D03*
Y1602380D03*
X536451D03*
Y1614292D03*
X544251Y1602380D03*
Y1614292D03*
X544685Y1675383D03*
Y1679920D03*
X536811Y1679320D03*
X544685Y1684454D03*
Y1689556D03*
Y1694093D03*
Y1698627D03*
X536811Y1688391D03*
Y1693493D03*
Y1698030D03*
Y1683857D03*
X544685Y1703729D03*
Y1708266D03*
Y1712800D03*
X536811Y1707666D03*
Y1712203D03*
Y1702564D03*
X544685Y1726974D03*
Y1722440D03*
Y1717903D03*
X536811Y1730911D03*
Y1726377D03*
Y1721840D03*
Y1716737D03*
X555271Y1578182D03*
X563071D03*
X551011D03*
X555271Y1590094D03*
X563071D03*
X551011D03*
X560571Y1602380D03*
X556311Y1614292D03*
Y1602380D03*
X552559Y1679320D03*
X564370Y1675383D03*
Y1679920D03*
X552559Y1688391D03*
Y1693493D03*
Y1698030D03*
Y1683857D03*
X564370Y1684454D03*
Y1689556D03*
Y1694093D03*
Y1698627D03*
X552559Y1707666D03*
Y1712203D03*
Y1702564D03*
X564370Y1703729D03*
Y1708266D03*
Y1712800D03*
X552559Y1730911D03*
Y1726377D03*
Y1721840D03*
Y1716737D03*
X564370Y1726974D03*
Y1722440D03*
Y1717903D03*
X579391Y1578182D03*
X567331D03*
X575131D03*
X579391Y1590094D03*
X567331D03*
X575131D03*
X580431Y1614292D03*
X572631D03*
Y1602380D03*
X568371D03*
Y1614292D03*
X580118Y1675383D03*
Y1679920D03*
X572244Y1679320D03*
X580118Y1684454D03*
Y1689556D03*
Y1694093D03*
Y1698627D03*
X572244Y1688391D03*
Y1693493D03*
Y1698030D03*
Y1683857D03*
X580118Y1703729D03*
Y1708266D03*
Y1712800D03*
X572244Y1707666D03*
Y1712203D03*
Y1702564D03*
X580118Y1726974D03*
Y1722440D03*
Y1717903D03*
X572244Y1730911D03*
Y1726377D03*
Y1721840D03*
Y1716737D03*
X599251Y1578182D03*
X591451D03*
X587191D03*
X599251Y1590094D03*
X591451D03*
X587191D03*
X596751Y1614292D03*
Y1602380D03*
X584691D03*
Y1614292D03*
X592491Y1602380D03*
Y1614292D03*
X595866Y1675383D03*
Y1679920D03*
X587992Y1679320D03*
X595866Y1684454D03*
Y1689556D03*
Y1694093D03*
Y1698627D03*
X587992Y1688391D03*
Y1693493D03*
Y1698030D03*
Y1683857D03*
X595866Y1703729D03*
Y1708266D03*
Y1712800D03*
X587992Y1707666D03*
Y1712203D03*
Y1702564D03*
X595866Y1726974D03*
Y1722440D03*
Y1717903D03*
X587992Y1730911D03*
Y1726377D03*
Y1721840D03*
Y1716737D03*
X615571Y1578182D03*
X603511D03*
X611311D03*
X615571Y1590094D03*
X603511D03*
X611311D03*
X608811Y1602380D03*
Y1614292D03*
X604551Y1602380D03*
Y1614292D03*
X611614Y1675383D03*
Y1679920D03*
X603740Y1679320D03*
X611614Y1684454D03*
Y1689556D03*
Y1694093D03*
Y1698627D03*
X603740Y1688391D03*
Y1693493D03*
Y1698030D03*
Y1683857D03*
X611614Y1703729D03*
Y1708266D03*
Y1712800D03*
X603740Y1707666D03*
Y1712203D03*
Y1702564D03*
X611614Y1726974D03*
Y1722440D03*
Y1717903D03*
X603740Y1730911D03*
Y1726377D03*
Y1721840D03*
Y1716737D03*
X629599Y770144D03*
X620899D03*
X629599Y783530D03*
X620899D03*
X629599Y776837D03*
X620899D03*
X620846Y800263D03*
X629599D03*
Y793570D03*
X620899D03*
Y820341D03*
X629599D03*
X620076Y813648D03*
X630593D03*
X619632Y806955D03*
X630792D03*
X620899Y830381D03*
X629599D03*
X620005Y850459D03*
X630754D03*
X620899Y843766D03*
X629599D03*
Y837074D03*
X620899D03*
Y867192D03*
X629599D03*
X620058Y857152D03*
X630481D03*
X620899Y880577D03*
X629599D03*
X620899Y873885D03*
X629599D03*
X630756Y893963D03*
X620899D03*
X629599Y887270D03*
X620899D03*
Y910696D03*
X629599D03*
Y917389D03*
X620899D03*
X629599Y904003D03*
X620899D03*
X630399Y930697D03*
X619905Y930774D03*
X620899Y924081D03*
X629599D03*
Y947507D03*
X620899D03*
X619964Y940814D03*
X630777D03*
X629599Y964239D03*
X620899D03*
X629599Y954200D03*
X620899D03*
Y977625D03*
X629599D03*
Y970932D03*
X620899D03*
Y991011D03*
X629599D03*
Y984318D03*
X620899D03*
Y1031168D03*
X629599D03*
X620899Y1017782D03*
X629599D03*
X620899Y1024475D03*
X629599D03*
X620899Y1044554D03*
X629599D03*
X620899Y1037861D03*
X629599D03*
X620899Y1057940D03*
X629599D03*
Y1051247D03*
X620899D03*
Y1078018D03*
X629599D03*
X630399Y1071326D03*
X619999D03*
X620899Y1064633D03*
X629599D03*
X620899Y1088058D03*
X629599D03*
Y1094751D03*
X620899D03*
Y1108137D03*
X629599D03*
Y1101444D03*
X620899D03*
X630363Y1124674D03*
X620369Y1124969D03*
X630399Y1114829D03*
X620099D03*
X620899Y1131562D03*
X629599D03*
Y1144948D03*
X620899D03*
X629599Y1138255D03*
X620899D03*
X620511Y1161680D03*
X629833Y1161581D03*
X629599Y1151641D03*
X620899D03*
X629599Y1175066D03*
X620899D03*
X629599Y1168373D03*
X620899D03*
X630623Y1188452D03*
X620899D03*
X629599Y1181759D03*
X620899D03*
X629599Y1205184D03*
X620899D03*
Y1198491D03*
X629599D03*
X620899Y1225263D03*
X629599D03*
Y1218570D03*
X620899D03*
X629599Y1211877D03*
X620899D03*
X629599Y1241995D03*
X620899D03*
X630922Y1235302D03*
X620036D03*
X620899Y1248688D03*
X629599D03*
X625246Y1273164D03*
X627646D03*
X627631Y1578182D03*
X623371D03*
X627631Y1590094D03*
X623371D03*
X628671Y1602380D03*
Y1614292D03*
X620871D03*
Y1602380D03*
X616611Y1614292D03*
Y1602380D03*
X619488Y1679320D03*
Y1688391D03*
Y1693493D03*
Y1698030D03*
Y1683857D03*
Y1707666D03*
Y1712203D03*
Y1702564D03*
Y1730911D03*
Y1726377D03*
Y1721840D03*
Y1716737D03*
X637041Y766798D03*
X645741D03*
Y773491D03*
X637041D03*
X645741Y780184D03*
X637041D03*
Y803609D03*
X645741D03*
X637041Y796916D03*
X645741D03*
Y790223D03*
X637041D03*
X636221Y810302D03*
X646844D03*
X646774Y816995D03*
X637041D03*
X645741Y833727D03*
X637041D03*
Y827034D03*
X645741D03*
X637041Y847113D03*
X645801D03*
X637041Y840420D03*
X645741D03*
X646819Y853806D03*
X636332Y853955D03*
X645918Y863845D03*
X636266D03*
X637041Y877231D03*
X645741D03*
X637041Y870538D03*
X645741D03*
Y883924D03*
X637041D03*
Y900656D03*
X645741D03*
X637041Y890617D03*
X645741D03*
X637041Y914042D03*
X645741D03*
Y907349D03*
X637041D03*
X646393Y927526D03*
X636026Y927428D03*
X645741Y920735D03*
X637041D03*
X645741Y944160D03*
X637041D03*
X636170Y937467D03*
X646703D03*
X645741Y960892D03*
X637041D03*
Y950853D03*
X645741D03*
X637041Y980971D03*
X645741D03*
X637041Y974278D03*
X645741D03*
X637041Y967585D03*
X645741D03*
X637041Y987664D03*
X645741D03*
X637041Y1027822D03*
X645741D03*
Y1017782D03*
X637041D03*
X645741Y1047900D03*
X637041D03*
Y1041207D03*
X645741D03*
X637041Y1034515D03*
X645741D03*
X637041Y1061286D03*
X645741D03*
Y1054593D03*
X637041D03*
X636141Y1074672D03*
X646541D03*
X645741Y1067979D03*
X636841D03*
X637041Y1091404D03*
X645741D03*
Y1084711D03*
X636241D03*
X645741Y1111483D03*
X637041D03*
X645741Y1098097D03*
X637041D03*
X645741Y1104790D03*
X637041D03*
Y1121522D03*
X645741D03*
X637041Y1128915D03*
X645741Y1128215D03*
X646584Y1135108D03*
X635744Y1134908D03*
X645741Y1141601D03*
X637041D03*
X645741Y1148294D03*
X637041D03*
X645741Y1158333D03*
X637041D03*
Y1171719D03*
X645741D03*
Y1165026D03*
X637041D03*
Y1185105D03*
X645741D03*
Y1178412D03*
X637041D03*
X645741Y1208530D03*
X637041D03*
X645741Y1201837D03*
X637041D03*
Y1195144D03*
X645741D03*
X636005Y1221916D03*
X646570D03*
X645741Y1215223D03*
X637041D03*
X645741Y1238648D03*
X637041D03*
X635995Y1231862D03*
X646539Y1231955D03*
X645741Y1245341D03*
X637041D03*
X634213Y1258679D03*
X642746Y1273364D03*
X639946D03*
X647491Y1578088D03*
X639691Y1578182D03*
X635431D03*
X647491Y1590094D03*
X639691D03*
X635431D03*
X644991Y1614292D03*
Y1602380D03*
X632931D03*
Y1614292D03*
X640731D03*
Y1602380D03*
X650599Y770144D03*
X659299D03*
X650599Y783530D03*
X659299D03*
X650599Y776837D03*
X659299D03*
Y800263D03*
X650599D03*
Y793570D03*
X659299D03*
Y806955D03*
X650599D03*
X660432Y813648D03*
X650599D03*
X660199Y820341D03*
X650599D03*
X659299Y830381D03*
X650599D03*
X659299Y850459D03*
X650599D03*
X659299Y843766D03*
X650599D03*
Y837074D03*
X659299D03*
Y857152D03*
X650599D03*
X649563Y867192D03*
X660299D03*
X659299Y873885D03*
X650599D03*
Y880577D03*
X659299D03*
X650599Y893963D03*
X659299D03*
X650599Y887270D03*
X659299D03*
Y917389D03*
X650599D03*
X659299Y910696D03*
X650599D03*
Y904003D03*
X659299D03*
X660504Y924081D03*
X650599D03*
X660174Y930774D03*
X649661D03*
X659299Y947507D03*
X650599D03*
X659299Y940814D03*
X650599D03*
X659299Y964239D03*
X650599D03*
Y954200D03*
X659299D03*
Y977625D03*
X650599D03*
X659299Y970932D03*
X650599D03*
X659299Y991011D03*
X650599D03*
X659299Y984318D03*
X650599D03*
X659299Y1031168D03*
X650599D03*
X659299Y1017782D03*
X650599D03*
X659299Y1024475D03*
X650599D03*
X659299Y1044554D03*
X650599D03*
X659299Y1037861D03*
X650599D03*
X659299Y1051247D03*
X650599D03*
Y1057940D03*
X659299D03*
X660099Y1078018D03*
X649799D03*
X659299Y1071326D03*
X650599D03*
X659299Y1064633D03*
X650599D03*
X659299Y1094751D03*
X650599D03*
X660099Y1088058D03*
X649799D03*
X650599Y1108137D03*
X659299D03*
X650599Y1101444D03*
X659299D03*
X660199Y1124869D03*
X649932Y1124640D03*
X659299Y1114829D03*
X650599D03*
X659299Y1130762D03*
X650599D03*
X659299Y1138255D03*
X650599D03*
X659299Y1144948D03*
X650599D03*
X659299Y1151641D03*
X650599D03*
Y1161680D03*
X659299D03*
X650599Y1175066D03*
X659299D03*
X650599Y1168373D03*
X659299D03*
X650599Y1188452D03*
X659299D03*
X650599Y1181759D03*
X659299D03*
X650599Y1205184D03*
X659299D03*
X650599Y1198491D03*
X659299D03*
X660070Y1225263D03*
X649913D03*
X659299Y1218570D03*
X650599D03*
X659299Y1211877D03*
X650599D03*
X659299Y1241995D03*
X650599D03*
X660234Y1235302D03*
X649701D03*
X650599Y1248688D03*
X659299D03*
X659546Y1257664D03*
X656446Y1273364D03*
X653646D03*
X651751Y1578182D03*
X659551D03*
X651751Y1590094D03*
X659551D03*
X657051Y1602380D03*
Y1614292D03*
X652791Y1602286D03*
Y1614292D03*
X680299Y770144D03*
X675441Y766798D03*
X666741D03*
X680299Y783530D03*
Y776837D03*
X666741Y773491D03*
X675441D03*
X666741Y780184D03*
X675441D03*
Y803609D03*
X666741D03*
X680299Y800263D03*
Y793570D03*
X666741Y796916D03*
X675441D03*
X666741Y790223D03*
X675441D03*
X676403Y816995D03*
X665803D03*
X675441Y810302D03*
X666741D03*
X680299Y820341D03*
Y813648D03*
Y806955D03*
X675441Y833727D03*
X666741D03*
X676625Y827034D03*
X665876D03*
X680299Y830381D03*
X675441Y847113D03*
X666741D03*
X680299Y850459D03*
Y843766D03*
Y837074D03*
X666741Y840420D03*
X675441D03*
X676417Y853806D03*
X665890D03*
X680299Y867192D03*
Y857152D03*
X665916Y863845D03*
X676600D03*
X675441Y877231D03*
X666741D03*
X675441Y870538D03*
X666741D03*
Y883924D03*
X675441D03*
X680299Y880577D03*
Y873885D03*
X666741Y900656D03*
X675441D03*
X680299Y893963D03*
Y887270D03*
X666741Y890617D03*
X675441D03*
Y914042D03*
X666741D03*
X680299Y917389D03*
Y910696D03*
Y904003D03*
X666741Y907349D03*
X675441D03*
X676488Y927428D03*
X665896D03*
X675441Y920735D03*
X666741D03*
X680299Y930774D03*
Y924081D03*
X675441Y944160D03*
X666741D03*
X676359Y937467D03*
X665923D03*
X680299Y947507D03*
Y940814D03*
Y964239D03*
X675441Y960892D03*
X666741D03*
X680299Y954200D03*
X666741Y950853D03*
X675441D03*
Y980971D03*
X666741D03*
X680299Y970932D03*
X675441Y974278D03*
X666741D03*
X675441Y967585D03*
X666741D03*
X680299Y977625D03*
X675441Y987664D03*
X666741D03*
X680299Y991011D03*
Y984318D03*
Y1031168D03*
Y1024475D03*
X675441Y1027822D03*
X666741D03*
X675441Y1017782D03*
X666741D03*
X680299D03*
X675441Y1047900D03*
X666741D03*
X680299Y1037861D03*
X675441Y1041207D03*
X666741D03*
X675441Y1034515D03*
X666741D03*
X680299Y1044554D03*
Y1057940D03*
Y1051247D03*
X675441Y1054593D03*
X666741D03*
Y1061286D03*
X675441D03*
X676341Y1074672D03*
X665841D03*
X675441Y1067979D03*
X666741D03*
X680299Y1078018D03*
Y1071326D03*
Y1064633D03*
X675441Y1091404D03*
X666741D03*
X676241Y1084711D03*
X665941D03*
X680299Y1094751D03*
Y1088058D03*
X666741Y1111483D03*
X675441D03*
X680299Y1108137D03*
Y1101444D03*
X666741Y1104790D03*
X675441D03*
X666741Y1098097D03*
X675441D03*
X666741Y1128215D03*
X675441D03*
X680299Y1124869D03*
Y1114829D03*
X666741Y1121522D03*
X675441D03*
X680299Y1144948D03*
Y1138255D03*
Y1131562D03*
X666741Y1141601D03*
X675441D03*
X666741Y1134908D03*
X675441D03*
X676652Y1148294D03*
X665602D03*
X676241Y1158333D03*
X665941D03*
X680299Y1161680D03*
Y1151641D03*
X675441Y1165026D03*
X666741D03*
X680299Y1175066D03*
Y1168373D03*
X666741Y1171719D03*
X675441D03*
X680299Y1188452D03*
Y1181759D03*
X666741Y1185105D03*
X675441D03*
X666741Y1178412D03*
X675441D03*
X680299Y1205184D03*
Y1198491D03*
X666741Y1208530D03*
X675441D03*
X666741Y1201837D03*
X675441D03*
X666741Y1195144D03*
X675441D03*
X680299Y1218570D03*
Y1225263D03*
X676448Y1221916D03*
X665651D03*
X675441Y1215223D03*
X666741D03*
X680299Y1211877D03*
X675441Y1238648D03*
X666741D03*
X676462Y1231955D03*
X665912D03*
X680299Y1241995D03*
Y1235302D03*
X675441Y1245341D03*
X666741D03*
X676046Y1257964D03*
X680299Y1248688D03*
X672446Y1273364D03*
X669646D03*
X664851Y1602380D03*
Y1614292D03*
X696441Y766798D03*
X688999Y770144D03*
X696441Y773491D03*
Y780184D03*
X688999Y783530D03*
Y776837D03*
X696441Y803609D03*
Y796916D03*
Y790223D03*
X688999Y800263D03*
Y793570D03*
X696441Y816995D03*
Y810302D03*
X689888Y820341D03*
X688999Y813648D03*
Y806955D03*
X696441Y833727D03*
Y827034D03*
X688999Y830381D03*
X696441Y847113D03*
X688999Y850459D03*
X696441Y840420D03*
X688999Y843766D03*
Y837074D03*
X696441Y863845D03*
Y853806D03*
X688999Y867192D03*
X689896Y857152D03*
X696441Y883924D03*
Y877231D03*
Y870538D03*
X688999Y880577D03*
Y873885D03*
X696441Y900656D03*
Y890617D03*
X688999Y893963D03*
Y887270D03*
X696441Y914042D03*
Y907349D03*
X688999Y917389D03*
Y910696D03*
Y904003D03*
X696441Y927428D03*
Y920735D03*
X690104Y930774D03*
X688999Y924081D03*
X696441Y944160D03*
Y937467D03*
X688999Y947507D03*
Y940814D03*
X696441Y960892D03*
Y950853D03*
X688999Y964239D03*
Y954200D03*
X696441Y980971D03*
Y974278D03*
Y967585D03*
X688999Y970932D03*
Y977625D03*
X696441Y987664D03*
X688999Y991011D03*
Y984318D03*
X696441Y1027822D03*
Y1017782D03*
X688999Y1031168D03*
Y1024475D03*
Y1017782D03*
X696441Y1047900D03*
Y1041207D03*
Y1034515D03*
X688999Y1037861D03*
Y1044554D03*
X696441Y1054593D03*
Y1061286D03*
X688999Y1057940D03*
X696441Y1074672D03*
Y1067979D03*
X688999Y1077118D03*
Y1071326D03*
Y1064633D03*
X696441Y1091404D03*
Y1084711D03*
X688999Y1094751D03*
Y1088058D03*
X696441Y1111483D03*
Y1104790D03*
Y1098097D03*
X688999Y1108137D03*
Y1101444D03*
X696441Y1128215D03*
Y1121522D03*
X688999Y1124869D03*
Y1114829D03*
X696441Y1141601D03*
Y1134908D03*
X688999Y1144948D03*
Y1138255D03*
Y1131562D03*
X696441Y1158333D03*
Y1148294D03*
X688999Y1161680D03*
X689999Y1151641D03*
X696441Y1171719D03*
Y1165026D03*
X688999Y1175066D03*
Y1168373D03*
X696441Y1185105D03*
Y1178412D03*
X688999Y1188452D03*
Y1181759D03*
X696441Y1208530D03*
Y1201837D03*
Y1195144D03*
X688999Y1205184D03*
Y1198491D03*
X696441Y1221916D03*
Y1215223D03*
X688999Y1218570D03*
X689799Y1225263D03*
X688999Y1211877D03*
X696441Y1238648D03*
Y1231955D03*
X688999Y1241995D03*
Y1235302D03*
X688916Y1256964D03*
X696441Y1245341D03*
X688999Y1248688D03*
X686146Y1273364D03*
X683346D03*
X709999Y770144D03*
X705141Y766798D03*
X709999Y783530D03*
Y776837D03*
X705141Y773491D03*
Y780184D03*
X709999Y800263D03*
Y793570D03*
X705141Y803609D03*
Y796916D03*
Y790223D03*
X709999Y820341D03*
Y813648D03*
Y806955D03*
X705141Y816995D03*
Y810302D03*
X709999Y830381D03*
X705141Y833727D03*
Y827034D03*
Y847113D03*
X709999Y850459D03*
Y843766D03*
Y837074D03*
X705141Y840420D03*
Y863845D03*
Y853806D03*
X709999Y867192D03*
Y857152D03*
X705141Y883924D03*
Y877231D03*
Y870538D03*
X709999Y880577D03*
Y873885D03*
X705141Y900656D03*
Y890617D03*
X709999Y893963D03*
Y887270D03*
X705141Y914042D03*
Y907349D03*
X709999Y917389D03*
Y910696D03*
Y904003D03*
X705141Y927428D03*
Y920735D03*
X709999Y930774D03*
Y924081D03*
X705141Y944160D03*
Y937467D03*
X709999Y947507D03*
Y940814D03*
X705141Y960892D03*
Y950853D03*
X709999Y964239D03*
Y954200D03*
X705141Y980971D03*
Y974278D03*
Y967585D03*
X709999Y977625D03*
Y970932D03*
X705141Y987664D03*
X709999Y991011D03*
Y984318D03*
X705141Y1027822D03*
Y1017782D03*
X709999Y1031168D03*
Y1024475D03*
Y1017782D03*
X705141Y1047900D03*
Y1041207D03*
Y1034515D03*
X709999Y1044554D03*
Y1037861D03*
X705141Y1054593D03*
Y1061286D03*
X709999Y1057940D03*
Y1051247D03*
X705141Y1074672D03*
Y1067979D03*
X709999Y1078018D03*
Y1071326D03*
Y1064633D03*
X705141Y1091404D03*
Y1084711D03*
X709999Y1094751D03*
Y1088058D03*
X705141Y1111483D03*
Y1104790D03*
Y1098097D03*
X709999Y1108137D03*
Y1101444D03*
X705141Y1128215D03*
Y1121522D03*
X709999Y1124869D03*
Y1114829D03*
X705141Y1141601D03*
Y1134908D03*
X709999Y1144948D03*
Y1138255D03*
Y1131562D03*
X705141Y1158333D03*
Y1148294D03*
X709999Y1161680D03*
Y1151641D03*
X705141Y1171719D03*
Y1165026D03*
X709999Y1175066D03*
Y1168373D03*
X705141Y1185105D03*
Y1178412D03*
X709999Y1188452D03*
Y1181759D03*
X705141Y1208530D03*
Y1201837D03*
Y1195144D03*
X709999Y1205184D03*
Y1198491D03*
X705141Y1221916D03*
Y1215223D03*
X709999Y1225263D03*
Y1218570D03*
Y1211877D03*
X705141Y1238648D03*
Y1231955D03*
X709999Y1241995D03*
Y1235302D03*
X705141Y1245341D03*
X709999Y1248688D03*
X713046Y1273364D03*
X702146D03*
X699346D03*
X726141Y766798D03*
X718699Y770144D03*
X726141Y773491D03*
Y780184D03*
X718699Y783530D03*
Y776837D03*
X726141Y803609D03*
Y796916D03*
Y790223D03*
X718699Y800263D03*
Y793570D03*
X726141Y816995D03*
Y810302D03*
X718699Y820341D03*
Y813648D03*
Y806955D03*
X726141Y833727D03*
Y827034D03*
X718699Y830381D03*
X726141Y847113D03*
Y840420D03*
X718699Y850459D03*
Y843766D03*
Y837074D03*
X726141Y863845D03*
Y853806D03*
X718699Y867192D03*
Y857152D03*
X726141Y883924D03*
Y877231D03*
Y870538D03*
X718699Y880577D03*
Y873885D03*
X726141Y900656D03*
Y890617D03*
X718699Y893963D03*
Y887270D03*
X726141Y914042D03*
Y907349D03*
X718699Y917389D03*
Y910696D03*
Y904003D03*
X726141Y927428D03*
Y920735D03*
X718699Y930774D03*
Y924081D03*
X726141Y944160D03*
Y937467D03*
X718699Y947507D03*
Y940814D03*
X726141Y960892D03*
Y950853D03*
X718699Y964239D03*
Y954200D03*
X726141Y980971D03*
Y974278D03*
Y967585D03*
X718699Y977625D03*
Y970932D03*
X726141Y987664D03*
X718699Y991011D03*
Y984318D03*
X726141Y1027822D03*
Y1017782D03*
X718699Y1031168D03*
Y1024475D03*
Y1017782D03*
X726141Y1047900D03*
Y1041207D03*
Y1034515D03*
X718699Y1044554D03*
Y1037861D03*
X726141Y1061286D03*
Y1054593D03*
X718699Y1057940D03*
Y1051247D03*
X726141Y1074672D03*
Y1067979D03*
X718699Y1078018D03*
Y1071326D03*
Y1064633D03*
X726141Y1091404D03*
Y1084711D03*
X718699Y1094751D03*
Y1088058D03*
X726141Y1111483D03*
Y1104790D03*
Y1098097D03*
X718699Y1108137D03*
Y1101444D03*
X726141Y1128215D03*
Y1121522D03*
X718699Y1124869D03*
Y1114829D03*
X726141Y1141601D03*
Y1134908D03*
X718699Y1144948D03*
Y1138255D03*
Y1131562D03*
X726141Y1158333D03*
Y1148294D03*
X718699Y1161680D03*
Y1151641D03*
X726141Y1171719D03*
Y1165026D03*
X718699Y1175066D03*
Y1168373D03*
X726141Y1185105D03*
Y1178412D03*
X718699Y1188452D03*
Y1181759D03*
X726141Y1208530D03*
Y1201837D03*
Y1195144D03*
X718699Y1205184D03*
Y1198491D03*
X726141Y1221916D03*
Y1215223D03*
X718699Y1225263D03*
Y1218570D03*
Y1211877D03*
X726141Y1238648D03*
Y1231955D03*
X718699Y1241995D03*
Y1235302D03*
X726141Y1245341D03*
X719046Y1257064D03*
X718699Y1248688D03*
X729046Y1273364D03*
X715846D03*
X739699Y770144D03*
X734841Y766798D03*
X739699Y783530D03*
Y776837D03*
X734841Y773491D03*
Y780184D03*
X739699Y800263D03*
Y793570D03*
X734841Y803609D03*
Y796916D03*
Y790223D03*
X739699Y820341D03*
Y813648D03*
Y806955D03*
X734841Y816995D03*
Y810302D03*
X739699Y830381D03*
X734841Y833727D03*
Y827034D03*
X739699Y850459D03*
Y843766D03*
Y837074D03*
X734841Y847113D03*
Y840420D03*
X739699Y867192D03*
Y857152D03*
X734841Y863845D03*
Y853806D03*
X739699Y880577D03*
Y873885D03*
X734841Y883924D03*
Y877231D03*
Y870538D03*
X739699Y893963D03*
Y887270D03*
X734841Y900656D03*
Y890617D03*
X739699Y917389D03*
Y910696D03*
Y904003D03*
X734841Y914042D03*
Y907349D03*
X739699Y930774D03*
Y924081D03*
X734841Y927428D03*
Y920735D03*
X739699Y947507D03*
Y940814D03*
X734841Y944160D03*
Y937467D03*
X739699Y964239D03*
Y954200D03*
X734841Y960892D03*
Y950853D03*
X739699Y977625D03*
Y970932D03*
X734841Y980971D03*
Y974278D03*
Y967585D03*
X739699Y991011D03*
Y984318D03*
X734841Y987664D03*
X739699Y1031168D03*
Y1024475D03*
Y1017782D03*
X734841Y1027822D03*
Y1017782D03*
X739699Y1044554D03*
Y1037861D03*
X734841Y1047900D03*
Y1041207D03*
Y1034515D03*
X739699Y1057940D03*
Y1051247D03*
X734841Y1061286D03*
Y1054593D03*
X739699Y1078018D03*
Y1071326D03*
Y1064633D03*
X734841Y1074672D03*
Y1067979D03*
X739699Y1094751D03*
Y1088058D03*
X734841Y1091404D03*
Y1084711D03*
X739699Y1108137D03*
Y1101444D03*
X734841Y1111483D03*
Y1104790D03*
Y1098097D03*
X739699Y1124869D03*
Y1114829D03*
X734841Y1128215D03*
Y1121522D03*
X739699Y1144948D03*
Y1138255D03*
Y1131562D03*
X734841Y1141601D03*
Y1134908D03*
X739699Y1161680D03*
Y1151641D03*
X734841Y1158333D03*
Y1148294D03*
X739699Y1175066D03*
Y1168373D03*
X734841Y1171719D03*
Y1165026D03*
X739699Y1188452D03*
Y1181759D03*
X734841Y1185105D03*
Y1178412D03*
X739699Y1205184D03*
Y1198491D03*
X734841Y1208530D03*
Y1201837D03*
Y1195144D03*
X739699Y1225263D03*
Y1218570D03*
Y1211877D03*
X734841Y1221916D03*
Y1215223D03*
X739699Y1241995D03*
Y1235302D03*
X734841Y1238648D03*
Y1231955D03*
X739699Y1248688D03*
X734841Y1245341D03*
X745546Y1273364D03*
X742746D03*
X731372Y1273464D03*
X755841Y766798D03*
X748399Y770144D03*
X755841Y780184D03*
Y773491D03*
X748399Y783530D03*
Y776837D03*
X755841Y803609D03*
Y796916D03*
Y790223D03*
X748399Y800263D03*
Y793570D03*
X755841Y816995D03*
Y810302D03*
X748399Y820341D03*
Y813648D03*
Y806955D03*
X755841Y833727D03*
Y827034D03*
X748399Y830381D03*
X755841Y847113D03*
Y840420D03*
X748399Y850459D03*
Y843766D03*
Y837074D03*
X755841Y863845D03*
Y853806D03*
X748399Y867192D03*
Y857152D03*
X755841Y883924D03*
Y877231D03*
Y870538D03*
X748399Y880577D03*
Y873885D03*
X755841Y900656D03*
Y890617D03*
X748399Y893963D03*
Y887270D03*
X755841Y914042D03*
Y907349D03*
X748399Y917389D03*
Y910696D03*
Y904003D03*
X755841Y927428D03*
Y920735D03*
X748399Y930774D03*
Y924081D03*
X755841Y944160D03*
Y937467D03*
X748399Y947507D03*
Y940814D03*
X755841Y960892D03*
Y950853D03*
X748399Y964239D03*
Y954200D03*
X755841Y980971D03*
Y974278D03*
Y967585D03*
X748399Y977625D03*
Y970932D03*
X755841Y987664D03*
X748399Y991011D03*
Y984318D03*
X755841Y1027822D03*
Y1017782D03*
X748399Y1031168D03*
Y1024475D03*
Y1017782D03*
X755841Y1047900D03*
Y1041207D03*
Y1034515D03*
X748399Y1044554D03*
Y1037861D03*
X755841Y1054593D03*
Y1061286D03*
X748399Y1057940D03*
X755841Y1067979D03*
Y1074672D03*
X748399Y1078018D03*
Y1071326D03*
Y1064633D03*
X755841Y1084711D03*
Y1091404D03*
X748399Y1094751D03*
Y1088058D03*
X755841Y1111483D03*
Y1104790D03*
Y1098097D03*
X748399Y1108137D03*
Y1101444D03*
X755841Y1128215D03*
Y1121522D03*
X748399Y1124869D03*
Y1114829D03*
X755841Y1141601D03*
Y1134908D03*
X748399Y1144948D03*
Y1138255D03*
Y1131562D03*
X755841Y1158333D03*
Y1148294D03*
X748399Y1161680D03*
Y1151641D03*
X755841Y1171719D03*
Y1165026D03*
X748399Y1175066D03*
Y1168373D03*
X755841Y1185105D03*
Y1178412D03*
X748399Y1188452D03*
Y1181759D03*
X755841Y1208530D03*
Y1201837D03*
Y1195144D03*
X748399Y1205184D03*
Y1198491D03*
X755841Y1221916D03*
Y1215223D03*
X748399Y1225263D03*
Y1218570D03*
Y1211877D03*
X755841Y1238648D03*
Y1231955D03*
X748399Y1241995D03*
Y1235302D03*
X755841Y1245341D03*
X748283Y1256964D03*
X748399Y1248688D03*
X758746Y1273364D03*
X761546D03*
X769399Y770144D03*
X778099D03*
X764541Y766798D03*
X769399Y783530D03*
X778099D03*
X769399Y776837D03*
X778099D03*
X764541Y780184D03*
Y773491D03*
X769399Y800263D03*
X778099D03*
X769399Y793570D03*
X778099D03*
X764541Y803609D03*
Y796916D03*
Y790223D03*
X769399Y820341D03*
X778099D03*
X769399Y813648D03*
X778099D03*
X769399Y806955D03*
X778099D03*
X764541Y816995D03*
Y810302D03*
X769399Y830381D03*
X778099D03*
X764541Y833727D03*
Y827034D03*
X769399Y850459D03*
X778099D03*
Y843766D03*
X769399D03*
Y837074D03*
X778099D03*
X764541Y847113D03*
Y840420D03*
X778099Y867192D03*
X769399D03*
Y857152D03*
X778099D03*
X764541Y863845D03*
Y853806D03*
X769399Y880577D03*
X778099D03*
X769399Y873885D03*
X778099D03*
X764541Y883924D03*
Y877231D03*
Y870538D03*
X778099Y893963D03*
X769399D03*
Y887270D03*
X778099D03*
X764541Y900656D03*
Y890617D03*
X769399Y917389D03*
X778099D03*
X769399Y910696D03*
X778099D03*
X769399Y904003D03*
X778099D03*
X764541Y914042D03*
Y907349D03*
X769399Y930774D03*
X778099D03*
X769399Y924081D03*
X778099D03*
X764541Y927428D03*
Y920735D03*
X769399Y947507D03*
X778099D03*
X769399Y940814D03*
X778099D03*
X764541Y944160D03*
Y937467D03*
X769399Y964239D03*
X778099D03*
X769399Y954200D03*
X778099D03*
X764541Y960892D03*
Y950853D03*
X769399Y977625D03*
X778099D03*
X769399Y970932D03*
X778099D03*
X764541Y980971D03*
Y974278D03*
Y967585D03*
X769399Y991011D03*
X778099D03*
X769399Y984318D03*
X778099D03*
X764541Y987664D03*
X769399Y1031168D03*
X778099D03*
X769399Y1024475D03*
X778099D03*
X769399Y1017782D03*
X778099D03*
X764541Y1027822D03*
Y1017782D03*
X778099Y1044554D03*
X769399D03*
Y1037861D03*
X778099D03*
X764541Y1047900D03*
Y1041207D03*
Y1034515D03*
X769399Y1057940D03*
X778099D03*
X769399Y1051247D03*
X778099D03*
X764541Y1054593D03*
Y1061286D03*
X778099Y1078018D03*
X769399D03*
X778099Y1071326D03*
X769399D03*
Y1064633D03*
X778099D03*
X764541Y1067979D03*
Y1074672D03*
X778099Y1094751D03*
X769399D03*
X778099Y1088058D03*
X769399D03*
X764541Y1084711D03*
Y1091404D03*
X778099Y1108137D03*
X769399D03*
X778099Y1101444D03*
X769399D03*
X764541Y1111483D03*
Y1104790D03*
Y1098097D03*
X778099Y1124869D03*
X769399D03*
X778099Y1114829D03*
X769399D03*
X764541Y1128215D03*
Y1121522D03*
X778099Y1144948D03*
X769399D03*
X778099Y1138255D03*
X769399D03*
X778099Y1131562D03*
X769399D03*
X764541Y1141601D03*
Y1134908D03*
X778099Y1161680D03*
X769399D03*
X778099Y1151641D03*
X769399D03*
X764541Y1158333D03*
Y1148294D03*
X778099Y1175066D03*
X769399D03*
X778099Y1168373D03*
X769399D03*
X764541Y1171719D03*
Y1165026D03*
X778099Y1188452D03*
X769399D03*
X778099Y1181759D03*
X769399D03*
X764541Y1185105D03*
Y1178412D03*
X769399Y1205184D03*
X778099D03*
Y1198491D03*
X769399D03*
X764541Y1208530D03*
Y1201837D03*
Y1195144D03*
X778099Y1225263D03*
X769399D03*
X778099Y1218570D03*
X769399D03*
Y1211877D03*
X778099D03*
X764541Y1221916D03*
Y1215223D03*
X778099Y1241995D03*
X769399D03*
X778099Y1235302D03*
X769399D03*
X764541Y1238648D03*
Y1231955D03*
X778346Y1257264D03*
X778099Y1248688D03*
X769399D03*
X764541Y1245341D03*
X772446Y1273364D03*
X775246D03*
X785541Y766798D03*
X794241D03*
X785541Y773491D03*
X794241D03*
X785541Y780184D03*
X794241D03*
X785541Y803609D03*
X794241D03*
X785541Y790223D03*
X794241D03*
X785541Y796916D03*
X794241D03*
X785541Y816995D03*
X794241D03*
X785541Y810302D03*
X794241D03*
X785541Y833727D03*
X794241D03*
X785541Y827034D03*
X794241D03*
X785541Y840420D03*
X794241D03*
X785541Y847113D03*
X794241D03*
X785541Y853806D03*
X794241D03*
X785541Y863845D03*
X794241D03*
X785541Y883924D03*
X794241D03*
X785541Y870538D03*
X794241D03*
X785541Y877231D03*
X794241D03*
X785541Y900656D03*
X794241D03*
X785541Y890617D03*
X794241D03*
X785541Y907349D03*
X794241D03*
X785541Y914042D03*
X794241D03*
X785541Y920735D03*
X794241D03*
X785541Y927428D03*
X794241D03*
X785541Y937467D03*
X794241D03*
X785541Y944160D03*
X794241D03*
X785541Y960892D03*
X794241D03*
X785541Y950853D03*
X794241D03*
X785541Y980971D03*
X794241D03*
X785541Y974278D03*
X794241D03*
X785541Y967585D03*
X794241D03*
X785541Y987664D03*
X794241D03*
X785541Y1027822D03*
X794241D03*
X785541Y1017782D03*
X794241D03*
X785541Y1047900D03*
X794241D03*
X785541Y1041207D03*
X794241D03*
X785541Y1034515D03*
X794241D03*
X785541Y1054593D03*
X794241D03*
X785541Y1061286D03*
X794241D03*
X785541Y1074672D03*
X794241D03*
X785541Y1067979D03*
X794241D03*
X785541Y1091404D03*
X794241D03*
X785541Y1084711D03*
X794241D03*
X785541Y1111483D03*
X794241D03*
X785541Y1104790D03*
X794241D03*
X785541Y1098097D03*
X794241D03*
X785541Y1128215D03*
X794241D03*
X785541Y1121522D03*
X794241D03*
X785541Y1141601D03*
X794241D03*
X785541Y1134908D03*
X794241D03*
X785541Y1158333D03*
X794241D03*
X785541Y1148294D03*
X794241D03*
X785541Y1171719D03*
X794241D03*
X785541Y1165026D03*
X794241D03*
X785541Y1178412D03*
X794241D03*
X785541Y1185105D03*
X794241D03*
X785541Y1208530D03*
X794241D03*
X785541Y1195144D03*
X794241D03*
X785541Y1201837D03*
X794241D03*
X785541Y1221916D03*
X794241D03*
X785541Y1215223D03*
X794241D03*
X785541Y1238648D03*
X794241D03*
X785541Y1231955D03*
X794241D03*
X785541Y1245341D03*
X794241D03*
X788446Y1273364D03*
X791246D03*
X799099Y770144D03*
X807799D03*
X799099Y783530D03*
X807799D03*
X799099Y776837D03*
X807799D03*
X799099Y800263D03*
X807799D03*
X799099Y793570D03*
X807799D03*
X799099Y820341D03*
X807799D03*
X799099Y806955D03*
X807799D03*
X799099Y813648D03*
X807799D03*
X799099Y830381D03*
X807799D03*
X799099Y850459D03*
X807799D03*
X799099Y837074D03*
X807799D03*
X799099Y843766D03*
X807799D03*
X799099Y867192D03*
X807799D03*
X799099Y857152D03*
X807799D03*
X799099Y873885D03*
X807799D03*
X799099Y880577D03*
X807799D03*
X799099Y887270D03*
X807799D03*
X799099Y893963D03*
X807799D03*
X799099Y917389D03*
X807799D03*
X799099Y904003D03*
X807799D03*
X799099Y910696D03*
X807799D03*
X799099Y930774D03*
X807799D03*
X799099Y924081D03*
X807799D03*
X799099Y947507D03*
X807799D03*
X799099Y940814D03*
X807799D03*
X799099Y964239D03*
X807799D03*
X799099Y954200D03*
X807799D03*
X799099Y970932D03*
X807799D03*
X799099Y977625D03*
X807799D03*
X799099Y991011D03*
X807799D03*
X799099Y984318D03*
X807799D03*
X799099Y1031168D03*
X807799D03*
X799099Y1024475D03*
X807799D03*
X799099Y1017782D03*
X807799D03*
X799099Y1037861D03*
X807799D03*
X799099Y1044554D03*
X807799D03*
X799099Y1057940D03*
X807799D03*
X799099Y1051247D03*
X807799D03*
X799099Y1078018D03*
X807799D03*
X799099Y1071326D03*
X807799D03*
X799099Y1064633D03*
X807799D03*
X799099Y1094751D03*
X807799D03*
X799099Y1088058D03*
X807799D03*
X799099Y1108137D03*
X807799D03*
X799099Y1101444D03*
X807799D03*
X799099Y1124869D03*
X807799D03*
X799099Y1114829D03*
X807799D03*
X799099Y1144948D03*
X807799D03*
X799099Y1138255D03*
X807799D03*
X799099Y1131562D03*
X807799D03*
X799099Y1161680D03*
X807799D03*
X799099Y1151641D03*
X807799D03*
X799099Y1175066D03*
X807799D03*
X799099Y1168373D03*
X807799D03*
X799099Y1188452D03*
X807799D03*
X799099Y1181759D03*
X807799D03*
X799099Y1205184D03*
X807799D03*
X799099Y1198491D03*
X807799D03*
X799099Y1225263D03*
X807799D03*
X799099Y1211877D03*
X807799D03*
X799099Y1218570D03*
X807799D03*
X799099Y1241995D03*
X807799D03*
X799099Y1235302D03*
X807799D03*
X799099Y1248688D03*
X807799D03*
X808046Y1257664D03*
X804946Y1273364D03*
X802146D03*
X815241Y766798D03*
X823941D03*
X815241Y773491D03*
X823941D03*
X815241Y780184D03*
X823941D03*
X815241Y803609D03*
X823941D03*
X815241Y790223D03*
X823941D03*
X815241Y796916D03*
X823941D03*
X815241Y816995D03*
X823941D03*
X815241Y810302D03*
X823941D03*
X815241Y833727D03*
X823941D03*
X815241Y827034D03*
X823941D03*
X815241Y840420D03*
X823941D03*
X815241Y847113D03*
X823941D03*
X815241Y853806D03*
X823941D03*
X815241Y863845D03*
X823941D03*
X815241Y883924D03*
X823941D03*
X815241Y870538D03*
X823941D03*
X815241Y877231D03*
X823941D03*
X815241Y900656D03*
X823941D03*
X815241Y890617D03*
X823941D03*
X815241Y907349D03*
X823941D03*
X815241Y914042D03*
X823941D03*
X815241Y920735D03*
X823941D03*
X815241Y927428D03*
X823941D03*
X815241Y937467D03*
X823941D03*
X815241Y944160D03*
X823941D03*
X815241Y960892D03*
X823941D03*
X815241Y950853D03*
X823941D03*
X815241Y980971D03*
X823941D03*
X815241Y974278D03*
X823941D03*
X815241Y967585D03*
X823941D03*
X815241Y987664D03*
X823941D03*
X815241Y1027822D03*
X823941D03*
X815241Y1017782D03*
X823941D03*
X815241Y1047900D03*
X823941D03*
X815241Y1041207D03*
X823941D03*
X815241Y1034515D03*
X823941D03*
X815241Y1054593D03*
X823941D03*
X815241Y1061286D03*
X823941D03*
X815241Y1074672D03*
X823941D03*
X815241Y1067979D03*
X823941D03*
X815241Y1091404D03*
X823941D03*
X815241Y1084711D03*
X823941D03*
X815241Y1111483D03*
X823941D03*
X815241Y1104790D03*
X823941D03*
X815241Y1098097D03*
X823941D03*
X815241Y1128215D03*
X823941D03*
X815241Y1121522D03*
X823941D03*
X815241Y1141601D03*
X823941D03*
X815241Y1134908D03*
X823941D03*
X815241Y1158333D03*
X823941D03*
X815241Y1148294D03*
X823941D03*
X815241Y1171719D03*
X823941D03*
X815241Y1165026D03*
X823941D03*
X815241Y1178412D03*
X823941D03*
X815241Y1185105D03*
X823941D03*
X815241Y1208530D03*
X823941D03*
X815241Y1195144D03*
X823941D03*
X815241Y1201837D03*
X823941D03*
X815241Y1221916D03*
X823941D03*
X815241Y1215223D03*
X823941D03*
X815241Y1238648D03*
X823941D03*
X815241Y1231955D03*
X823941D03*
X815241Y1245341D03*
X823941D03*
X820946Y1273364D03*
X818146D03*
X828799Y770144D03*
X837499D03*
X828799Y783530D03*
X837499D03*
X828799Y776837D03*
X837499D03*
Y800263D03*
X828799D03*
X837499Y793570D03*
X828799D03*
Y820341D03*
X837499D03*
X828799Y813648D03*
X837499D03*
X828799Y806955D03*
X837499D03*
X828799Y830381D03*
X837499D03*
X828799Y850459D03*
X837499D03*
X828799Y843766D03*
X837499D03*
X828799Y837074D03*
X837499D03*
X828799Y867192D03*
X837499D03*
X828799Y857152D03*
X837499D03*
X828799Y880577D03*
X837499D03*
X828799Y873885D03*
X837499D03*
X828799Y893963D03*
X837499D03*
X828799Y887270D03*
X837499D03*
X828799Y917389D03*
X837499D03*
Y904003D03*
X828799D03*
X837499Y910696D03*
X828799D03*
Y930774D03*
X837499D03*
X828799Y924081D03*
X837499D03*
X828799Y947507D03*
X837499D03*
X828799Y940814D03*
X837499D03*
X828799Y964239D03*
X837499D03*
X828799Y954200D03*
X837499D03*
X828799Y977625D03*
X837499D03*
X828799Y970932D03*
X837499D03*
X828799Y991011D03*
X837499D03*
X828799Y984318D03*
X837499D03*
X828799Y1031168D03*
X837499D03*
X828799Y1024475D03*
X837499D03*
X828799Y1017782D03*
X837499D03*
X828799Y1044554D03*
X837499D03*
X828799Y1037861D03*
X837499D03*
X828799Y1057940D03*
X837499D03*
X828799Y1051247D03*
X837499D03*
X828799Y1078018D03*
X837499D03*
X828799Y1071326D03*
X837499D03*
X828799Y1064633D03*
X837499D03*
X828799Y1094751D03*
X837499D03*
Y1088058D03*
X828799D03*
X837499Y1108137D03*
X828799D03*
Y1101444D03*
X837499D03*
Y1124869D03*
X828799D03*
X837499Y1114829D03*
X828799D03*
X837499Y1144948D03*
X828799D03*
X837499Y1138255D03*
X828799D03*
X837499Y1131562D03*
X828799D03*
X837499Y1161680D03*
X828799D03*
X837499Y1151641D03*
X828799D03*
X837499Y1175066D03*
X828799D03*
X837499Y1168373D03*
X828799D03*
Y1188452D03*
X837499D03*
Y1181759D03*
X828799D03*
X837499Y1205184D03*
X828799D03*
X837499Y1198491D03*
X828799D03*
X837499Y1225263D03*
X828799D03*
X837499Y1218570D03*
X828799D03*
X837499Y1211877D03*
X828799D03*
X837499Y1241995D03*
X828799D03*
X837499Y1235302D03*
X828799D03*
X837499Y1248688D03*
X828799D03*
X837846Y1256964D03*
X839246Y1273064D03*
X842046D03*
X831846Y1273364D03*
X834646D03*
X844941Y766798D03*
X853641D03*
X844941Y780184D03*
X853641D03*
X844941Y773491D03*
X853641D03*
X844941Y803609D03*
X853641D03*
X844941Y796916D03*
X853641D03*
X844941Y790223D03*
X853641D03*
X844941Y816995D03*
X853641D03*
X844941Y810302D03*
X853641D03*
X844941Y833727D03*
X853641D03*
X844941Y827034D03*
X853641D03*
X844941Y847113D03*
X853641D03*
X844941Y840420D03*
X853641D03*
X844941Y863845D03*
X853641D03*
X844941Y853806D03*
X853641D03*
X844941Y883924D03*
X853641D03*
X844941Y877231D03*
X853641D03*
X844941Y870538D03*
X853641D03*
X844941Y900656D03*
X853641D03*
X844941Y890617D03*
X853641D03*
X844941Y914042D03*
X853641D03*
X844941Y907349D03*
X853641D03*
X844941Y927428D03*
X853641D03*
X844941Y920735D03*
X853641D03*
X844941Y944160D03*
X853641D03*
X844941Y937467D03*
X853641D03*
X844941Y960892D03*
X853641D03*
X844941Y950853D03*
X853641D03*
X844941Y980971D03*
X853641D03*
X844941Y974278D03*
X853641D03*
X844941Y967585D03*
X853641D03*
X844941Y987664D03*
X853641D03*
X844941Y1027822D03*
X853641D03*
X844941Y1017782D03*
X853641D03*
X844941Y1047900D03*
X853641D03*
X844941Y1041207D03*
X853641D03*
X844941Y1034515D03*
X853641D03*
X844941Y1061286D03*
X853641D03*
X844941Y1054593D03*
X853641D03*
X844941Y1074672D03*
X853641D03*
X844941Y1067979D03*
X853641D03*
X844941Y1091404D03*
X853641D03*
X844941Y1084711D03*
X853641D03*
X844941Y1111483D03*
X853641D03*
X844941Y1104790D03*
X853641D03*
X844941Y1098097D03*
X853641D03*
X844941Y1128215D03*
X853641D03*
X844941Y1121522D03*
X853641D03*
X844941Y1141601D03*
X853641D03*
X844941Y1134908D03*
X853641D03*
X844941Y1158333D03*
X853641D03*
X844941Y1148294D03*
X853641D03*
X844941Y1171719D03*
X853641D03*
X844941Y1165026D03*
X853641D03*
X844941Y1185105D03*
X853641D03*
X844941Y1178412D03*
X853641D03*
X844941Y1208530D03*
X853641D03*
X844941Y1201837D03*
X853641D03*
X844941Y1195144D03*
X853641D03*
X844941Y1221916D03*
X853641D03*
X844941Y1215223D03*
X853641D03*
X844941Y1238648D03*
X853641D03*
X844941Y1231955D03*
X853641D03*
X844941Y1245341D03*
X853641D03*
X1003841Y770144D03*
Y783530D03*
Y776837D03*
Y800263D03*
Y793570D03*
Y820341D03*
Y813648D03*
Y806955D03*
Y830381D03*
Y850459D03*
Y843766D03*
Y837074D03*
Y867192D03*
Y857152D03*
Y880577D03*
Y873885D03*
Y893963D03*
Y887270D03*
Y917389D03*
Y910696D03*
Y904003D03*
Y930774D03*
Y924081D03*
Y947507D03*
Y940814D03*
Y964239D03*
Y954200D03*
Y977625D03*
Y970932D03*
Y991011D03*
Y984318D03*
Y1031168D03*
Y1024475D03*
Y1017782D03*
Y1044554D03*
Y1037861D03*
Y1057940D03*
Y1051247D03*
Y1078018D03*
Y1071326D03*
Y1064633D03*
Y1094751D03*
Y1088058D03*
Y1108137D03*
Y1101444D03*
Y1124869D03*
Y1114829D03*
Y1144948D03*
Y1138255D03*
Y1131562D03*
Y1161680D03*
Y1151641D03*
Y1175066D03*
Y1168373D03*
Y1188452D03*
Y1181759D03*
Y1205184D03*
Y1198491D03*
Y1225263D03*
Y1218570D03*
Y1211877D03*
Y1241995D03*
Y1235302D03*
Y1248688D03*
X1019983Y766798D03*
X1012541Y770144D03*
X1019983Y780184D03*
Y773491D03*
X1012541Y783530D03*
Y776837D03*
X1019983Y803609D03*
Y796916D03*
Y790223D03*
X1012541Y800263D03*
Y793570D03*
X1019983Y816995D03*
Y810302D03*
X1012541Y820341D03*
Y813648D03*
Y806955D03*
X1019983Y833727D03*
Y827034D03*
X1012541Y830381D03*
X1019983Y847113D03*
Y840420D03*
X1012541Y850459D03*
Y843766D03*
Y837074D03*
X1019983Y863845D03*
Y853806D03*
X1012541Y867192D03*
Y857152D03*
X1019983Y883924D03*
Y877231D03*
Y870538D03*
X1012541Y880577D03*
Y873885D03*
X1019983Y900656D03*
Y890617D03*
X1012541Y893963D03*
Y887270D03*
X1019983Y914042D03*
Y907349D03*
X1012541Y917389D03*
Y910696D03*
Y904003D03*
X1019983Y927428D03*
Y920735D03*
X1012541Y930774D03*
Y924081D03*
X1019983Y944160D03*
Y937467D03*
X1012541Y947507D03*
Y940814D03*
X1019983Y960892D03*
Y950853D03*
X1012541Y964239D03*
Y954200D03*
X1019983Y980971D03*
Y974278D03*
Y967585D03*
X1012541Y977625D03*
Y970932D03*
X1019983Y987664D03*
X1012541Y991011D03*
Y984318D03*
X1019983Y1027822D03*
Y1017782D03*
X1012541Y1031168D03*
Y1024475D03*
Y1017782D03*
X1019983Y1047900D03*
Y1041207D03*
Y1034515D03*
X1012541Y1044554D03*
Y1037861D03*
X1019983Y1061286D03*
Y1054593D03*
X1012541Y1057940D03*
Y1051247D03*
X1019983Y1067979D03*
Y1074672D03*
X1012541Y1078018D03*
Y1071326D03*
Y1064633D03*
X1019983Y1091404D03*
Y1084711D03*
X1012541Y1094751D03*
Y1088058D03*
X1019983Y1111483D03*
Y1104790D03*
Y1098097D03*
X1012541Y1108137D03*
Y1101444D03*
X1019983Y1128215D03*
Y1121522D03*
X1012541Y1124869D03*
Y1114829D03*
X1019983Y1141601D03*
Y1134908D03*
X1012541Y1144948D03*
Y1138255D03*
Y1131562D03*
X1019983Y1158333D03*
Y1148294D03*
X1012541Y1161680D03*
Y1151641D03*
X1019983Y1171719D03*
Y1165026D03*
X1012541Y1175066D03*
Y1168373D03*
X1019983Y1185105D03*
Y1178412D03*
X1012541Y1188452D03*
Y1181759D03*
X1019983Y1208530D03*
Y1201837D03*
Y1195144D03*
X1012541Y1205184D03*
Y1198491D03*
X1019983Y1221916D03*
Y1215223D03*
X1012541Y1225263D03*
Y1218570D03*
Y1211877D03*
X1019983Y1238648D03*
Y1231955D03*
X1012541Y1241995D03*
Y1235302D03*
X1012543Y1257198D03*
X1019983Y1245341D03*
X1012541Y1248688D03*
X1017111Y1273299D03*
X1014111D03*
X1033541Y770144D03*
X1028683Y766798D03*
X1033541Y783530D03*
Y776837D03*
X1028683Y780184D03*
Y773491D03*
X1033541Y800263D03*
Y793570D03*
X1028683Y803609D03*
Y796916D03*
Y790223D03*
X1033541Y820341D03*
Y813648D03*
Y806955D03*
X1028683Y816995D03*
Y810302D03*
X1033541Y830381D03*
X1028683Y833727D03*
Y827034D03*
X1033541Y850459D03*
Y843766D03*
Y837074D03*
X1028683Y847113D03*
Y840420D03*
X1033541Y867192D03*
Y857152D03*
X1028683Y863845D03*
Y853806D03*
X1033541Y880577D03*
Y873885D03*
X1028683Y883924D03*
Y877231D03*
Y870538D03*
X1033541Y893963D03*
Y887270D03*
X1028683Y900656D03*
Y890617D03*
X1033541Y917389D03*
Y910696D03*
Y904003D03*
X1028683Y914042D03*
Y907349D03*
X1033541Y930774D03*
Y924081D03*
X1028683Y927428D03*
Y920735D03*
X1033541Y947507D03*
Y940814D03*
X1028683Y944160D03*
Y937467D03*
X1033541Y964239D03*
Y954200D03*
X1028683Y960892D03*
Y950853D03*
X1033541Y977625D03*
Y970932D03*
X1028683Y980971D03*
Y974278D03*
Y967585D03*
X1033541Y991011D03*
Y984318D03*
X1028683Y987664D03*
X1033541Y1031168D03*
Y1017782D03*
Y1024475D03*
X1028683Y1027822D03*
Y1017782D03*
X1033541Y1044554D03*
Y1037861D03*
X1028683Y1047900D03*
Y1041207D03*
Y1034515D03*
X1033541Y1057940D03*
Y1051247D03*
X1028683Y1061286D03*
Y1054593D03*
X1033541Y1078018D03*
Y1071326D03*
Y1064633D03*
X1028683Y1067979D03*
Y1074672D03*
X1033541Y1094751D03*
Y1088058D03*
X1028683Y1091404D03*
Y1084711D03*
X1033541Y1108137D03*
Y1101444D03*
X1028683Y1111483D03*
Y1104790D03*
Y1098097D03*
X1033541Y1114829D03*
Y1124869D03*
X1028683Y1128215D03*
Y1121522D03*
X1033541Y1144948D03*
Y1138255D03*
Y1131562D03*
X1028683Y1141601D03*
Y1134908D03*
X1033541Y1161680D03*
Y1151641D03*
X1028683Y1158333D03*
Y1148294D03*
X1033541Y1175066D03*
Y1168373D03*
X1028683Y1171719D03*
Y1165026D03*
X1033541Y1188452D03*
Y1181759D03*
X1028683Y1185105D03*
Y1178412D03*
X1033541Y1205184D03*
Y1198491D03*
X1028683Y1208530D03*
Y1201837D03*
Y1195144D03*
X1033541Y1225263D03*
Y1218570D03*
Y1211877D03*
X1028683Y1221916D03*
Y1215223D03*
X1033541Y1241995D03*
Y1235302D03*
X1028683Y1238648D03*
Y1231955D03*
X1033541Y1248688D03*
X1028683Y1245341D03*
X1036588Y1273344D03*
X1022888D03*
X1025688D03*
X1049683Y766798D03*
X1042241Y770144D03*
X1049683Y780184D03*
Y773491D03*
X1042241Y783530D03*
Y776837D03*
X1049683Y803609D03*
Y796916D03*
Y790223D03*
X1042241Y800263D03*
Y793570D03*
X1049683Y816995D03*
Y810302D03*
X1042241Y820341D03*
Y813648D03*
Y806955D03*
X1049683Y833727D03*
Y827034D03*
X1042241Y830381D03*
X1049683Y847113D03*
Y840420D03*
X1042241Y850459D03*
Y843766D03*
Y837074D03*
X1049683Y863845D03*
Y853806D03*
X1042241Y867192D03*
Y857152D03*
X1049683Y883924D03*
Y877231D03*
Y870538D03*
X1042241Y880577D03*
Y873885D03*
X1049683Y900656D03*
Y890617D03*
X1042241Y893963D03*
Y887270D03*
X1049683Y914042D03*
Y907349D03*
X1042241Y917389D03*
Y910696D03*
Y904003D03*
X1049683Y927428D03*
Y920735D03*
X1042241Y930774D03*
Y924081D03*
X1049683Y944160D03*
Y937467D03*
X1042241Y947507D03*
Y940814D03*
X1049683Y960892D03*
Y950853D03*
X1042241Y964239D03*
Y954200D03*
X1049683Y980971D03*
Y974278D03*
Y967585D03*
X1042241Y977625D03*
Y970932D03*
X1049683Y987664D03*
X1042241Y991011D03*
Y984318D03*
X1049683Y1027822D03*
Y1017782D03*
X1042241Y1031168D03*
Y1017782D03*
Y1024475D03*
X1049683Y1047900D03*
Y1041207D03*
Y1034515D03*
X1042241Y1044554D03*
Y1037861D03*
X1049683Y1061286D03*
Y1054593D03*
X1042241Y1057940D03*
Y1051247D03*
X1049683Y1074672D03*
Y1067979D03*
X1042241Y1078018D03*
Y1071326D03*
Y1064633D03*
X1049683Y1091404D03*
Y1084711D03*
X1042241Y1094751D03*
Y1088058D03*
X1049683Y1111483D03*
Y1104790D03*
Y1098097D03*
X1042241Y1108137D03*
Y1101444D03*
Y1114829D03*
X1049683Y1128215D03*
Y1121522D03*
X1042241Y1124869D03*
X1049683Y1141601D03*
Y1134908D03*
X1042241Y1144948D03*
Y1138255D03*
Y1131562D03*
Y1161680D03*
X1049683Y1158333D03*
Y1148294D03*
X1042241Y1151641D03*
X1049683Y1171719D03*
Y1165026D03*
X1042241Y1175066D03*
Y1168373D03*
X1049683Y1185105D03*
Y1178412D03*
X1042241Y1188452D03*
Y1181759D03*
X1049683Y1208530D03*
Y1201837D03*
Y1195144D03*
X1042241Y1205184D03*
Y1198491D03*
X1049683Y1215223D03*
Y1221916D03*
X1042241Y1225263D03*
Y1218570D03*
Y1211877D03*
X1049683Y1238648D03*
Y1231955D03*
X1042241Y1241995D03*
Y1235302D03*
X1042331Y1257488D03*
X1049683Y1245341D03*
X1042241Y1248688D03*
X1052588Y1273344D03*
X1039388D03*
X1063241Y770144D03*
X1058383Y766798D03*
X1063241Y783530D03*
Y776837D03*
X1058383Y780184D03*
Y773491D03*
X1063241Y800263D03*
Y793570D03*
X1058383Y803609D03*
Y796916D03*
Y790223D03*
X1063241Y820341D03*
Y813648D03*
Y806955D03*
X1058383Y816995D03*
Y810302D03*
X1063241Y830381D03*
X1058383Y833727D03*
Y827034D03*
X1063241Y850459D03*
Y843766D03*
Y837074D03*
X1058383Y847113D03*
Y840420D03*
X1063241Y867192D03*
Y857152D03*
X1058383Y863845D03*
Y853806D03*
X1063241Y880577D03*
Y873885D03*
X1058383Y883924D03*
Y877231D03*
Y870538D03*
X1063241Y893963D03*
Y887270D03*
X1058383Y900656D03*
Y890617D03*
X1063241Y917389D03*
Y910696D03*
Y904003D03*
X1058383Y914042D03*
Y907349D03*
X1063241Y930774D03*
Y924081D03*
X1058383Y927428D03*
Y920735D03*
X1063241Y947507D03*
Y940814D03*
X1058383Y944160D03*
Y937467D03*
X1063241Y964239D03*
Y954200D03*
X1058383Y960892D03*
Y950853D03*
X1063241Y977625D03*
Y970932D03*
X1058383Y980971D03*
Y974278D03*
Y967585D03*
X1063241Y991011D03*
Y984318D03*
X1058383Y987664D03*
X1063241Y1031168D03*
Y1024475D03*
Y1017782D03*
X1058383Y1027822D03*
Y1017782D03*
X1063241Y1044554D03*
Y1037861D03*
X1058383Y1047900D03*
Y1041207D03*
Y1034515D03*
X1063241Y1057940D03*
Y1051247D03*
X1058383Y1061286D03*
Y1054593D03*
X1063241Y1078018D03*
Y1071326D03*
Y1064633D03*
X1058383Y1074672D03*
Y1067979D03*
X1063241Y1094751D03*
Y1088058D03*
X1058383Y1091404D03*
Y1084711D03*
X1063241Y1108137D03*
Y1101444D03*
X1058383Y1111483D03*
Y1104790D03*
Y1098097D03*
X1063241Y1124869D03*
Y1114829D03*
X1058383Y1128215D03*
Y1121522D03*
X1063241Y1144948D03*
Y1138255D03*
Y1131562D03*
X1058383Y1141601D03*
Y1134908D03*
X1063241Y1161680D03*
Y1151641D03*
X1058383Y1158333D03*
Y1148294D03*
X1063241Y1175066D03*
Y1168373D03*
X1058383Y1171719D03*
Y1165026D03*
X1063241Y1188452D03*
Y1181759D03*
X1058383Y1185105D03*
Y1178412D03*
X1063241Y1205184D03*
Y1198491D03*
X1058383Y1208530D03*
Y1201837D03*
Y1195144D03*
X1063241Y1225263D03*
Y1218570D03*
Y1211877D03*
X1058383Y1215223D03*
Y1221916D03*
X1063241Y1241995D03*
Y1235302D03*
X1058383Y1238648D03*
Y1231955D03*
X1063241Y1248688D03*
X1058383Y1245341D03*
X1069088Y1273344D03*
X1066288D03*
X1055388D03*
X1079383Y766798D03*
X1071941Y770144D03*
X1079383Y780184D03*
Y773491D03*
X1071941Y783530D03*
Y776837D03*
X1079383Y803609D03*
Y796916D03*
Y790223D03*
X1071941Y800263D03*
Y793570D03*
X1079383Y816995D03*
Y810302D03*
X1071941Y820341D03*
Y813648D03*
Y806955D03*
X1079383Y833727D03*
Y827034D03*
X1071941Y830381D03*
X1079383Y847113D03*
Y840420D03*
X1071941Y850459D03*
Y843766D03*
Y837074D03*
X1079383Y863845D03*
Y853806D03*
X1071941Y867192D03*
Y857152D03*
X1079383Y883924D03*
Y877231D03*
Y870538D03*
X1071941Y880577D03*
Y873885D03*
X1079383Y900656D03*
Y890617D03*
X1071941Y893963D03*
Y887270D03*
X1079383Y914042D03*
Y907349D03*
X1071941Y917389D03*
Y910696D03*
Y904003D03*
X1079383Y927428D03*
Y920735D03*
X1071941Y930774D03*
Y924081D03*
X1079383Y944160D03*
Y937467D03*
X1071941Y947507D03*
Y940814D03*
X1079383Y960892D03*
Y950853D03*
X1071941Y964239D03*
Y954200D03*
X1079383Y980971D03*
Y974278D03*
Y967585D03*
X1071941Y977625D03*
Y970932D03*
X1079383Y987664D03*
X1071941Y991011D03*
Y984318D03*
X1079383Y1027822D03*
Y1017782D03*
X1071941Y1031168D03*
Y1024475D03*
Y1017782D03*
X1079383Y1047900D03*
Y1041207D03*
Y1034515D03*
X1071941Y1044554D03*
Y1037861D03*
X1079383Y1061286D03*
Y1054593D03*
X1071941Y1057940D03*
Y1051247D03*
X1079383Y1074672D03*
Y1067979D03*
X1071941Y1078018D03*
Y1071326D03*
Y1064633D03*
X1079383Y1091404D03*
Y1084711D03*
X1071941Y1094751D03*
Y1088058D03*
X1079383Y1111483D03*
Y1104790D03*
Y1098097D03*
X1071941Y1108137D03*
Y1101444D03*
X1079383Y1128215D03*
Y1121522D03*
X1071941Y1124869D03*
Y1114829D03*
X1079383Y1141601D03*
Y1134908D03*
X1071941Y1144948D03*
Y1138255D03*
Y1131562D03*
X1079383Y1158333D03*
Y1148294D03*
X1071941Y1161680D03*
Y1151641D03*
X1079383Y1171719D03*
Y1165026D03*
X1071941Y1175066D03*
Y1168373D03*
X1079383Y1185105D03*
Y1178412D03*
X1071941Y1188452D03*
Y1181759D03*
X1079383Y1208530D03*
Y1201837D03*
Y1195144D03*
X1071941Y1205184D03*
Y1198491D03*
X1079383Y1221916D03*
Y1215223D03*
X1071941Y1225263D03*
Y1218570D03*
Y1211877D03*
X1079383Y1238648D03*
Y1231955D03*
X1071941Y1241995D03*
Y1235302D03*
X1071991Y1257262D03*
X1079383Y1245341D03*
X1071941Y1248688D03*
X1085088Y1273344D03*
X1082288D03*
X1092941Y770144D03*
X1101641D03*
X1088083Y766798D03*
X1092941Y783530D03*
X1101641D03*
X1092941Y776837D03*
X1101641D03*
X1088083Y780184D03*
Y773491D03*
X1101641Y800263D03*
X1092941D03*
X1101641Y793570D03*
X1092941D03*
X1088083Y803609D03*
Y796916D03*
Y790223D03*
X1101641Y820341D03*
X1092941D03*
X1101641Y813648D03*
X1092941D03*
X1101641Y806955D03*
X1092941D03*
X1088083Y816995D03*
Y810302D03*
X1101641Y830381D03*
X1092941D03*
X1088083Y833727D03*
Y827034D03*
X1101641Y850459D03*
X1092941D03*
X1101641Y843766D03*
X1092941D03*
X1101641Y837074D03*
X1092941D03*
X1088083Y847113D03*
Y840420D03*
X1101641Y867192D03*
X1092941D03*
X1101641Y857152D03*
X1092941D03*
X1088083Y863845D03*
Y853806D03*
X1101641Y880577D03*
X1092941D03*
X1101641Y873885D03*
X1092941D03*
X1088083Y883924D03*
Y877231D03*
Y870538D03*
X1101641Y893963D03*
X1092941D03*
X1101641Y887270D03*
X1092941D03*
X1088083Y900656D03*
Y890617D03*
X1101641Y917389D03*
X1092941D03*
X1101641Y910696D03*
X1092941D03*
X1101641Y904003D03*
X1092941D03*
X1088083Y914042D03*
Y907349D03*
X1101641Y930774D03*
X1092941D03*
X1101641Y924081D03*
X1092941D03*
X1088083Y927428D03*
Y920735D03*
X1101641Y947507D03*
X1092941D03*
X1101641Y940814D03*
X1092941D03*
X1088083Y944160D03*
Y937467D03*
X1101641Y964239D03*
X1092941D03*
X1101641Y954200D03*
X1092941D03*
X1088083Y960892D03*
Y950853D03*
X1101641Y977625D03*
X1092941D03*
X1101641Y970932D03*
X1092941D03*
X1088083Y980971D03*
Y974278D03*
Y967585D03*
X1101641Y991011D03*
X1092941D03*
X1101641Y984318D03*
X1092941D03*
X1088083Y987664D03*
X1101641Y1031168D03*
X1092941D03*
X1101641Y1024475D03*
X1092941D03*
X1101641Y1017782D03*
X1092941D03*
X1088083Y1027822D03*
Y1017782D03*
X1101641Y1044554D03*
X1092941D03*
X1101641Y1037861D03*
X1092941D03*
X1088083Y1047900D03*
Y1041207D03*
Y1034515D03*
X1101641Y1057940D03*
X1092941D03*
X1101641Y1051247D03*
X1092941D03*
X1088083Y1061286D03*
Y1054593D03*
X1101641Y1078018D03*
X1092941D03*
X1101641Y1071326D03*
X1092941D03*
X1101641Y1064633D03*
X1092941D03*
X1088083Y1074672D03*
Y1067979D03*
X1101641Y1094751D03*
X1092941D03*
X1101641Y1088058D03*
X1092941D03*
X1088083Y1091404D03*
Y1084711D03*
X1101641Y1108137D03*
X1092941D03*
X1101641Y1101444D03*
X1092941D03*
X1088083Y1111483D03*
Y1104790D03*
Y1098097D03*
X1101641Y1124869D03*
X1092941D03*
X1101641Y1114829D03*
X1092941D03*
X1088083Y1128215D03*
Y1121522D03*
X1101641Y1144948D03*
X1092941D03*
X1101641Y1138255D03*
X1092941D03*
X1101641Y1131562D03*
X1092941D03*
X1088083Y1141601D03*
Y1134908D03*
X1092941Y1161680D03*
X1101641D03*
Y1151641D03*
X1092941D03*
X1088083Y1158333D03*
Y1148294D03*
X1101641Y1175066D03*
X1092941D03*
X1101641Y1168373D03*
X1092941D03*
X1088083Y1171719D03*
Y1165026D03*
X1101641Y1181759D03*
X1092941D03*
Y1188452D03*
X1101641D03*
X1088083Y1185105D03*
Y1178412D03*
X1092941Y1205184D03*
X1101641D03*
X1092941Y1198491D03*
X1101641D03*
X1088083Y1208530D03*
Y1201837D03*
Y1195144D03*
X1101641Y1225263D03*
X1092941D03*
X1101641Y1218570D03*
X1092941D03*
Y1211877D03*
X1101641D03*
X1088083Y1221916D03*
Y1215223D03*
X1101641Y1241995D03*
X1092941D03*
X1101641Y1235302D03*
X1092941D03*
X1088083Y1238648D03*
Y1231955D03*
X1101554Y1257102D03*
X1101641Y1248688D03*
X1092941D03*
X1088083Y1245341D03*
X1098788Y1273344D03*
X1095988D03*
X1109083Y766798D03*
X1117783D03*
Y780184D03*
X1109083D03*
X1117783Y773491D03*
X1109083D03*
X1117783Y803609D03*
X1109083D03*
X1117783Y796916D03*
X1109083D03*
Y790223D03*
X1117783D03*
Y816995D03*
X1109083D03*
X1117783Y810302D03*
X1109083D03*
X1117783Y833727D03*
X1109083D03*
X1117783Y827034D03*
X1109083D03*
X1117783Y847113D03*
X1109083D03*
X1117783Y840420D03*
X1109083D03*
X1117783Y863845D03*
X1109083D03*
X1117783Y853806D03*
X1109083D03*
X1117783Y883924D03*
X1109083D03*
X1117783Y877231D03*
X1109083D03*
X1117783Y870538D03*
X1109083D03*
X1117783Y900656D03*
X1109083D03*
X1117783Y890617D03*
X1109083D03*
X1117783Y914042D03*
X1109083D03*
X1117783Y907349D03*
X1109083D03*
X1117783Y927428D03*
X1109083D03*
X1117783Y920735D03*
X1109083D03*
X1117783Y944160D03*
X1109083D03*
X1117783Y937467D03*
X1109083D03*
X1117783Y960892D03*
X1109083D03*
X1117783Y950853D03*
X1109083D03*
X1117783Y980971D03*
X1109083D03*
X1117783Y974278D03*
X1109083D03*
X1117783Y967585D03*
X1109083D03*
X1117783Y987664D03*
X1109083D03*
X1117783Y1027822D03*
X1109083D03*
X1117783Y1017782D03*
X1109083D03*
X1117783Y1047900D03*
X1109083D03*
X1117783Y1041207D03*
X1109083D03*
X1117783Y1034515D03*
X1109083D03*
X1117783Y1061286D03*
X1109083D03*
X1117783Y1054593D03*
X1109083D03*
X1117783Y1074672D03*
X1109083D03*
X1117783Y1067979D03*
X1109083D03*
X1117783Y1091404D03*
X1109083D03*
X1117783Y1084711D03*
X1109083D03*
X1117783Y1111483D03*
X1109083D03*
X1117783Y1104790D03*
X1109083D03*
X1117783Y1098097D03*
X1109083D03*
X1117783Y1128215D03*
X1109083D03*
X1117783Y1121522D03*
X1109083D03*
X1117783Y1141601D03*
X1109083D03*
X1117783Y1134908D03*
X1109083D03*
X1117783Y1158333D03*
X1109083D03*
X1117783Y1148294D03*
X1109083D03*
X1117783Y1171719D03*
X1109083D03*
X1117783Y1165026D03*
X1109083D03*
X1117783Y1185105D03*
X1109083D03*
X1117783Y1178412D03*
X1109083D03*
X1117783Y1208530D03*
X1109083D03*
X1117783Y1201837D03*
X1109083D03*
X1117783Y1195144D03*
X1109083D03*
X1117783Y1221916D03*
X1109083D03*
X1117783Y1215223D03*
X1109083D03*
X1117783Y1238648D03*
X1109083D03*
X1117783Y1231955D03*
X1109083D03*
X1117783Y1245341D03*
X1109083D03*
X1111988Y1273344D03*
X1114788D03*
X1131341Y770144D03*
X1122641D03*
X1131341Y783530D03*
X1122641D03*
X1131341Y776837D03*
X1122641D03*
X1131341Y800263D03*
X1122641D03*
X1131341Y793570D03*
X1122641D03*
X1131341Y820341D03*
X1122641D03*
X1131341Y813648D03*
X1122641D03*
X1131341Y806955D03*
X1122641D03*
X1131341Y830381D03*
X1122641D03*
X1131341Y850459D03*
X1122641D03*
X1131341Y843766D03*
X1122641D03*
X1131341Y837074D03*
X1122641D03*
X1131341Y867192D03*
X1122641D03*
X1131341Y857152D03*
X1122641D03*
X1131341Y880577D03*
X1122641D03*
X1131341Y873885D03*
X1122641D03*
X1131341Y893963D03*
X1122641D03*
X1131341Y887270D03*
X1122641D03*
X1131341Y917389D03*
X1122641D03*
X1131341Y910696D03*
X1122641D03*
X1131341Y904003D03*
X1122641D03*
X1131341Y930774D03*
X1122641D03*
X1131341Y924081D03*
X1122641D03*
Y947507D03*
X1131341D03*
Y940814D03*
X1122641D03*
X1131341Y964239D03*
X1122641D03*
X1131341Y954200D03*
X1122641D03*
X1131341Y977625D03*
X1122641D03*
X1131341Y970932D03*
X1122641D03*
X1131341Y991011D03*
X1122641D03*
X1131341Y984318D03*
X1122641D03*
X1131341Y1031168D03*
X1122641D03*
X1131341Y1024475D03*
X1122641D03*
X1131341Y1017782D03*
X1122641D03*
X1131341Y1044554D03*
X1122641D03*
X1131341Y1037861D03*
X1122641D03*
X1131341Y1057940D03*
X1122641D03*
X1131341Y1051247D03*
X1122641D03*
X1131341Y1078018D03*
X1122641D03*
X1131341Y1071326D03*
X1122641D03*
X1131341Y1064633D03*
X1122641D03*
X1131341Y1094751D03*
X1122641D03*
X1131341Y1088058D03*
X1122641D03*
X1131341Y1108137D03*
X1122641D03*
X1131341Y1101444D03*
X1122641D03*
X1131341Y1124869D03*
X1122641D03*
X1131341Y1114829D03*
X1122641D03*
X1131341Y1144948D03*
X1122641D03*
X1131341Y1138255D03*
X1122641D03*
X1131341Y1131562D03*
X1122641D03*
X1131341Y1161680D03*
X1122641D03*
X1131341Y1151641D03*
X1122641D03*
X1131341Y1175066D03*
X1122641D03*
X1131341Y1168373D03*
X1122641D03*
X1131341Y1188452D03*
X1122641D03*
X1131341Y1181759D03*
X1122641D03*
X1131341Y1205184D03*
X1122641D03*
X1131341Y1198491D03*
X1122641D03*
X1131341Y1225263D03*
X1122641D03*
X1131341Y1218570D03*
X1122641D03*
X1131341Y1211877D03*
X1122641D03*
X1131341Y1241995D03*
X1122641D03*
X1131341Y1235302D03*
X1122641D03*
X1131434Y1257291D03*
X1122641Y1248688D03*
X1131341D03*
X1126188Y1273344D03*
X1128988D03*
X1152341Y770144D03*
X1147483Y766798D03*
X1138783D03*
X1152341Y783530D03*
Y776837D03*
X1147483Y780184D03*
X1138783D03*
Y773491D03*
X1147483D03*
X1152341Y800263D03*
X1147483Y803609D03*
X1138783D03*
X1152341Y793570D03*
X1147483Y796916D03*
X1138783D03*
X1147483Y790223D03*
X1138783D03*
X1152341Y820341D03*
X1147483Y816995D03*
X1138783D03*
X1152341Y813648D03*
Y806955D03*
X1147483Y810302D03*
X1138783D03*
X1147483Y833727D03*
X1138783D03*
X1152341Y830381D03*
X1147483Y827034D03*
X1138783D03*
X1152341Y850459D03*
Y843766D03*
Y837074D03*
X1147483Y847113D03*
X1138783D03*
X1147483Y840420D03*
X1138783D03*
X1152341Y867192D03*
Y857152D03*
X1147483Y863845D03*
X1138783D03*
X1147483Y853806D03*
X1138783D03*
X1152341Y880577D03*
Y873885D03*
X1147483Y883924D03*
X1138783D03*
X1147483Y877231D03*
X1138783D03*
X1147483Y870538D03*
X1138783D03*
X1152341Y893963D03*
Y887270D03*
X1138783Y900656D03*
X1147483D03*
X1138783Y890617D03*
X1147483D03*
X1152341Y917389D03*
Y910696D03*
Y904003D03*
X1147483Y914042D03*
X1138783D03*
X1147483Y907349D03*
X1138783D03*
X1152341Y930774D03*
Y924081D03*
X1147483Y927428D03*
X1138783D03*
X1147483Y920735D03*
X1138783D03*
X1152341Y947507D03*
Y940814D03*
X1147483Y944160D03*
X1138783D03*
X1147483Y937467D03*
X1138783D03*
X1152341Y964239D03*
Y954200D03*
X1147483Y960892D03*
X1138783D03*
X1147483Y950853D03*
X1138783D03*
X1152341Y977625D03*
Y970932D03*
X1147483Y980971D03*
X1138783D03*
X1147483Y974278D03*
X1138783D03*
X1147483Y967585D03*
X1138783D03*
X1152341Y991011D03*
Y984318D03*
X1147483Y987664D03*
X1138783D03*
X1152341Y1031168D03*
Y1024475D03*
Y1017782D03*
X1147483Y1027822D03*
X1138783D03*
X1147483Y1017782D03*
X1138783D03*
X1152341Y1044554D03*
Y1037861D03*
X1138783Y1047900D03*
X1147483D03*
Y1041207D03*
X1138783D03*
X1147483Y1034515D03*
X1138783D03*
X1152341Y1057940D03*
Y1051247D03*
X1147483Y1061286D03*
X1138783D03*
X1147483Y1054593D03*
X1138783D03*
X1152341Y1078018D03*
Y1071326D03*
Y1064633D03*
X1147483Y1074672D03*
X1138783D03*
X1147483Y1067979D03*
X1138783D03*
X1152341Y1094751D03*
Y1088058D03*
X1147483Y1091404D03*
X1138783D03*
X1147483Y1084711D03*
X1138783D03*
X1152341Y1108137D03*
Y1101444D03*
X1147483Y1111483D03*
X1138783D03*
X1147483Y1104790D03*
X1138783D03*
X1147483Y1098097D03*
X1138783D03*
X1152341Y1124869D03*
Y1114829D03*
X1147483Y1128215D03*
X1138783D03*
X1147483Y1121522D03*
X1138783D03*
X1152341Y1144948D03*
Y1138255D03*
Y1131562D03*
X1147483Y1141601D03*
X1138783D03*
X1147483Y1134908D03*
X1138783D03*
X1152341Y1161680D03*
Y1151641D03*
X1147483Y1158333D03*
X1138783D03*
Y1148294D03*
X1147483D03*
X1152341Y1175066D03*
Y1168373D03*
X1147483Y1171719D03*
X1138783D03*
X1147483Y1165026D03*
X1138783D03*
X1152341Y1188452D03*
Y1181759D03*
X1147483Y1185105D03*
X1138783D03*
X1147483Y1178412D03*
X1138783D03*
X1152341Y1205184D03*
Y1198491D03*
X1147483Y1208530D03*
X1138783D03*
X1147483Y1201837D03*
X1138783D03*
X1147483Y1195144D03*
X1138783D03*
X1152341Y1225263D03*
Y1218570D03*
Y1211877D03*
X1147483Y1221916D03*
X1138783D03*
X1147483Y1215223D03*
X1138783D03*
X1152341Y1241995D03*
Y1235302D03*
X1147483Y1238648D03*
X1138783D03*
X1147483Y1231955D03*
X1138783D03*
X1152341Y1248688D03*
X1147483Y1245341D03*
X1138783D03*
X1152381Y1269684D03*
X1147681D03*
X1138201Y1270277D03*
X1168483Y766798D03*
X1161041Y770144D03*
X1168483Y780184D03*
Y773491D03*
X1161041Y783530D03*
Y776837D03*
X1168483Y803609D03*
Y796916D03*
Y790223D03*
X1161041Y800263D03*
Y793570D03*
X1168483Y816995D03*
Y810302D03*
X1161041Y820341D03*
Y813648D03*
Y806955D03*
X1168483Y833727D03*
X1167633Y827034D03*
X1161041Y830381D03*
X1168483Y847113D03*
Y840420D03*
X1161041Y850459D03*
Y843766D03*
Y837074D03*
X1167633Y863845D03*
X1161041Y867192D03*
X1168483Y853806D03*
X1161041Y857152D03*
X1168483Y883924D03*
Y877231D03*
Y870538D03*
X1161041Y880577D03*
Y873885D03*
X1168483Y900656D03*
Y890617D03*
X1161041Y893963D03*
Y887270D03*
X1168483Y914042D03*
Y907349D03*
X1161041Y917389D03*
Y910696D03*
Y904003D03*
X1167633Y927428D03*
X1168483Y920735D03*
X1161041Y930774D03*
Y924081D03*
X1168483Y937467D03*
Y944160D03*
X1161041Y947507D03*
Y940814D03*
X1168483Y960892D03*
Y950853D03*
X1161041Y964239D03*
Y954200D03*
X1168483Y974278D03*
Y980971D03*
Y967585D03*
X1161041Y977625D03*
Y970932D03*
X1168483Y987664D03*
X1161041Y991011D03*
Y984318D03*
X1168483Y1027822D03*
Y1017782D03*
X1161041Y1031168D03*
Y1024475D03*
Y1017782D03*
X1168483Y1047900D03*
Y1041207D03*
Y1034515D03*
X1161041Y1044554D03*
Y1037861D03*
X1168483Y1054593D03*
Y1061286D03*
X1161041Y1057940D03*
Y1051247D03*
X1168483Y1074672D03*
Y1067979D03*
X1161041Y1078018D03*
Y1071326D03*
Y1064633D03*
X1168483Y1091404D03*
X1167633Y1084711D03*
X1161041Y1094751D03*
Y1088058D03*
X1168483Y1111483D03*
Y1104790D03*
Y1098097D03*
X1161041Y1108137D03*
Y1101444D03*
X1168483Y1128215D03*
Y1121522D03*
X1161041Y1124869D03*
Y1114829D03*
X1168483Y1141601D03*
Y1134908D03*
X1161041Y1144948D03*
Y1138255D03*
Y1131562D03*
X1167633Y1158333D03*
X1168483Y1148294D03*
X1161041Y1161680D03*
Y1151641D03*
X1168483Y1171719D03*
Y1165026D03*
X1161041Y1175066D03*
Y1168373D03*
X1168483Y1185105D03*
Y1178412D03*
X1161041Y1188452D03*
Y1181759D03*
X1168483Y1208530D03*
Y1201837D03*
Y1195144D03*
X1161041Y1205184D03*
Y1198491D03*
X1168483Y1221916D03*
Y1215223D03*
X1161041Y1225263D03*
Y1218570D03*
Y1211877D03*
X1168483Y1238648D03*
X1167633Y1231955D03*
X1161041Y1241995D03*
Y1235302D03*
X1161065Y1258871D03*
X1168483Y1245341D03*
X1161041Y1248688D03*
X1161781Y1269684D03*
X1182041Y770144D03*
X1177183Y766798D03*
X1182041Y783530D03*
Y776837D03*
X1177183Y780184D03*
Y773491D03*
X1182041Y800263D03*
Y793570D03*
X1177183Y803609D03*
Y796916D03*
Y790223D03*
X1182041Y813648D03*
Y806955D03*
X1181191Y820341D03*
X1177183Y816995D03*
Y810302D03*
X1181191Y830381D03*
X1177183Y833727D03*
Y827034D03*
X1182041Y850459D03*
Y837074D03*
Y843766D03*
X1177183Y847113D03*
Y840420D03*
X1181191Y867192D03*
X1177183Y863845D03*
X1181191Y857152D03*
X1177183Y853806D03*
X1182041Y873885D03*
Y880577D03*
X1177183Y883924D03*
Y877231D03*
Y870538D03*
X1182041Y893963D03*
Y887270D03*
X1177183Y900656D03*
Y890617D03*
X1182041Y917389D03*
Y910696D03*
Y904003D03*
X1177183Y914042D03*
Y907349D03*
X1181191Y930774D03*
Y924081D03*
X1177183Y927428D03*
Y920735D03*
X1182041Y940814D03*
Y947507D03*
X1177183Y937467D03*
Y944160D03*
X1182041Y964239D03*
Y954200D03*
X1177183Y960892D03*
Y950853D03*
X1182041Y970932D03*
Y977625D03*
X1177183Y974278D03*
Y980971D03*
Y967585D03*
X1182041Y991011D03*
Y984318D03*
X1177183Y987664D03*
X1182041Y1031168D03*
Y1017782D03*
Y1024475D03*
X1177183Y1027822D03*
Y1017782D03*
X1182041Y1044554D03*
Y1037861D03*
X1177183Y1047900D03*
Y1041207D03*
Y1034515D03*
X1182041Y1057940D03*
Y1051247D03*
X1177183Y1054593D03*
Y1061286D03*
X1181191Y1078018D03*
X1182041Y1071326D03*
Y1064633D03*
X1177183Y1074672D03*
Y1067979D03*
X1182041Y1094751D03*
X1181191Y1088058D03*
X1177183Y1091404D03*
Y1084711D03*
X1182041Y1101444D03*
Y1108137D03*
X1177183Y1111483D03*
Y1104790D03*
Y1098097D03*
X1182041Y1114829D03*
Y1124869D03*
X1177183Y1128215D03*
Y1121522D03*
X1182041Y1144948D03*
Y1138255D03*
Y1131562D03*
X1177183Y1141601D03*
Y1134908D03*
X1181191Y1161680D03*
Y1151641D03*
X1177183Y1158333D03*
Y1148294D03*
X1182041Y1168373D03*
Y1175066D03*
X1177183Y1171719D03*
Y1165026D03*
X1182041Y1188452D03*
Y1181759D03*
X1177183Y1185105D03*
Y1178412D03*
X1182041Y1205184D03*
Y1198491D03*
X1177183Y1208530D03*
Y1201837D03*
Y1195144D03*
X1181191Y1225263D03*
X1182041Y1211877D03*
Y1218570D03*
X1177183Y1221916D03*
Y1215223D03*
X1182041Y1241995D03*
X1181191Y1235302D03*
X1177183Y1238648D03*
Y1231955D03*
X1182041Y1248688D03*
X1177183Y1245341D03*
X1176867Y1270029D03*
X1198183Y766798D03*
X1190741Y770144D03*
X1198183Y780184D03*
Y773491D03*
X1190741Y783530D03*
Y776837D03*
X1198183Y803609D03*
Y796916D03*
Y790223D03*
X1190741Y800263D03*
Y793570D03*
X1197333Y816995D03*
X1198183Y810302D03*
X1190741Y813648D03*
Y806955D03*
X1191591Y820341D03*
X1198183Y833727D03*
X1197333Y827034D03*
X1191591Y830381D03*
X1198183Y847113D03*
Y840420D03*
X1190741Y850459D03*
Y837074D03*
Y843766D03*
X1197333Y863845D03*
X1191591Y867192D03*
X1198183Y853806D03*
X1191591Y857152D03*
X1198183Y877231D03*
X1197333Y870538D03*
X1198183Y883924D03*
X1190741Y873885D03*
Y880577D03*
X1198183Y900656D03*
Y890617D03*
X1190741Y893963D03*
Y887270D03*
X1198183Y914042D03*
Y907349D03*
X1190741Y917389D03*
Y910696D03*
Y904003D03*
X1197383Y927428D03*
X1198183Y920735D03*
X1191591Y930774D03*
Y924081D03*
X1198183Y944160D03*
X1197333Y937467D03*
X1190741Y940814D03*
Y947507D03*
X1198183Y960892D03*
Y950853D03*
X1190741Y964239D03*
Y954200D03*
X1198183Y980971D03*
Y974278D03*
Y967585D03*
X1190741Y970932D03*
Y977625D03*
X1198183Y987664D03*
X1190741Y991011D03*
Y984318D03*
X1198183Y1027822D03*
Y1017782D03*
X1190741Y1031168D03*
Y1017782D03*
Y1024475D03*
X1198183Y1047900D03*
Y1041207D03*
Y1034515D03*
X1190741Y1044554D03*
Y1037861D03*
X1198183Y1054593D03*
Y1061286D03*
X1190741Y1057940D03*
Y1051247D03*
X1197333Y1074672D03*
X1198183Y1067979D03*
X1191591Y1078018D03*
X1190741Y1071326D03*
Y1064633D03*
X1198183Y1091404D03*
X1197333Y1084711D03*
X1190741Y1094751D03*
X1191591Y1088058D03*
X1198183Y1111483D03*
Y1098097D03*
Y1104790D03*
X1190741Y1101444D03*
Y1108137D03*
X1198183Y1128215D03*
Y1121522D03*
X1190741Y1114829D03*
Y1124869D03*
X1198183Y1141601D03*
X1197333Y1134908D03*
X1190741Y1144948D03*
Y1138255D03*
Y1131562D03*
X1198183Y1158333D03*
X1197333Y1148294D03*
X1191591Y1161680D03*
Y1151641D03*
X1198183Y1165026D03*
Y1171719D03*
X1190741Y1168373D03*
Y1175066D03*
X1198183Y1185105D03*
Y1178412D03*
X1190741Y1188452D03*
Y1181759D03*
X1198183Y1208530D03*
Y1201837D03*
Y1195144D03*
X1190741Y1205184D03*
Y1198491D03*
X1198183Y1221916D03*
Y1215223D03*
X1191591Y1225263D03*
X1190741Y1211877D03*
Y1218570D03*
X1197333Y1238648D03*
Y1231955D03*
X1190741Y1241995D03*
X1191591Y1235302D03*
X1198183Y1245341D03*
X1190966Y1258711D03*
X1190741Y1248688D03*
X1191538Y1270004D03*
X1194572Y1578182D03*
Y1590094D03*
X1199872Y1614292D03*
Y1602380D03*
X1211741Y770144D03*
X1206883Y766798D03*
X1211741Y783530D03*
Y776837D03*
X1206883Y780184D03*
Y773491D03*
X1211741Y800263D03*
Y793570D03*
X1206883Y803609D03*
Y796916D03*
Y790223D03*
X1210891Y820341D03*
Y813648D03*
X1211741Y806955D03*
X1207148Y817554D03*
X1206883Y810302D03*
X1211741Y830381D03*
X1206883Y833727D03*
X1207733Y827034D03*
X1211741Y850459D03*
Y837074D03*
Y843766D03*
X1206883Y847113D03*
Y840420D03*
X1210891Y867492D03*
X1207733Y863845D03*
X1210891Y857152D03*
X1206883Y853806D03*
X1211741Y874185D03*
Y880577D03*
X1206883Y877231D03*
X1207201Y871084D03*
X1206883Y883924D03*
X1211741Y893963D03*
Y887270D03*
X1206883Y900656D03*
Y890617D03*
X1211741Y917389D03*
Y910696D03*
Y904003D03*
X1206883Y914042D03*
Y907349D03*
X1211741Y930774D03*
Y924081D03*
X1207683Y927428D03*
X1206883Y920735D03*
X1211741Y947507D03*
X1211001Y940814D03*
X1206883Y944660D03*
X1207733Y937467D03*
X1211741Y964239D03*
Y954200D03*
X1206883Y960892D03*
Y950853D03*
X1211741Y977625D03*
Y970932D03*
X1206883Y980971D03*
Y974278D03*
Y967585D03*
X1211741Y991011D03*
X1206883Y987664D03*
X1211741Y984318D03*
Y1031168D03*
X1206883Y1027822D03*
Y1017782D03*
X1211741D03*
Y1024475D03*
Y1044554D03*
Y1037861D03*
X1206883Y1047900D03*
Y1041207D03*
Y1034515D03*
X1211741Y1051247D03*
Y1057940D03*
X1206883Y1054593D03*
Y1061286D03*
X1210891Y1078018D03*
X1211741Y1064633D03*
Y1071326D03*
X1207733Y1074672D03*
X1206883Y1067979D03*
X1211741Y1094751D03*
X1210891Y1088058D03*
X1206883Y1091404D03*
Y1084711D03*
X1211741Y1108137D03*
Y1101444D03*
X1206883Y1111483D03*
Y1098097D03*
Y1104790D03*
X1210891Y1124869D03*
X1211741Y1114829D03*
X1206883Y1128215D03*
Y1121522D03*
X1211741Y1144948D03*
Y1138255D03*
X1210891Y1131562D03*
X1206883Y1141601D03*
X1207733Y1134908D03*
X1211741Y1151641D03*
Y1161680D03*
X1206883Y1158333D03*
X1207733Y1148294D03*
X1211741Y1175066D03*
Y1168373D03*
X1206883Y1165026D03*
Y1171719D03*
X1211741Y1188452D03*
Y1181759D03*
X1206883Y1185105D03*
Y1178412D03*
X1211741Y1205184D03*
Y1198491D03*
X1206883Y1208530D03*
Y1201837D03*
Y1195144D03*
X1210891Y1225263D03*
X1211741Y1218570D03*
Y1211877D03*
X1206883Y1221916D03*
Y1215223D03*
X1211741Y1241995D03*
X1211328Y1234977D03*
X1207733Y1238648D03*
Y1231955D03*
X1206883Y1245341D03*
X1211741Y1248688D03*
X1204608Y1273119D03*
X1202043Y1273123D03*
X1202372Y1578182D03*
X1214432D03*
X1206632D03*
X1202372Y1590094D03*
X1214432D03*
X1206632D03*
X1207672Y1602380D03*
Y1614292D03*
X1211932D03*
Y1602380D03*
X1227883Y766798D03*
X1220441Y770144D03*
X1227883Y780184D03*
Y773491D03*
X1220441Y783530D03*
Y776837D03*
X1227883Y803609D03*
Y796916D03*
Y790223D03*
X1220441Y800263D03*
Y793570D03*
X1227033Y816995D03*
X1227883Y810302D03*
X1221291Y820341D03*
Y813648D03*
X1220441Y806955D03*
X1227883Y833727D03*
X1227033Y827034D03*
X1220441Y830381D03*
X1227883Y847113D03*
Y840420D03*
X1220441Y850459D03*
Y837074D03*
Y843766D03*
X1227033Y863845D03*
X1221291Y867192D03*
X1227033Y853806D03*
X1221291Y857152D03*
X1227883Y870538D03*
Y883924D03*
Y877231D03*
X1220441Y873885D03*
Y880577D03*
X1227033Y900656D03*
X1227883Y890617D03*
X1220441Y893963D03*
Y887270D03*
X1227883Y914042D03*
Y907349D03*
X1220441Y917389D03*
Y910696D03*
Y904003D03*
X1227033Y927428D03*
X1227883Y920735D03*
X1221291Y930774D03*
X1220441Y924081D03*
X1227883Y944160D03*
X1227033Y937467D03*
X1220441Y947507D03*
X1221291Y940814D03*
X1227883Y960892D03*
Y950853D03*
X1220441Y964239D03*
Y954200D03*
X1227883Y974278D03*
Y967585D03*
X1220441Y977625D03*
Y970932D03*
X1227883Y980971D03*
Y987664D03*
X1220441Y991011D03*
Y984318D03*
X1227883Y1027822D03*
X1220441Y1031168D03*
X1227883Y1017782D03*
X1220441D03*
Y1024475D03*
X1227883Y1047900D03*
Y1041207D03*
Y1034515D03*
X1220441Y1044554D03*
Y1037861D03*
X1227883Y1061286D03*
Y1054593D03*
X1220441Y1051247D03*
Y1057940D03*
X1227033Y1074672D03*
Y1067979D03*
X1221291Y1078018D03*
X1220441Y1064633D03*
Y1071326D03*
X1227883Y1091404D03*
Y1084711D03*
X1220441Y1094751D03*
X1221291Y1088058D03*
X1227883Y1104790D03*
X1227033Y1111483D03*
X1227883Y1098097D03*
X1220441Y1108137D03*
Y1101444D03*
X1227883Y1128215D03*
X1227033Y1121522D03*
X1221291Y1124869D03*
X1220441Y1114829D03*
X1227883Y1134908D03*
Y1141601D03*
X1220441Y1144948D03*
Y1138255D03*
X1221291Y1131562D03*
X1227883Y1158333D03*
Y1148294D03*
X1220441Y1151641D03*
Y1161680D03*
X1227883Y1171719D03*
Y1165026D03*
X1220441Y1175066D03*
Y1168373D03*
X1227883Y1185105D03*
Y1178412D03*
X1220441Y1188452D03*
Y1181759D03*
X1227883Y1208530D03*
Y1201837D03*
X1227033Y1195144D03*
X1220441Y1205184D03*
Y1198491D03*
X1227033Y1221916D03*
X1227883Y1215223D03*
X1221291Y1225263D03*
X1220441Y1218570D03*
Y1211877D03*
X1227883Y1238648D03*
X1227033Y1231955D03*
X1220441Y1241995D03*
X1221291Y1235302D03*
X1220441Y1248688D03*
X1227883Y1245341D03*
X1220601Y1269684D03*
X1220931Y1260093D03*
X1233327Y1274515D03*
X1231377Y1275855D03*
X1218692Y1578182D03*
X1226492D03*
X1230752D03*
X1218692Y1590094D03*
X1226492D03*
X1230752D03*
X1219732Y1614292D03*
Y1602380D03*
X1231792Y1614292D03*
Y1602380D03*
X1223992D03*
Y1614292D03*
X1236583Y766798D03*
Y780184D03*
Y773491D03*
Y803609D03*
Y796916D03*
Y790223D03*
X1237433Y816995D03*
X1236583Y810302D03*
Y833727D03*
X1237433Y827034D03*
X1236583Y847113D03*
Y840420D03*
X1237433Y863845D03*
Y853806D03*
X1236583Y870538D03*
Y883924D03*
Y877231D03*
Y900656D03*
Y890617D03*
Y914042D03*
Y907349D03*
X1237433Y927428D03*
X1236583Y920735D03*
Y944160D03*
X1237433Y937467D03*
X1236583Y960892D03*
Y950853D03*
Y974278D03*
Y967585D03*
Y980971D03*
Y987664D03*
Y1027822D03*
Y1017782D03*
Y1047900D03*
Y1041207D03*
Y1034515D03*
Y1061286D03*
Y1054593D03*
X1237433Y1074672D03*
Y1067979D03*
X1236583Y1091404D03*
Y1084711D03*
Y1104790D03*
X1237433Y1111483D03*
X1236583Y1098097D03*
Y1128215D03*
X1237433Y1121522D03*
X1236583Y1134908D03*
Y1141601D03*
Y1158333D03*
Y1148294D03*
Y1171719D03*
Y1165026D03*
Y1185105D03*
Y1178412D03*
Y1208530D03*
Y1201837D03*
Y1195144D03*
X1237433Y1221916D03*
X1236583Y1215223D03*
Y1238648D03*
X1237433Y1231955D03*
X1236583Y1245341D03*
X1238552Y1578182D03*
X1242812D03*
X1238552Y1590094D03*
X1242812D03*
X1236052Y1602380D03*
Y1614292D03*
X1243852D03*
Y1602380D03*
X1248112D03*
Y1614292D03*
X1241142Y1675383D03*
Y1679920D03*
X1249016Y1679320D03*
X1241142Y1684454D03*
Y1689556D03*
Y1694093D03*
Y1698627D03*
X1249016Y1688391D03*
Y1693493D03*
Y1698030D03*
Y1683857D03*
X1241142Y1703729D03*
Y1708266D03*
Y1712800D03*
X1249016Y1707666D03*
Y1712203D03*
Y1702564D03*
X1241142Y1726974D03*
Y1722440D03*
Y1717903D03*
X1249016Y1730911D03*
Y1726377D03*
Y1721840D03*
Y1716737D03*
X1250612Y1578182D03*
X1262672D03*
X1254872D03*
X1250612Y1590094D03*
X1262672D03*
X1254872D03*
X1255912Y1614292D03*
Y1602380D03*
X1260172D03*
Y1614292D03*
X1256890Y1675383D03*
Y1679920D03*
X1264764Y1679320D03*
X1256890Y1684454D03*
Y1689556D03*
Y1694093D03*
Y1698627D03*
X1264764Y1688391D03*
Y1693493D03*
Y1698030D03*
Y1683857D03*
X1256890Y1703729D03*
Y1708266D03*
Y1712800D03*
X1264764Y1707666D03*
Y1712203D03*
Y1702564D03*
X1256890Y1726974D03*
Y1722440D03*
Y1717903D03*
X1264764Y1730911D03*
Y1726377D03*
Y1721840D03*
Y1716737D03*
X1266932Y1578182D03*
X1274732D03*
X1278992D03*
X1266932Y1590094D03*
X1274732D03*
X1278992D03*
X1267972Y1614292D03*
Y1602380D03*
X1272232D03*
Y1614292D03*
X1280032D03*
Y1602380D03*
X1272638Y1675383D03*
Y1679920D03*
X1280512Y1679320D03*
X1272638Y1684454D03*
Y1689556D03*
Y1694093D03*
Y1698627D03*
X1280512Y1688391D03*
Y1693493D03*
Y1698030D03*
Y1683857D03*
X1272638Y1703729D03*
Y1708266D03*
Y1712800D03*
X1280512Y1707666D03*
Y1712203D03*
Y1702564D03*
X1272638Y1726974D03*
Y1722440D03*
Y1717903D03*
X1280512Y1730911D03*
Y1726377D03*
Y1721840D03*
Y1716737D03*
X1286792Y1578182D03*
X1298852D03*
X1291052D03*
X1286792Y1590094D03*
X1298852D03*
X1291052D03*
X1284292Y1602380D03*
Y1614292D03*
X1292092D03*
Y1602380D03*
X1296352D03*
Y1614292D03*
X1296260Y1679320D03*
X1288386Y1675383D03*
Y1679920D03*
X1296260Y1688391D03*
Y1693493D03*
Y1698030D03*
Y1683857D03*
X1288386Y1684454D03*
Y1689556D03*
Y1694093D03*
Y1698627D03*
X1296260Y1707666D03*
Y1712203D03*
Y1702564D03*
X1288386Y1703729D03*
Y1708266D03*
Y1712800D03*
X1296260Y1730911D03*
Y1726377D03*
Y1721840D03*
Y1716737D03*
X1288386Y1726974D03*
Y1722440D03*
Y1717903D03*
X1314353Y1124651D03*
X1303112Y1578182D03*
X1310912D03*
X1315172D03*
X1303112Y1590094D03*
X1310912D03*
X1315172D03*
X1304152Y1602380D03*
Y1614292D03*
X1308412Y1602380D03*
Y1614292D03*
X1308071Y1675383D03*
Y1679920D03*
Y1684454D03*
Y1689556D03*
Y1694093D03*
Y1698627D03*
Y1703729D03*
Y1708266D03*
Y1712800D03*
Y1726974D03*
Y1722440D03*
Y1717903D03*
X1328721Y854584D03*
X1323171Y870606D03*
Y889832D03*
X1319849Y1091513D03*
X1318053Y1124651D03*
X1321753Y1131060D03*
X1322972Y1578182D03*
X1327232D03*
X1322972Y1590094D03*
X1327232D03*
X1316212Y1614292D03*
Y1602380D03*
X1328272D03*
Y1614292D03*
X1320472Y1602380D03*
Y1614292D03*
X1323819Y1675383D03*
Y1679920D03*
X1315945Y1679320D03*
X1323819Y1684454D03*
Y1689556D03*
Y1694093D03*
Y1698627D03*
X1315945Y1688391D03*
Y1693493D03*
Y1698030D03*
Y1683857D03*
X1323819Y1703729D03*
Y1708266D03*
Y1712800D03*
X1315945Y1707666D03*
Y1712203D03*
Y1702564D03*
X1323819Y1726974D03*
Y1722440D03*
Y1717903D03*
X1315945Y1730911D03*
Y1726377D03*
Y1721840D03*
Y1716737D03*
X1336121Y880219D03*
Y899445D03*
X1347220D03*
X1336121Y918670D03*
X1341671Y941100D03*
X1336121Y937896D03*
X1347220D03*
X1345804Y1006093D03*
X1342104Y1076587D03*
X1335032Y1578182D03*
X1347092D03*
X1339292D03*
X1335032Y1590094D03*
X1347092D03*
X1339292D03*
X1340332Y1602380D03*
Y1614292D03*
X1332532Y1602380D03*
Y1614292D03*
X1344592Y1602380D03*
Y1614292D03*
X1339567Y1675383D03*
Y1679920D03*
X1331693Y1679320D03*
X1347441D03*
X1339567Y1684454D03*
Y1689556D03*
Y1694093D03*
Y1698627D03*
X1331693Y1688391D03*
Y1693493D03*
Y1698030D03*
Y1683857D03*
X1347441Y1688391D03*
Y1693493D03*
Y1698030D03*
Y1683857D03*
X1339567Y1703729D03*
Y1708266D03*
Y1712800D03*
X1331693Y1707666D03*
Y1712203D03*
Y1702564D03*
X1347441Y1707666D03*
Y1712203D03*
Y1702564D03*
X1339567Y1726974D03*
Y1722440D03*
Y1717903D03*
X1331693Y1730911D03*
Y1726377D03*
Y1721840D03*
Y1716737D03*
X1347441Y1730911D03*
Y1726377D03*
Y1721840D03*
Y1716737D03*
X1354620Y931488D03*
X1355053Y1060565D03*
X1351352Y1578182D03*
X1359152D03*
X1363412D03*
X1351352Y1590094D03*
X1359152D03*
X1363412D03*
X1352392Y1602380D03*
Y1614292D03*
X1356652Y1602380D03*
Y1614292D03*
X1363189Y1679320D03*
X1355315Y1675383D03*
Y1679920D03*
X1363189Y1688391D03*
Y1693493D03*
Y1698030D03*
Y1683857D03*
X1355315Y1684454D03*
Y1689556D03*
Y1694093D03*
Y1698627D03*
X1363189Y1707666D03*
Y1712203D03*
Y1702564D03*
X1355315Y1703729D03*
Y1708266D03*
Y1712800D03*
X1363189Y1730911D03*
Y1726377D03*
Y1721840D03*
Y1716737D03*
X1355315Y1726974D03*
Y1722440D03*
Y1717903D03*
X1373120Y899445D03*
Y931488D03*
Y937896D03*
X1371212Y1578088D03*
X1375472Y1578182D03*
X1371212Y1590094D03*
X1375472D03*
X1364452Y1602380D03*
Y1614292D03*
X1376512Y1602286D03*
Y1614292D03*
X1368712Y1602380D03*
Y1614292D03*
X1393716Y985579D03*
X1391326D03*
Y1014539D03*
X1393716D03*
X1393903Y1115039D03*
X1392053Y1118243D03*
X1390203Y1121447D03*
X1388353Y1124651D03*
Y1118243D03*
X1390204Y1134264D03*
X1388354Y1131060D03*
X1383272Y1578182D03*
Y1590094D03*
X1380772Y1602380D03*
Y1614292D03*
X1388572D03*
Y1602380D03*
X1411971Y851380D03*
Y864197D03*
Y877014D03*
Y889832D03*
Y902649D03*
X1404571Y921875D03*
X1410121Y944304D03*
Y957122D03*
Y950713D03*
Y963530D03*
Y976347D03*
Y969939D03*
Y982756D03*
X1410553Y1009297D03*
Y1002888D03*
Y1028523D03*
Y1022114D03*
Y1015705D03*
X1405004Y1044544D03*
X1410553Y1034931D03*
X1406854Y1047749D03*
X1399453D03*
X1408703Y1050952D03*
X1401304Y1057361D03*
X1410553Y1060565D03*
Y1054157D03*
X1408703Y1076587D03*
X1406853Y1073383D03*
X1403153D03*
Y1066974D03*
X1401304Y1076587D03*
X1399453Y1066974D03*
X1410553Y1073383D03*
Y1066974D03*
X1403154Y1079791D03*
X1410553D03*
X1408703Y1089404D03*
Y1082995D03*
X1405003D03*
X1401304Y1089404D03*
X1410553Y1092608D03*
Y1086200D03*
X1408703Y1095813D03*
X1405003D03*
X1403153Y1099017D03*
X1401303Y1102221D03*
X1399453Y1105426D03*
X1397604Y1108630D03*
X1410553Y1105426D03*
X1399453Y1111834D03*
X1410553D03*
X1399453Y1124651D03*
Y1118243D03*
X1397604Y1115039D03*
X1410553Y1124651D03*
Y1118243D03*
X1399454Y1137469D03*
X1399453Y1131060D03*
X1410554Y1137769D03*
X1410553Y1131060D03*
X1426771Y851380D03*
Y877014D03*
X1413820Y912262D03*
X1423070Y941100D03*
X1423071Y947509D03*
Y960326D03*
Y953917D03*
Y966735D03*
Y979552D03*
Y973143D03*
X1423503Y1006093D03*
Y999684D03*
Y1012501D03*
Y1025318D03*
Y1018910D03*
Y1031727D03*
X1429053Y1041340D03*
X1423503Y1038136D03*
X1429053Y1092608D03*
X1427204Y1089404D03*
X1427203Y1095812D03*
X1429053Y1099017D03*
X1423503Y1108630D03*
Y1102221D03*
Y1121447D03*
Y1115039D03*
Y1127856D03*
Y1134264D03*
X1432320Y912262D03*
X1437871Y921875D03*
X1438402Y942151D03*
X1440702D03*
X1443002D03*
X1430564Y949138D03*
X1440015Y956539D03*
X1430564Y951438D03*
X1442413Y956539D03*
X1430534Y963828D03*
Y966128D03*
X1440015Y971139D03*
X1442413Y971099D03*
X1430404Y981208D03*
Y978908D03*
X1440015Y985579D03*
X1430604Y995298D03*
Y992998D03*
X1442413Y985579D03*
X1440015Y1014539D03*
Y1000059D03*
X1430584Y1009408D03*
Y1007108D03*
X1442413Y1014539D03*
Y1000059D03*
X1436454Y1105426D03*
X1434604Y1102221D03*
X1432753Y1099017D03*
X1440154Y1105426D03*
X1438304Y1108630D03*
X1440154Y1111834D03*
X1434604Y1121447D03*
Y1115039D03*
X1443854Y1124651D03*
X1443853Y1118243D03*
X1442004Y1121447D03*
Y1115039D03*
X1434604Y1127856D03*
Y1134264D03*
X1450820Y899445D03*
Y912262D03*
X1445703Y1115039D03*
X1447553Y1118243D03*
X1445704Y1127856D03*
X1445703Y1140973D03*
X1447554Y1137469D03*
Y1131060D03*
X1460095Y1578182D03*
Y1590094D03*
X1465620Y912262D03*
X1471604Y1108630D03*
X1469753Y1111834D03*
X1472155Y1578182D03*
X1467895D03*
X1472155Y1590094D03*
X1467895D03*
X1477455Y1602380D03*
Y1614292D03*
X1473195D03*
Y1602380D03*
X1465395D03*
Y1614292D03*
X1484120Y937896D03*
X1485971Y947509D03*
X1491953Y1086200D03*
X1492015Y1578182D03*
X1484215D03*
X1479955D03*
X1492015Y1590094D03*
X1484215D03*
X1479955D03*
X1489515Y1614292D03*
Y1602380D03*
X1485255D03*
Y1614292D03*
X1508335Y1578182D03*
X1496275D03*
X1504075D03*
X1508335Y1590094D03*
X1496275D03*
X1504075D03*
X1501575Y1614292D03*
Y1602380D03*
X1509375D03*
Y1614292D03*
X1497315Y1602380D03*
Y1614292D03*
X1505315Y1675383D03*
Y1679920D03*
Y1684454D03*
Y1689556D03*
Y1694093D03*
Y1698627D03*
Y1703729D03*
Y1708266D03*
Y1712800D03*
Y1726974D03*
Y1722440D03*
Y1717903D03*
X1511871Y928283D03*
X1519271D03*
X1515571D03*
X1524820Y925079D03*
X1513720D03*
X1524820Y944304D03*
X1513720D03*
X1520395Y1578182D03*
X1516135D03*
X1520395Y1590094D03*
X1516135D03*
X1525695Y1614292D03*
Y1602380D03*
X1521435D03*
Y1614292D03*
X1513635D03*
Y1602380D03*
X1521063Y1675383D03*
Y1679920D03*
X1513189Y1679320D03*
X1521063Y1684454D03*
Y1689556D03*
Y1694093D03*
Y1698627D03*
X1513189Y1688391D03*
Y1693493D03*
Y1698030D03*
Y1683857D03*
X1521063Y1703729D03*
Y1708266D03*
Y1712800D03*
X1513189Y1707666D03*
Y1712203D03*
Y1702564D03*
X1521063Y1726974D03*
Y1722440D03*
Y1717903D03*
X1513189Y1730911D03*
Y1726377D03*
Y1721840D03*
Y1716737D03*
X1540255Y1578182D03*
X1532455D03*
X1528195D03*
X1540255Y1590094D03*
X1532455D03*
X1528195D03*
X1537755Y1614292D03*
Y1602380D03*
X1533495D03*
Y1614292D03*
X1536811Y1675383D03*
Y1679920D03*
X1528937Y1679320D03*
X1536811Y1684454D03*
Y1689556D03*
Y1694093D03*
Y1698627D03*
X1528937Y1688391D03*
Y1693493D03*
Y1698030D03*
Y1683857D03*
X1536811Y1703729D03*
Y1708266D03*
Y1712800D03*
X1528937Y1707666D03*
Y1712203D03*
Y1702564D03*
X1536811Y1726974D03*
Y1722440D03*
Y1717903D03*
X1528937Y1730911D03*
Y1726377D03*
Y1721840D03*
Y1716737D03*
X1556575Y1578182D03*
X1544515D03*
X1552315D03*
X1556575Y1590094D03*
X1544515D03*
X1552315D03*
X1549815Y1614292D03*
Y1602380D03*
X1557615D03*
Y1614292D03*
X1545555Y1602380D03*
Y1614292D03*
X1552559Y1675383D03*
Y1679920D03*
X1544685Y1679320D03*
X1552559Y1684454D03*
Y1689556D03*
Y1694093D03*
Y1698627D03*
X1544685Y1688391D03*
Y1693493D03*
Y1698030D03*
Y1683857D03*
X1552559Y1703729D03*
Y1708266D03*
Y1712800D03*
X1544685Y1707666D03*
Y1712203D03*
Y1702564D03*
X1552559Y1726974D03*
Y1722440D03*
Y1717903D03*
X1544685Y1730911D03*
Y1726377D03*
Y1721840D03*
Y1716737D03*
X1568635Y1578182D03*
X1564375D03*
X1568635Y1590094D03*
X1564375D03*
X1573935Y1614292D03*
Y1602380D03*
X1569675Y1614292D03*
Y1602380D03*
X1561875Y1614292D03*
Y1602380D03*
X1560433Y1679320D03*
X1572244Y1675383D03*
Y1679920D03*
X1560433Y1688391D03*
Y1693493D03*
Y1698030D03*
Y1683857D03*
X1572244Y1684454D03*
Y1689556D03*
Y1694093D03*
Y1698627D03*
X1560433Y1707666D03*
Y1712203D03*
Y1702564D03*
X1572244Y1703729D03*
Y1708266D03*
Y1712800D03*
X1560433Y1730911D03*
Y1726377D03*
Y1721840D03*
Y1716737D03*
X1572244Y1726974D03*
Y1722440D03*
Y1717903D03*
X1588495Y1578182D03*
X1580695D03*
X1576435D03*
X1588495Y1590094D03*
X1580695D03*
X1576435D03*
X1585995Y1614292D03*
Y1602380D03*
X1581735D03*
Y1614292D03*
X1587992Y1675383D03*
Y1679920D03*
X1580118Y1679320D03*
X1587992Y1684454D03*
Y1689556D03*
Y1694093D03*
Y1698627D03*
X1580118Y1688391D03*
Y1693493D03*
Y1698030D03*
Y1683857D03*
X1587992Y1703729D03*
Y1708266D03*
Y1712800D03*
X1580118Y1707666D03*
Y1712203D03*
Y1702564D03*
X1587992Y1726974D03*
Y1722440D03*
Y1717903D03*
X1580118Y1730911D03*
Y1726377D03*
Y1721840D03*
Y1716737D03*
X1597041Y770144D03*
X1605741D03*
Y776837D03*
X1597041D03*
X1605741Y783530D03*
X1597041D03*
X1605741Y793570D03*
X1597041D03*
X1596988Y800263D03*
X1605741D03*
X1595774Y806955D03*
X1606934D03*
X1596218Y813648D03*
X1606735D03*
X1597041Y820341D03*
X1605741D03*
X1597041Y830381D03*
X1605741D03*
Y837074D03*
X1597041D03*
Y843766D03*
X1605741D03*
X1596147Y850459D03*
X1606896D03*
X1596200Y857152D03*
X1606623D03*
X1597041Y867192D03*
X1605741D03*
X1597041Y873885D03*
X1605741D03*
X1597041Y880577D03*
X1605741D03*
X1597041Y887270D03*
X1605741D03*
X1606898Y893963D03*
X1597041D03*
X1605741Y904003D03*
X1597041D03*
Y917389D03*
X1605741D03*
X1597041Y910696D03*
X1605741D03*
X1597041Y924081D03*
X1605741D03*
X1606541Y930697D03*
X1596047Y930774D03*
X1596106Y940814D03*
X1606919D03*
X1605741Y947507D03*
X1597041D03*
X1605741Y954200D03*
X1597041D03*
Y964239D03*
X1605741D03*
X1597041Y977625D03*
X1605741D03*
Y970932D03*
X1597041D03*
Y984318D03*
X1605741D03*
X1597041Y991011D03*
X1605741D03*
X1597041Y1024475D03*
X1605741D03*
X1597041Y1017782D03*
X1605741D03*
X1597041Y1031168D03*
X1605741D03*
X1597041Y1037861D03*
X1605741D03*
X1597041Y1044554D03*
X1605741D03*
Y1051247D03*
X1597041D03*
Y1057940D03*
X1605741D03*
X1597041Y1064633D03*
X1605741D03*
X1606541Y1071326D03*
X1596141D03*
X1597041Y1078018D03*
X1605741D03*
Y1094751D03*
X1597041D03*
Y1088058D03*
X1605741D03*
Y1101444D03*
X1597041D03*
Y1108137D03*
X1605741D03*
X1606541Y1114829D03*
X1596241D03*
X1596511Y1124969D03*
X1606505Y1124674D03*
X1605741Y1138255D03*
X1597041D03*
X1605741Y1144948D03*
X1597041D03*
Y1131562D03*
X1605741D03*
Y1151641D03*
X1597041D03*
X1596653Y1161680D03*
X1605975Y1161581D03*
X1605741Y1168373D03*
X1597041D03*
X1605741Y1175066D03*
X1597041D03*
X1605741Y1181759D03*
X1597041D03*
X1606765Y1188452D03*
X1597041D03*
Y1198491D03*
X1605741D03*
Y1205184D03*
X1597041D03*
Y1211877D03*
X1605741D03*
X1597041Y1218570D03*
X1605741D03*
X1597041Y1225263D03*
X1605741D03*
X1607064Y1235302D03*
X1596178D03*
X1605741Y1241995D03*
X1597041D03*
Y1248688D03*
X1605741D03*
X1603788Y1273144D03*
X1601388D03*
X1604815Y1578182D03*
X1592755D03*
X1600555D03*
X1604815Y1590094D03*
X1592755D03*
X1600555D03*
X1598055Y1614292D03*
Y1602380D03*
X1605855Y1614292D03*
Y1602380D03*
X1593795Y1614292D03*
Y1602380D03*
X1603740Y1675383D03*
Y1679920D03*
X1595866Y1679320D03*
X1603740Y1684454D03*
Y1689556D03*
Y1694093D03*
Y1698627D03*
X1595866Y1688391D03*
Y1693493D03*
Y1698030D03*
Y1683857D03*
X1603740Y1703729D03*
Y1708266D03*
Y1712800D03*
X1595866Y1707666D03*
Y1712203D03*
Y1702564D03*
X1603740Y1726974D03*
Y1722440D03*
Y1717903D03*
X1595866Y1730911D03*
Y1726377D03*
Y1721840D03*
Y1716737D03*
X1613183Y766798D03*
X1621883D03*
Y773491D03*
X1613183D03*
X1621883Y780184D03*
X1613183D03*
X1621883Y790223D03*
X1613183D03*
Y796916D03*
X1621883D03*
X1613183Y803609D03*
X1621883D03*
X1622916Y816995D03*
X1613183D03*
X1612363Y810302D03*
X1622986D03*
X1613183Y827034D03*
X1621883D03*
Y833727D03*
X1613183D03*
Y840420D03*
X1621883D03*
X1613183Y847113D03*
X1621943D03*
X1622060Y863845D03*
X1612408D03*
X1612474Y853955D03*
X1622961Y853806D03*
X1621883Y883924D03*
X1613183D03*
Y870538D03*
X1621883D03*
X1613183Y877231D03*
X1621883D03*
X1613183Y890617D03*
X1621883D03*
X1613183Y900656D03*
X1621883D03*
Y907349D03*
X1613183D03*
Y914042D03*
X1621883D03*
Y920735D03*
X1613183D03*
X1622535Y927526D03*
X1612168Y927428D03*
X1622845Y937467D03*
X1612312D03*
X1621883Y944160D03*
X1613183D03*
X1621883Y950853D03*
X1613183D03*
X1621883Y960892D03*
X1613183D03*
Y974278D03*
X1621883D03*
X1613183Y980971D03*
X1621883D03*
X1613183Y967585D03*
X1621883D03*
X1613183Y987664D03*
X1621883D03*
Y1017782D03*
X1613183D03*
Y1027822D03*
X1621883D03*
X1613183Y1034515D03*
X1621883D03*
X1613183Y1041207D03*
X1621883D03*
X1613183Y1047900D03*
X1621883D03*
Y1054593D03*
X1613183D03*
Y1061286D03*
X1621883D03*
Y1067979D03*
X1612983D03*
X1612283Y1074672D03*
X1622683D03*
X1621883Y1084711D03*
X1612383D03*
X1613183Y1091404D03*
X1621883D03*
Y1104790D03*
X1613183D03*
X1621883Y1098097D03*
X1613183D03*
X1621883Y1111483D03*
X1613183D03*
Y1128915D03*
X1621883Y1128215D03*
X1613183Y1121522D03*
X1621883D03*
Y1141601D03*
X1613183D03*
X1622726Y1135108D03*
X1611886Y1134908D03*
X1621883Y1158333D03*
X1613183D03*
X1621883Y1148294D03*
X1613183D03*
X1621883Y1165026D03*
X1613183D03*
Y1171719D03*
X1621883D03*
Y1178412D03*
X1613183D03*
X1621883Y1185105D03*
X1613183D03*
Y1195144D03*
X1621883D03*
Y1201837D03*
X1613183D03*
X1621883Y1208530D03*
X1613183D03*
X1621883Y1215223D03*
X1613183D03*
X1612147Y1221916D03*
X1622712D03*
X1612137Y1231862D03*
X1622681Y1231955D03*
X1621883Y1238648D03*
X1613183D03*
X1610150Y1257172D03*
X1621883Y1245341D03*
X1613183D03*
X1618888Y1273344D03*
X1616088D03*
X1616875Y1578182D03*
X1612615D03*
X1616875Y1590094D03*
X1612615D03*
X1622175Y1614292D03*
Y1602380D03*
X1617915Y1614292D03*
Y1602380D03*
X1610115Y1614292D03*
Y1602380D03*
X1619488Y1675383D03*
Y1679920D03*
X1611614Y1679320D03*
X1619488Y1684454D03*
Y1689556D03*
Y1694093D03*
Y1698627D03*
X1611614Y1688391D03*
Y1693493D03*
Y1698030D03*
Y1683857D03*
X1619488Y1703729D03*
Y1708266D03*
Y1712800D03*
X1611614Y1707666D03*
Y1712203D03*
Y1702564D03*
X1619488Y1726974D03*
Y1722440D03*
Y1717903D03*
X1611614Y1730911D03*
Y1726377D03*
Y1721840D03*
Y1716737D03*
X1626741Y770144D03*
X1635441D03*
X1626741Y776837D03*
X1635441D03*
X1626741Y783530D03*
X1635441D03*
X1626741Y793570D03*
X1635441D03*
Y800263D03*
X1626741D03*
X1636341Y820341D03*
X1626741D03*
X1636574Y813648D03*
X1626741D03*
X1635441Y806955D03*
X1626741D03*
X1635441Y830381D03*
X1626741D03*
X1635441Y837074D03*
X1626741D03*
Y843766D03*
X1635441D03*
Y850459D03*
X1626741D03*
X1625705Y867192D03*
X1636441D03*
X1635441Y857152D03*
X1626741D03*
Y880577D03*
X1635441D03*
Y873885D03*
X1626741D03*
Y887270D03*
X1635441D03*
X1626741Y893963D03*
X1635441D03*
X1626741Y904003D03*
X1635441D03*
Y910696D03*
X1626741D03*
X1635441Y917389D03*
X1626741D03*
X1636316Y930774D03*
X1625803D03*
X1636646Y924081D03*
X1626741D03*
X1635441Y940814D03*
X1626741D03*
X1635441Y947507D03*
X1626741D03*
X1635441Y954200D03*
X1626741D03*
Y964239D03*
X1635441D03*
Y977625D03*
X1626741D03*
X1635441Y970932D03*
X1626741D03*
X1635441Y984318D03*
X1626741D03*
Y991011D03*
X1635441D03*
Y1024475D03*
X1626741D03*
X1635441Y1017782D03*
X1626741D03*
X1635441Y1031168D03*
X1626741D03*
X1635441Y1037861D03*
X1626741D03*
X1635441Y1044554D03*
X1626741D03*
Y1057940D03*
X1635441D03*
Y1051247D03*
X1626741D03*
X1635441Y1064633D03*
X1626741D03*
X1635441Y1071326D03*
X1626741D03*
X1636241Y1078018D03*
X1625941D03*
Y1088058D03*
X1636241D03*
X1635441Y1094751D03*
X1626741D03*
Y1101444D03*
X1635441D03*
X1626741Y1108137D03*
X1635441D03*
X1626074Y1124640D03*
X1636341Y1124869D03*
X1635441Y1114829D03*
X1626741D03*
X1635441Y1144948D03*
X1626741D03*
X1635441Y1138255D03*
X1626741D03*
X1635441Y1130762D03*
X1626741D03*
Y1161680D03*
X1635441D03*
Y1151641D03*
X1626741D03*
Y1168373D03*
X1635441D03*
X1626741Y1175066D03*
X1635441D03*
X1626741Y1181759D03*
X1635441D03*
X1626741Y1188452D03*
X1635441D03*
X1626741Y1198491D03*
X1635441D03*
X1626741Y1205184D03*
X1635441D03*
Y1211877D03*
X1626741D03*
X1635441Y1218570D03*
X1626741D03*
X1636212Y1225263D03*
X1626055D03*
X1636376Y1235302D03*
X1625843D03*
X1635441Y1241995D03*
X1626741D03*
X1635688Y1257664D03*
X1626741Y1248688D03*
X1635441D03*
X1629788Y1273344D03*
X1632588D03*
X1625729Y1266766D03*
X1636735Y1578088D03*
X1628935Y1578182D03*
X1624675D03*
X1636735Y1590094D03*
X1628935D03*
X1624675D03*
X1634235Y1614292D03*
Y1602380D03*
X1629975Y1614292D03*
Y1602380D03*
X1627362Y1679320D03*
Y1688391D03*
Y1693493D03*
Y1698030D03*
Y1683857D03*
Y1707666D03*
Y1712203D03*
Y1702564D03*
Y1730911D03*
Y1726377D03*
Y1721840D03*
Y1716737D03*
X1651583Y766798D03*
X1642883D03*
X1656441Y770144D03*
Y776837D03*
X1642883Y773491D03*
X1651583D03*
X1642883Y780184D03*
X1651583D03*
X1656441Y783530D03*
Y793570D03*
X1642883Y790223D03*
X1651583D03*
X1642883Y796916D03*
X1651583D03*
X1656441Y800263D03*
X1651583Y803609D03*
X1642883D03*
X1656441Y806955D03*
Y813648D03*
Y820341D03*
X1651583Y810302D03*
X1642883D03*
X1652545Y816995D03*
X1641945D03*
X1656441Y830381D03*
X1652767Y827034D03*
X1642018D03*
X1651583Y833727D03*
X1642883D03*
X1656441Y837074D03*
Y843766D03*
X1642883Y840420D03*
X1651583D03*
X1656441Y850459D03*
X1651583Y847113D03*
X1642883D03*
X1642058Y863845D03*
X1652742D03*
X1656441Y857152D03*
Y867192D03*
X1652559Y853806D03*
X1642032D03*
X1656441Y873885D03*
Y880577D03*
X1642883Y883924D03*
X1651583D03*
Y870538D03*
X1642883D03*
X1651583Y877231D03*
X1642883D03*
X1656441Y887270D03*
Y893963D03*
X1642883Y890617D03*
X1651583D03*
X1642883Y900656D03*
X1651583D03*
X1656441Y904003D03*
Y910696D03*
X1642883Y907349D03*
X1651583D03*
X1656441Y917389D03*
X1651583Y914042D03*
X1642883D03*
X1656441Y924081D03*
Y930774D03*
X1652630Y927428D03*
X1642038D03*
X1651583Y920735D03*
X1642883D03*
X1656441Y940814D03*
Y947507D03*
X1652501Y937467D03*
X1642065D03*
X1651583Y944160D03*
X1642883D03*
X1656441Y954200D03*
X1642883Y950853D03*
X1651583D03*
Y960892D03*
X1642883D03*
X1656441Y964239D03*
Y977625D03*
Y970932D03*
X1651583Y967585D03*
X1642883D03*
X1651583Y974278D03*
X1642883D03*
X1651583Y980971D03*
X1642883D03*
X1656441Y984318D03*
Y991011D03*
X1651583Y987664D03*
X1642883D03*
X1651583Y1017782D03*
X1642883D03*
X1656441D03*
Y1024475D03*
X1651583Y1027822D03*
X1642883D03*
X1656441Y1031168D03*
Y1044554D03*
Y1037861D03*
X1651583Y1034515D03*
X1642883D03*
X1651583Y1041207D03*
X1642883D03*
X1651583Y1047900D03*
X1642883D03*
Y1061286D03*
X1651583D03*
X1656441Y1051247D03*
Y1057940D03*
X1651583Y1054593D03*
X1642883D03*
X1656441Y1064633D03*
Y1071326D03*
Y1078018D03*
X1652483Y1074672D03*
X1641983D03*
X1651583Y1067979D03*
X1642883D03*
X1656441Y1088058D03*
Y1094751D03*
X1652383Y1084711D03*
X1642083D03*
X1651583Y1091404D03*
X1642883D03*
X1656441Y1101444D03*
Y1108137D03*
X1642883Y1098097D03*
X1651583D03*
X1642883Y1104790D03*
X1651583D03*
X1642883Y1111483D03*
X1651583D03*
X1656441Y1114829D03*
Y1124869D03*
X1642883Y1121522D03*
X1651583D03*
X1642883Y1128215D03*
X1651583D03*
X1656441Y1131562D03*
Y1138255D03*
X1642883Y1134908D03*
X1651583D03*
X1642883Y1141601D03*
X1651583D03*
X1656441Y1144948D03*
Y1151641D03*
Y1161680D03*
X1652383Y1158333D03*
X1642083D03*
X1652794Y1148294D03*
X1641744D03*
X1656441Y1168373D03*
Y1175066D03*
X1642883Y1171719D03*
X1651583D03*
Y1165026D03*
X1642883D03*
X1656441Y1181759D03*
Y1188452D03*
X1651583Y1178412D03*
X1642883D03*
X1651583Y1185105D03*
X1642883D03*
X1656441Y1198491D03*
Y1205184D03*
X1642883Y1195144D03*
X1651583D03*
X1642883Y1201837D03*
X1651583D03*
X1642883Y1208530D03*
X1651583D03*
X1656441Y1211877D03*
X1652590Y1221916D03*
X1641793D03*
X1656441Y1225263D03*
Y1218570D03*
X1651583Y1215223D03*
X1642883D03*
X1656441Y1235302D03*
Y1241995D03*
X1652604Y1231955D03*
X1642054D03*
X1651583Y1238648D03*
X1642883D03*
X1656441Y1248688D03*
X1651583Y1245341D03*
X1642883D03*
X1648588Y1273344D03*
X1645788D03*
X1640995Y1578182D03*
X1648795D03*
X1640995Y1590094D03*
X1648795D03*
X1646295Y1614292D03*
Y1602380D03*
X1654095Y1614292D03*
Y1602380D03*
X1642035Y1614292D03*
Y1602286D03*
X1665141Y770144D03*
X1672583Y766798D03*
X1665141Y776837D03*
Y783530D03*
X1672583Y773491D03*
Y780184D03*
X1665141Y793570D03*
Y800263D03*
X1672583Y790223D03*
Y796916D03*
Y803609D03*
X1665141Y806955D03*
Y813648D03*
X1666030Y820341D03*
X1672583Y810302D03*
Y816995D03*
X1665141Y830381D03*
X1672583Y827034D03*
Y833727D03*
X1665141Y837074D03*
Y843766D03*
X1672583Y840420D03*
X1665141Y850459D03*
X1672583Y847113D03*
X1666038Y857152D03*
X1665141Y867192D03*
X1672583Y853806D03*
Y863845D03*
X1665141Y873885D03*
Y880577D03*
X1672583Y870538D03*
Y877231D03*
Y883924D03*
X1665141Y887270D03*
Y893963D03*
X1672583Y890617D03*
Y900656D03*
X1665141Y904003D03*
Y910696D03*
Y917389D03*
X1672583Y907349D03*
Y914042D03*
X1665141Y924081D03*
X1666246Y930774D03*
X1672583Y920735D03*
Y927428D03*
X1665141Y940814D03*
Y947507D03*
X1672583Y937467D03*
Y944160D03*
X1665141Y954200D03*
Y964239D03*
X1672583Y950853D03*
Y960892D03*
X1665141Y977625D03*
Y970932D03*
X1672583Y967585D03*
Y974278D03*
Y980971D03*
X1665141Y984318D03*
Y991011D03*
X1672583Y987664D03*
X1665141Y1017782D03*
Y1024475D03*
Y1031168D03*
X1672583Y1017782D03*
Y1027822D03*
X1665141Y1044554D03*
Y1037861D03*
X1672583Y1034515D03*
Y1041207D03*
Y1047900D03*
X1665141Y1057940D03*
X1672583Y1061286D03*
Y1054593D03*
X1665141Y1064633D03*
Y1071326D03*
Y1077118D03*
X1672583Y1067979D03*
Y1074672D03*
X1665141Y1088058D03*
Y1094751D03*
X1672583Y1084711D03*
Y1091404D03*
X1665141Y1101444D03*
Y1108137D03*
X1672583Y1098097D03*
Y1104790D03*
Y1111483D03*
X1665141Y1114829D03*
Y1124869D03*
X1672583Y1121522D03*
Y1128215D03*
X1665141Y1131562D03*
Y1138255D03*
Y1144948D03*
X1672583Y1134908D03*
Y1141601D03*
X1666141Y1151641D03*
X1665141Y1161680D03*
X1672583Y1148294D03*
Y1158333D03*
X1665141Y1168373D03*
Y1175066D03*
X1672583Y1165026D03*
Y1171719D03*
X1665141Y1181759D03*
Y1188452D03*
X1672583Y1178412D03*
Y1185105D03*
X1665141Y1198491D03*
Y1205184D03*
X1672583Y1195144D03*
Y1201837D03*
Y1208530D03*
X1665141Y1211877D03*
X1665941Y1225263D03*
X1665141Y1218570D03*
X1672583Y1215223D03*
Y1221916D03*
X1665141Y1235302D03*
Y1241995D03*
X1672583Y1231955D03*
Y1238648D03*
X1665141Y1248688D03*
X1672583Y1245341D03*
X1665688Y1257964D03*
X1659488Y1273344D03*
X1662288D03*
X1681283Y766798D03*
X1686141Y770144D03*
X1681283Y773491D03*
Y780184D03*
X1686141Y776837D03*
Y783530D03*
X1681283Y790223D03*
Y796916D03*
Y803609D03*
X1686141Y793570D03*
Y800263D03*
X1681283Y810302D03*
Y816995D03*
X1686141Y806955D03*
Y813648D03*
Y820341D03*
X1681283Y827034D03*
Y833727D03*
X1686141Y830381D03*
X1681283Y840420D03*
X1686141Y837074D03*
Y843766D03*
Y850459D03*
X1681283Y847113D03*
X1686141Y857152D03*
Y867192D03*
X1681283Y853806D03*
Y863845D03*
X1686141Y873885D03*
Y880577D03*
X1681283Y870538D03*
Y877231D03*
Y883924D03*
X1686141Y887270D03*
Y893963D03*
X1681283Y890617D03*
Y900656D03*
X1686141Y904003D03*
Y910696D03*
Y917389D03*
X1681283Y907349D03*
Y914042D03*
X1686141Y924081D03*
Y930774D03*
X1681283Y920735D03*
Y927428D03*
X1686141Y940814D03*
Y947507D03*
X1681283Y937467D03*
Y944160D03*
X1686141Y954200D03*
Y964239D03*
X1681283Y950853D03*
Y960892D03*
X1686141Y970932D03*
Y977625D03*
X1681283Y967585D03*
Y974278D03*
Y980971D03*
X1686141Y984318D03*
Y991011D03*
X1681283Y987664D03*
X1686141Y1017782D03*
Y1024475D03*
Y1031168D03*
X1681283Y1017782D03*
Y1027822D03*
X1686141Y1037861D03*
Y1044554D03*
X1681283Y1034515D03*
Y1041207D03*
Y1047900D03*
X1686141Y1051247D03*
Y1057940D03*
X1681283Y1061286D03*
Y1054593D03*
X1686141Y1064633D03*
Y1071326D03*
Y1078018D03*
X1681283Y1067979D03*
Y1074672D03*
X1686141Y1088058D03*
Y1094751D03*
X1681283Y1084711D03*
Y1091404D03*
X1686141Y1101444D03*
Y1108137D03*
X1681283Y1098097D03*
Y1104790D03*
Y1111483D03*
X1686141Y1114829D03*
Y1124869D03*
X1681283Y1121522D03*
Y1128215D03*
X1686141Y1131562D03*
Y1138255D03*
Y1144948D03*
X1681283Y1134908D03*
Y1141601D03*
X1686141Y1151641D03*
Y1161680D03*
X1681283Y1148294D03*
Y1158333D03*
X1686141Y1168373D03*
Y1175066D03*
X1681283Y1165026D03*
Y1171719D03*
X1686141Y1181759D03*
Y1188452D03*
X1681283Y1178412D03*
Y1185105D03*
X1686141Y1198491D03*
Y1205184D03*
X1681283Y1195144D03*
Y1201837D03*
Y1208530D03*
X1686141Y1211877D03*
Y1218570D03*
Y1225263D03*
X1681283Y1215223D03*
Y1221916D03*
Y1231955D03*
Y1238648D03*
X1686141Y1235302D03*
Y1241995D03*
X1681283Y1245341D03*
X1686141Y1248688D03*
X1675488Y1273344D03*
X1678288D03*
X1689188D03*
X1694841Y770144D03*
X1702283Y766798D03*
X1694841Y776837D03*
Y783530D03*
X1702283Y773491D03*
Y780184D03*
X1694841Y793570D03*
Y800263D03*
X1702283Y790223D03*
Y796916D03*
Y803609D03*
X1694841Y806955D03*
Y813648D03*
Y820341D03*
X1702283Y810302D03*
Y816995D03*
X1694841Y830381D03*
X1702283Y827034D03*
Y833727D03*
X1694841Y837074D03*
Y843766D03*
Y850459D03*
X1702283Y840420D03*
Y847113D03*
X1694841Y857152D03*
Y867192D03*
X1702283Y853806D03*
Y863845D03*
X1694841Y873885D03*
Y880577D03*
X1702283Y870538D03*
Y877231D03*
Y883924D03*
X1694841Y887270D03*
Y893963D03*
X1702283Y890617D03*
Y900656D03*
X1694841Y904003D03*
Y910696D03*
Y917389D03*
X1702283Y907349D03*
Y914042D03*
X1694841Y924081D03*
Y930774D03*
X1702283Y920735D03*
Y927428D03*
X1694841Y940814D03*
Y947507D03*
X1702283Y937467D03*
Y944160D03*
X1694841Y954200D03*
Y964239D03*
X1702283Y950853D03*
Y960892D03*
X1694841Y970932D03*
Y977625D03*
X1702283Y967585D03*
Y974278D03*
Y980971D03*
X1694841Y984318D03*
Y991011D03*
X1702283Y987664D03*
X1694841Y1017782D03*
Y1024475D03*
Y1031168D03*
X1702283Y1017782D03*
Y1027822D03*
X1694841Y1037861D03*
Y1044554D03*
X1702283Y1034515D03*
Y1041207D03*
Y1047900D03*
X1694841Y1051247D03*
Y1057940D03*
X1702283Y1054593D03*
Y1061286D03*
X1694841Y1064633D03*
Y1071326D03*
Y1078018D03*
X1702283Y1067979D03*
Y1074672D03*
X1694841Y1088058D03*
Y1094751D03*
X1702283Y1084711D03*
Y1091404D03*
X1694841Y1101444D03*
Y1108137D03*
X1702283Y1098097D03*
Y1104790D03*
Y1111483D03*
X1694841Y1114829D03*
Y1124869D03*
X1702283Y1121522D03*
Y1128215D03*
X1694841Y1131562D03*
Y1138255D03*
Y1144948D03*
X1702283Y1134908D03*
Y1141601D03*
X1694841Y1151641D03*
Y1161680D03*
X1702283Y1148294D03*
Y1158333D03*
X1694841Y1168373D03*
Y1175066D03*
X1702283Y1165026D03*
Y1171719D03*
X1694841Y1181759D03*
Y1188452D03*
X1702283Y1178412D03*
Y1185105D03*
X1694841Y1198491D03*
Y1205184D03*
X1702283Y1195144D03*
Y1201837D03*
Y1208530D03*
X1694841Y1211877D03*
Y1218570D03*
Y1225263D03*
X1702283Y1215223D03*
Y1221916D03*
X1694841Y1235302D03*
Y1241995D03*
X1702283Y1231955D03*
Y1238648D03*
X1694841Y1248688D03*
X1695188Y1257064D03*
X1702283Y1245341D03*
X1691988Y1273344D03*
X1705188D03*
X1710983Y766798D03*
X1715841Y770144D03*
X1710983Y773491D03*
Y780184D03*
X1715841Y783530D03*
Y776837D03*
X1710983Y790223D03*
Y796916D03*
Y803609D03*
X1715841Y793570D03*
Y800263D03*
X1710983Y810302D03*
Y816995D03*
X1715841Y806955D03*
Y813648D03*
Y820341D03*
X1710983Y827034D03*
Y833727D03*
X1715841Y830381D03*
X1710983Y840420D03*
Y847113D03*
X1715841Y837074D03*
Y843766D03*
Y850459D03*
X1710983Y853806D03*
Y863845D03*
X1715841Y857152D03*
Y867192D03*
X1710983Y870538D03*
Y877231D03*
Y883924D03*
X1715841Y873885D03*
Y880577D03*
X1710983Y890617D03*
Y900656D03*
X1715841Y893963D03*
Y887270D03*
X1710983Y907349D03*
Y914042D03*
X1715841Y904003D03*
Y910696D03*
Y917389D03*
X1710983Y920735D03*
Y927428D03*
X1715841Y924081D03*
Y930774D03*
X1710983Y937467D03*
Y944160D03*
X1715841Y940814D03*
Y947507D03*
X1710983Y950853D03*
Y960892D03*
X1715841Y954200D03*
Y964239D03*
X1710983Y967585D03*
Y974278D03*
Y980971D03*
X1715841Y970932D03*
Y977625D03*
X1710983Y987664D03*
X1715841Y984318D03*
Y991011D03*
X1710983Y1017782D03*
Y1027822D03*
X1715841Y1017782D03*
Y1024475D03*
Y1031168D03*
X1710983Y1034515D03*
Y1041207D03*
Y1047900D03*
X1715841Y1037861D03*
Y1044554D03*
X1710983Y1054593D03*
Y1061286D03*
X1715841Y1051247D03*
Y1057940D03*
X1710983Y1067979D03*
Y1074672D03*
X1715841Y1071326D03*
Y1064633D03*
Y1078018D03*
X1710983Y1084711D03*
Y1091404D03*
X1715841Y1088058D03*
Y1094751D03*
X1710983Y1098097D03*
Y1104790D03*
Y1111483D03*
X1715841Y1101444D03*
Y1108137D03*
X1710983Y1121522D03*
Y1128215D03*
X1715841Y1114829D03*
Y1124869D03*
X1710983Y1134908D03*
Y1141601D03*
X1715841Y1131562D03*
Y1138255D03*
Y1144948D03*
X1710983Y1148294D03*
Y1158333D03*
X1715841Y1151641D03*
Y1161680D03*
X1710983Y1165026D03*
Y1171719D03*
X1715841Y1168373D03*
Y1175066D03*
X1710983Y1178412D03*
Y1185105D03*
X1715841Y1181759D03*
Y1188452D03*
X1710983Y1195144D03*
Y1201837D03*
Y1208530D03*
X1715841Y1198491D03*
Y1205184D03*
X1710983Y1215223D03*
Y1221916D03*
X1715841Y1211877D03*
Y1218570D03*
Y1225263D03*
X1710983Y1231955D03*
Y1238648D03*
X1715841Y1235302D03*
Y1241995D03*
X1710983Y1245341D03*
X1715841Y1248688D03*
X1707514Y1273444D03*
X1718888Y1273344D03*
X1721688D03*
X1731983Y766798D03*
X1724541Y770144D03*
X1731983Y773491D03*
Y780184D03*
X1724541Y783530D03*
Y776837D03*
Y793570D03*
Y800263D03*
X1731983Y790223D03*
Y796916D03*
Y803609D03*
X1724541Y806955D03*
Y813648D03*
Y820341D03*
X1731983Y810302D03*
Y816995D03*
X1724541Y830381D03*
X1731983Y827034D03*
Y833727D03*
X1724541Y837074D03*
Y843766D03*
Y850459D03*
X1731983Y840420D03*
Y847113D03*
X1724541Y857152D03*
Y867192D03*
X1731983Y853806D03*
Y863845D03*
X1724541Y873885D03*
Y880577D03*
X1731983Y870538D03*
Y877231D03*
Y883924D03*
X1724541Y893963D03*
Y887270D03*
X1731983Y890617D03*
Y900656D03*
X1724541Y904003D03*
Y910696D03*
Y917389D03*
X1731983Y907349D03*
Y914042D03*
X1724541Y924081D03*
Y930774D03*
X1731983Y920735D03*
Y927428D03*
X1724541Y940814D03*
Y947507D03*
X1731983Y937467D03*
Y944160D03*
X1724541Y954200D03*
Y964239D03*
X1731983Y950853D03*
Y960892D03*
X1724541Y970932D03*
Y977625D03*
X1731983Y967585D03*
Y974278D03*
Y980971D03*
X1724541Y984318D03*
Y991011D03*
X1731983Y987664D03*
X1724541Y1017782D03*
Y1024475D03*
Y1031168D03*
X1731983Y1017782D03*
Y1027822D03*
X1724541Y1037861D03*
Y1044554D03*
X1731983Y1034515D03*
Y1041207D03*
Y1047900D03*
X1724541Y1057940D03*
X1731983Y1054593D03*
Y1061286D03*
X1724541Y1071326D03*
Y1064633D03*
Y1078018D03*
X1731983Y1074672D03*
Y1067979D03*
X1724541Y1088058D03*
Y1094751D03*
X1731983Y1084711D03*
Y1091404D03*
X1724541Y1101444D03*
Y1108137D03*
X1731983Y1098097D03*
Y1104790D03*
Y1111483D03*
X1724541Y1114829D03*
Y1124869D03*
X1731983Y1121522D03*
Y1128215D03*
X1724541Y1131562D03*
Y1138255D03*
Y1144948D03*
X1731983Y1134908D03*
Y1141601D03*
X1724541Y1151641D03*
Y1161680D03*
X1731983Y1148294D03*
Y1158333D03*
X1724541Y1168373D03*
Y1175066D03*
X1731983Y1165026D03*
Y1171719D03*
X1724541Y1181759D03*
Y1188452D03*
X1731983Y1178412D03*
Y1185105D03*
X1724541Y1198491D03*
Y1205184D03*
X1731983Y1195144D03*
Y1201837D03*
Y1208530D03*
X1724541Y1211877D03*
Y1218570D03*
Y1225263D03*
X1731983Y1215223D03*
Y1221916D03*
X1724541Y1235302D03*
Y1241995D03*
X1731983Y1231955D03*
Y1238648D03*
X1724541Y1248688D03*
X1724588Y1257164D03*
X1731983Y1245341D03*
X1734888Y1273344D03*
X1737688D03*
X1740683Y766798D03*
X1745541Y770144D03*
X1754241D03*
X1740683Y773491D03*
Y780184D03*
X1745541Y776837D03*
X1754241D03*
X1745541Y783530D03*
X1754241D03*
X1740683Y790223D03*
Y796916D03*
Y803609D03*
X1745541Y793570D03*
X1754241D03*
X1745541Y800263D03*
X1754241D03*
X1740683Y810302D03*
Y816995D03*
X1745541Y806955D03*
X1754241D03*
X1745541Y813648D03*
X1754241D03*
X1745541Y820341D03*
X1754241D03*
X1740683Y827034D03*
Y833727D03*
X1745541Y830381D03*
X1754241D03*
X1740683Y840420D03*
Y847113D03*
X1754241Y843766D03*
X1745541D03*
Y837074D03*
X1754241D03*
X1745541Y850459D03*
X1754241D03*
X1740683Y853806D03*
Y863845D03*
X1745541Y857152D03*
X1754241D03*
Y867192D03*
X1745541D03*
X1740683Y870538D03*
Y877231D03*
Y883924D03*
X1745541Y873885D03*
X1754241D03*
X1745541Y880577D03*
X1754241D03*
X1740683Y890617D03*
Y900656D03*
X1754241Y893963D03*
X1745541D03*
Y887270D03*
X1754241D03*
X1740683Y907349D03*
Y914042D03*
X1754241Y904003D03*
X1745541D03*
X1754241Y910696D03*
X1745541D03*
X1754241Y917389D03*
X1745541D03*
X1740683Y920735D03*
Y927428D03*
X1754241Y924081D03*
X1745541D03*
X1754241Y930774D03*
X1745541D03*
X1740683Y937467D03*
Y944160D03*
X1754241Y940814D03*
X1745541D03*
X1754241Y947507D03*
X1745541D03*
X1740683Y950853D03*
Y960892D03*
X1754241Y954200D03*
X1745541D03*
X1754241Y964239D03*
X1745541D03*
X1740683Y967585D03*
Y974278D03*
Y980971D03*
X1754241Y970932D03*
X1745541D03*
X1754241Y977625D03*
X1745541D03*
X1740683Y987664D03*
X1754241Y984318D03*
X1745541D03*
X1754241Y991011D03*
X1745541D03*
X1740683Y1017782D03*
Y1027822D03*
X1754241Y1017782D03*
X1745541D03*
Y1024475D03*
X1754241D03*
X1745541Y1031168D03*
X1754241D03*
X1740683Y1034515D03*
Y1041207D03*
Y1047900D03*
X1754241Y1044554D03*
X1745541D03*
Y1037861D03*
X1754241D03*
X1740683Y1054593D03*
Y1061286D03*
X1745541Y1051247D03*
X1754241D03*
X1745541Y1057940D03*
X1754241D03*
X1740683Y1074672D03*
Y1067979D03*
X1754241Y1071326D03*
X1745541D03*
Y1064633D03*
X1754241D03*
Y1078018D03*
X1745541D03*
X1740683Y1084711D03*
Y1091404D03*
X1754241Y1088058D03*
X1745541D03*
X1754241Y1094751D03*
X1745541D03*
X1740683Y1098097D03*
Y1104790D03*
Y1111483D03*
X1754241Y1101444D03*
X1745541D03*
X1754241Y1108137D03*
X1745541D03*
X1740683Y1121522D03*
Y1128215D03*
X1754241Y1114829D03*
X1745541D03*
X1754241Y1124869D03*
X1745541D03*
X1740683Y1134908D03*
Y1141601D03*
X1754241Y1131562D03*
X1745541D03*
X1754241Y1138255D03*
X1745541D03*
X1754241Y1144948D03*
X1745541D03*
X1740683Y1148294D03*
Y1158333D03*
X1754241Y1151641D03*
X1745541D03*
X1754241Y1161680D03*
X1745541D03*
X1740683Y1165026D03*
Y1171719D03*
X1745541Y1175066D03*
X1754241D03*
Y1168373D03*
X1745541D03*
X1740683Y1178412D03*
Y1185105D03*
X1745541Y1181759D03*
X1754241D03*
Y1188452D03*
X1745541D03*
X1740683Y1195144D03*
Y1201837D03*
Y1208530D03*
X1754241Y1198491D03*
X1745541D03*
X1754241Y1205184D03*
X1745541D03*
X1740683Y1215223D03*
Y1221916D03*
X1754241Y1211877D03*
X1745541D03*
X1754241Y1218570D03*
X1745541D03*
X1754241Y1225263D03*
X1745541D03*
X1740683Y1231955D03*
Y1238648D03*
X1754241Y1235302D03*
X1745541D03*
X1754241Y1241995D03*
X1745541D03*
X1740683Y1245341D03*
X1754241Y1248688D03*
X1745541D03*
X1754488Y1257264D03*
X1751388Y1273344D03*
X1748588D03*
X1749088Y1310474D03*
X1746288D03*
X1770383Y766798D03*
X1761683D03*
X1770383Y773491D03*
X1761683D03*
Y780184D03*
X1770383D03*
X1761683Y790223D03*
X1770383D03*
X1761683Y796916D03*
X1770383D03*
X1761683Y803609D03*
X1770383D03*
X1761683Y810302D03*
X1770383D03*
X1761683Y816995D03*
X1770383D03*
X1761683Y827034D03*
X1770383D03*
X1761683Y833727D03*
X1770383D03*
X1761683Y840420D03*
X1770383D03*
X1761683Y847113D03*
X1770383D03*
X1761683Y853806D03*
X1770383D03*
X1761683Y863845D03*
X1770383D03*
X1761683Y870538D03*
X1770383D03*
X1761683Y877231D03*
X1770383D03*
X1761683Y883924D03*
X1770383D03*
X1761683Y890617D03*
X1770383D03*
X1761683Y900656D03*
X1770383D03*
X1761683Y907349D03*
X1770383D03*
X1761683Y914042D03*
X1770383D03*
Y927428D03*
X1761683D03*
Y920735D03*
X1770383D03*
X1761683Y937467D03*
X1770383D03*
X1761683Y944160D03*
X1770383D03*
X1761683Y950853D03*
X1770383D03*
X1761683Y960892D03*
X1770383D03*
X1761683Y967585D03*
X1770383D03*
X1761683Y974278D03*
X1770383D03*
X1761683Y980971D03*
X1770383D03*
X1761683Y987664D03*
X1770383D03*
X1761683Y1017782D03*
X1770383D03*
X1761683Y1027822D03*
X1770383D03*
X1761683Y1034515D03*
X1770383D03*
X1761683Y1041207D03*
X1770383D03*
X1761683Y1047900D03*
X1770383D03*
X1761683Y1054593D03*
X1770383D03*
X1761683Y1061286D03*
X1770383D03*
X1761683Y1067979D03*
X1770383D03*
X1761683Y1074672D03*
X1770383D03*
X1761683Y1084711D03*
X1770383D03*
X1761683Y1091404D03*
X1770383D03*
Y1098097D03*
X1761683D03*
Y1104790D03*
X1770383D03*
X1761683Y1111483D03*
X1770383D03*
X1761683Y1121522D03*
X1770383D03*
X1761683Y1128215D03*
X1770383D03*
X1761683Y1134908D03*
X1770383D03*
X1761683Y1141601D03*
X1770383D03*
X1761683Y1148294D03*
X1770383D03*
X1761683Y1158333D03*
X1770383D03*
X1761683Y1165026D03*
X1770383D03*
X1761683Y1171719D03*
X1770383D03*
X1761683Y1178412D03*
X1770383D03*
X1761683Y1185105D03*
X1770383D03*
X1761683Y1195144D03*
X1770383D03*
X1761683Y1201837D03*
X1770383D03*
X1761683Y1208530D03*
X1770383D03*
X1761683Y1215223D03*
X1770383D03*
X1761683Y1221916D03*
X1770383D03*
X1761683Y1231955D03*
X1770383D03*
X1761683Y1238648D03*
X1770383D03*
X1761683Y1245341D03*
X1770383D03*
X1767388Y1273344D03*
X1764588D03*
X1775241Y770144D03*
X1783941D03*
X1775241Y776837D03*
X1783941D03*
X1775241Y783530D03*
X1783941D03*
X1775241Y793570D03*
X1783941D03*
X1775241Y800263D03*
X1783941D03*
X1775241Y806955D03*
X1783941D03*
X1775241Y813648D03*
X1783941D03*
X1775241Y820341D03*
X1783941D03*
Y830381D03*
X1775241D03*
Y837074D03*
X1783941D03*
X1775241Y843766D03*
X1783941D03*
X1775241Y850459D03*
X1783941D03*
X1775241Y857152D03*
X1783941D03*
X1775241Y867192D03*
X1783941D03*
X1775241Y873885D03*
X1783941D03*
X1775241Y880577D03*
X1783941D03*
X1775241Y887270D03*
X1783941D03*
X1775241Y893963D03*
X1783941D03*
X1775241Y904003D03*
X1783941D03*
X1775241Y910696D03*
X1783941D03*
X1775241Y917389D03*
X1783941D03*
X1775241Y924081D03*
X1783941D03*
X1775241Y930774D03*
X1783941D03*
X1775241Y940814D03*
X1783941D03*
X1775241Y947507D03*
X1783941D03*
X1775241Y954200D03*
X1783941D03*
X1775241Y964239D03*
X1783941D03*
X1775241Y970932D03*
X1783941D03*
X1775241Y977625D03*
X1783941D03*
X1775241Y984318D03*
X1783941D03*
X1775241Y991011D03*
X1783941D03*
X1775241Y1017782D03*
X1783941D03*
X1775241Y1024475D03*
X1783941D03*
X1775241Y1031168D03*
X1783941D03*
X1775241Y1037861D03*
X1783941D03*
X1775241Y1044554D03*
X1783941D03*
X1775241Y1051247D03*
X1783941D03*
X1775241Y1057940D03*
X1783941D03*
X1775241Y1064633D03*
X1783941D03*
X1775241Y1071326D03*
X1783941D03*
X1775241Y1078018D03*
X1783941D03*
X1775241Y1088058D03*
X1783941D03*
X1775241Y1094751D03*
X1783941D03*
X1775241Y1101444D03*
X1783941D03*
X1775241Y1108137D03*
X1783941D03*
X1775241Y1114829D03*
X1783941D03*
X1775241Y1124869D03*
X1783941D03*
X1775241Y1131562D03*
X1783941D03*
X1775241Y1138255D03*
X1783941D03*
X1775241Y1144948D03*
X1783941D03*
Y1151641D03*
X1775241D03*
Y1161680D03*
X1783941D03*
X1775241Y1168373D03*
X1783941D03*
X1775241Y1175066D03*
X1783941D03*
X1775241Y1181759D03*
X1783941D03*
X1775241Y1188452D03*
X1783941D03*
X1775241Y1198491D03*
X1783941D03*
X1775241Y1205184D03*
X1783941D03*
X1775241Y1211877D03*
X1783941D03*
X1775241Y1218570D03*
X1783941D03*
X1775241Y1225263D03*
X1783941D03*
X1775241Y1235302D03*
X1783941D03*
X1775241Y1241995D03*
X1783941D03*
X1784188Y1257664D03*
X1775241Y1248688D03*
X1783941D03*
X1781088Y1273344D03*
X1778288D03*
X1791383Y766798D03*
X1800083D03*
X1791383Y773491D03*
X1800083D03*
X1791383Y780184D03*
X1800083D03*
X1791383Y790223D03*
X1800083D03*
X1791383Y796916D03*
X1800083D03*
X1791383Y803609D03*
X1800083D03*
X1791383Y810302D03*
X1800083D03*
X1791383Y816995D03*
X1800083D03*
X1791383Y827034D03*
X1800083D03*
Y833727D03*
X1791383D03*
Y840420D03*
X1800083D03*
X1791383Y847113D03*
X1800083D03*
X1791383Y853806D03*
X1800083D03*
X1791383Y863845D03*
X1800083D03*
X1791383Y870538D03*
X1800083D03*
X1791383Y877231D03*
X1800083D03*
X1791383Y883924D03*
X1800083D03*
X1791383Y890617D03*
X1800083D03*
X1791383Y900656D03*
X1800083D03*
X1791383Y907349D03*
X1800083D03*
X1791383Y914042D03*
X1800083D03*
X1791383Y920735D03*
X1800083D03*
X1791383Y927428D03*
X1800083D03*
X1791383Y937467D03*
X1800083D03*
X1791383Y944160D03*
X1800083D03*
Y950853D03*
X1791383D03*
Y960892D03*
X1800083D03*
X1791383Y967585D03*
X1800083D03*
X1791383Y974278D03*
X1800083D03*
X1791383Y980971D03*
X1800083D03*
X1791383Y987664D03*
X1800083D03*
X1791383Y1017782D03*
X1800083D03*
X1791383Y1027822D03*
X1800083D03*
X1791383Y1034515D03*
X1800083D03*
X1791383Y1041207D03*
X1800083D03*
X1791383Y1047900D03*
X1800083D03*
X1791383Y1054593D03*
X1800083D03*
X1791383Y1061286D03*
X1800083D03*
X1791383Y1067979D03*
X1800083D03*
X1791383Y1074672D03*
X1800083D03*
X1791383Y1084711D03*
X1800083D03*
X1791383Y1091404D03*
X1800083D03*
X1791383Y1098097D03*
X1800083D03*
X1791383Y1104790D03*
X1800083D03*
X1791383Y1111483D03*
X1800083D03*
X1791383Y1121522D03*
X1800083D03*
X1791383Y1128215D03*
X1800083D03*
Y1134908D03*
X1791383D03*
Y1141601D03*
X1800083D03*
X1791383Y1148294D03*
X1800083D03*
X1791383Y1158333D03*
X1800083D03*
X1791383Y1165026D03*
X1800083D03*
X1791383Y1171719D03*
X1800083D03*
X1791383Y1178412D03*
X1800083D03*
X1791383Y1185105D03*
X1800083D03*
X1791383Y1195144D03*
X1800083D03*
X1791383Y1201837D03*
X1800083D03*
X1791383Y1208530D03*
X1800083D03*
X1791383Y1215223D03*
X1800083D03*
X1791383Y1221916D03*
X1800083D03*
X1791383Y1231955D03*
X1800083D03*
X1791383Y1238648D03*
X1800083D03*
X1791383Y1245341D03*
X1800083D03*
X1797088Y1273344D03*
X1794288D03*
X1804941Y770144D03*
X1813641D03*
X1804941Y776837D03*
X1813641D03*
X1804941Y783530D03*
X1813641D03*
X1804941Y793570D03*
X1813641D03*
X1804941Y800263D03*
X1813641D03*
X1804941Y806955D03*
X1813641D03*
X1804941Y813648D03*
X1813641D03*
X1804941Y820341D03*
X1813641D03*
X1804941Y830381D03*
X1813641D03*
X1804941Y843766D03*
X1813641D03*
X1804941Y837074D03*
X1813641D03*
X1804941Y850459D03*
X1813641D03*
X1804941Y857152D03*
X1813641D03*
Y867192D03*
X1804941D03*
Y873885D03*
X1813641D03*
X1804941Y880577D03*
X1813641D03*
X1804941Y887270D03*
X1813641D03*
X1804941Y893963D03*
X1813641D03*
X1804941Y904003D03*
X1813641D03*
X1804941Y910696D03*
X1813641D03*
X1804941Y917389D03*
X1813641D03*
X1804941Y924081D03*
X1813641D03*
X1804941Y930774D03*
X1813641D03*
X1804941Y940814D03*
X1813641D03*
X1804941Y947507D03*
X1813641D03*
X1804941Y954200D03*
X1813641D03*
X1804941Y964239D03*
X1813641D03*
X1804941Y970932D03*
X1813641D03*
X1804941Y977625D03*
X1813641D03*
X1804941Y984318D03*
X1813641D03*
X1804941Y991011D03*
X1813641D03*
X1804941Y1017782D03*
X1813641D03*
X1804941Y1024475D03*
X1813641D03*
X1804941Y1031168D03*
X1813641D03*
X1804941Y1037861D03*
X1813641D03*
X1804941Y1044554D03*
X1813641D03*
Y1057940D03*
X1804941D03*
Y1051247D03*
X1813641D03*
X1804941Y1064633D03*
X1813641D03*
Y1071326D03*
X1804941D03*
X1813641Y1078018D03*
X1804941D03*
X1813641Y1088058D03*
X1804941D03*
X1813641Y1094751D03*
X1804941D03*
X1813641Y1101444D03*
X1804941D03*
X1813641Y1108137D03*
X1804941D03*
X1813641Y1114829D03*
X1804941D03*
X1813641Y1124869D03*
X1804941D03*
X1813641Y1131562D03*
X1804941D03*
X1813641Y1138255D03*
X1804941D03*
X1813641Y1144948D03*
X1804941D03*
X1813641Y1151641D03*
X1804941D03*
X1813641Y1161680D03*
X1804941D03*
X1813641Y1168373D03*
X1804941D03*
X1813641Y1175066D03*
X1804941D03*
X1813641Y1181759D03*
X1804941D03*
X1813641Y1188452D03*
X1804941D03*
X1813641Y1198491D03*
X1804941D03*
X1813641Y1205184D03*
X1804941D03*
X1813641Y1211877D03*
X1804941D03*
X1813641Y1218570D03*
X1804941D03*
X1813641Y1225263D03*
X1804941D03*
X1813641Y1235302D03*
X1804941D03*
X1813641Y1241995D03*
X1804941D03*
X1813641Y1248688D03*
X1804941D03*
X1819054Y1253986D03*
X1818188Y1273044D03*
X1810788Y1273344D03*
X1807988D03*
X1815388Y1273044D03*
X1829783Y766798D03*
X1821083D03*
X1829783Y773491D03*
X1821083D03*
X1829783Y780184D03*
X1821083D03*
X1829783Y790223D03*
X1821083D03*
X1829783Y796916D03*
X1821083D03*
X1829783Y803609D03*
X1821083D03*
X1829783Y810302D03*
X1821083D03*
X1829783Y816995D03*
X1821083D03*
X1829783Y827034D03*
X1821083D03*
X1829783Y833727D03*
X1821083D03*
Y847113D03*
X1829783D03*
Y840420D03*
X1821083D03*
X1829783Y853806D03*
X1821083D03*
X1829783Y863845D03*
X1821083D03*
X1829783Y870538D03*
X1821083D03*
X1829783Y877231D03*
X1821083D03*
X1829783Y883924D03*
X1821083D03*
X1829783Y890617D03*
X1821083D03*
X1829783Y900656D03*
X1821083D03*
X1829783Y907349D03*
X1821083D03*
X1829783Y914042D03*
X1821083D03*
X1829783Y920735D03*
X1821083D03*
X1829783Y927428D03*
X1821083D03*
X1829783Y937467D03*
X1821083D03*
X1829783Y944160D03*
X1821083D03*
X1829783Y950853D03*
X1821083D03*
X1829783Y960892D03*
X1821083D03*
X1829783Y967585D03*
X1821083D03*
X1829783Y974278D03*
X1821083D03*
X1829783Y980971D03*
X1821083D03*
X1829783Y987664D03*
X1821083D03*
X1829783Y1017782D03*
X1821083D03*
X1829783Y1027822D03*
X1821083D03*
X1829783Y1034515D03*
X1821083D03*
X1829783Y1041207D03*
X1821083D03*
X1829783Y1047900D03*
X1821083D03*
X1829783Y1054593D03*
X1821083D03*
X1829783Y1061286D03*
X1821083D03*
X1829783Y1067979D03*
X1821083D03*
Y1074672D03*
X1829783D03*
X1821083Y1084711D03*
X1829783D03*
X1821083Y1091404D03*
X1829783D03*
X1821083Y1098097D03*
X1829783D03*
X1821083Y1104790D03*
X1829783D03*
X1821083Y1111483D03*
X1829783D03*
X1821083Y1121522D03*
X1829783D03*
X1821083Y1128215D03*
X1829783D03*
X1821083Y1134908D03*
X1829783D03*
X1821083Y1141601D03*
X1829783D03*
X1821083Y1148294D03*
X1829783D03*
X1821083Y1158333D03*
X1829783D03*
X1821083Y1165026D03*
X1829783D03*
X1821083Y1171719D03*
X1829783D03*
X1821083Y1178412D03*
X1829783D03*
X1821083Y1185105D03*
X1829783D03*
X1821083Y1195144D03*
X1829783D03*
X1821083Y1201837D03*
X1829783D03*
X1821083Y1208530D03*
X1829783D03*
X1821083Y1215223D03*
X1829783D03*
X1821083Y1221916D03*
X1829783D03*
X1821083Y1231955D03*
X1829783D03*
X1821083Y1238648D03*
X1829783D03*
Y1245341D03*
X1821083D03*
G54D57*
X841240Y1420330D03*
X1016240D03*
G54D63*
X986642Y-27947D03*
X986627Y-25432D03*
Y-21558D03*
X986642Y-17918D03*
X986627Y-15403D03*
Y-11529D03*
X986642Y-7889D03*
X986627Y-5374D03*
Y4655D03*
X986642Y2140D03*
X986627Y14684D03*
X986642Y12169D03*
X986627Y8529D03*
X986642Y22698D03*
X989910Y22684D03*
X986627Y19058D03*
Y25213D03*
X989895Y25199D03*
X1296019Y-35472D03*
Y-31598D03*
X1296034Y-37987D03*
Y-27958D03*
X1296019Y-25443D03*
Y-21569D03*
X1296034Y-17929D03*
X1296019Y-15414D03*
Y-11540D03*
X1296034Y-7900D03*
X1296019Y-5385D03*
Y4644D03*
X1296034Y2129D03*
X1296019Y-1511D03*
Y14673D03*
X1296034Y12158D03*
X1296019Y8518D03*
X1296034Y22687D03*
X1296019Y19047D03*
Y25202D03*
X1299302Y22673D03*
X1299287Y25188D03*
X1488393Y-27958D03*
X1488378Y-25443D03*
X1488393Y-37987D03*
X1488378Y-35472D03*
Y-31598D03*
X1488393Y-17929D03*
X1488378Y-15414D03*
Y-11540D03*
Y-21569D03*
X1488393Y2129D03*
X1488378Y4644D03*
X1488393Y-7900D03*
X1488378Y-5385D03*
Y-1511D03*
Y14673D03*
X1488393Y12158D03*
Y22687D03*
X1491661Y22673D03*
X1488378Y8518D03*
Y19047D03*
Y25202D03*
X1491646Y25188D03*
G54D71*
X1879155Y344948D03*
Y592848D03*
X1900275Y-19342D03*
X1889155Y344948D03*
Y592848D03*
X1900275Y716808D03*
X1910275Y-19342D03*
Y716808D03*
X1931395Y592868D03*
X1921395D03*
X1952395Y-19152D03*
X1942395D03*
X1963362Y593010D03*
X1984482Y-19180D03*
X1973362Y593010D03*
X1994482Y-19180D03*
X2015452Y593020D03*
X2005452D03*
X2026452Y-19000D03*
X2036452D03*
X2047419Y593162D03*
X2057419D03*
G54D24*
X57646Y12480D03*
X137272D03*
X186622D03*
X266858D03*
X315598D03*
X502528Y33268D03*
X582154D03*
X631504D03*
X711740D03*
X760480D03*
X1532055Y12480D03*
X1611681D03*
X1661031D03*
X1741267D03*
X1790007D03*
G54D64*
X1077638Y133866D03*
G54D46*
X460000Y278543D03*
G54D69*
X1771457Y1634646D03*
G54D58*
X900196Y175197D03*
X944684Y155216D03*
G54D78*
X1903086Y1318228D03*
X1902402Y1683256D03*
X1950484Y1683497D03*
X1993147Y1682875D03*
G54D76*
X1880836Y1317164D03*
X1881165Y1682207D03*
X1929695Y1683220D03*
X1971555Y1683130D03*
%LPC*%
G75*
G54D79*
G01X-6350Y-464479D02*
Y-539479D01*
X493650D01*
Y-464479D01*
X-6350D01*
G01X5650Y-529479D02*
Y-534479D01*
G01X4193Y-529479D02*
X7107D01*
G01X12017Y-534479D02*
X9483D01*
Y-529479D01*
X12017D01*
G01X11003Y-531896D02*
X9483D01*
G01X14583Y-529479D02*
Y-534479D01*
X17117D01*
G01X20950Y-534646D02*
X20823Y-534562D01*
Y-534396D01*
X20950Y-534312D01*
X21077Y-534396D01*
Y-534562D01*
X20950Y-534646D01*
G01Y-532396D02*
X20823Y-532312D01*
Y-532146D01*
X20950Y-532062D01*
X21077Y-532146D01*
Y-532312D01*
X20950Y-532396D01*
G01X25733Y-536146D02*
X25100Y-535312D01*
X24783Y-534479D01*
Y-531146D01*
X25100Y-530312D01*
X25733Y-529479D01*
G01X31150D02*
X30643Y-529646D01*
X30263Y-530062D01*
X30010Y-530562D01*
X29820Y-531229D01*
X29757Y-531979D01*
X29820Y-532729D01*
X30010Y-533396D01*
X30263Y-533896D01*
X30643Y-534312D01*
X31150Y-534479D01*
X31657Y-534312D01*
X32037Y-533896D01*
X32290Y-533396D01*
X32480Y-532729D01*
X32543Y-531979D01*
X32480Y-531229D01*
X32290Y-530562D01*
X32037Y-530062D01*
X31657Y-529646D01*
X31150Y-529479D01*
G01X34857Y-533479D02*
X35237Y-534062D01*
X35743Y-534396D01*
X36313Y-534479D01*
X36820Y-534396D01*
X37327Y-533979D01*
X37643Y-533479D01*
X37707Y-532979D01*
X37580Y-532396D01*
X37137Y-531979D01*
X36693Y-531812D01*
X36123D01*
G01X36693D02*
X37073Y-531562D01*
X37390Y-531146D01*
X37517Y-530646D01*
X37390Y-530146D01*
X37073Y-529729D01*
X36503Y-529479D01*
X35933Y-529562D01*
X35363Y-529896D01*
G01X41667Y-536146D02*
X42300Y-535312D01*
X42617Y-534479D01*
Y-531146D01*
X42300Y-530312D01*
X41667Y-529479D01*
G01X45057Y-533479D02*
X45437Y-534062D01*
X45943Y-534396D01*
X46513Y-534479D01*
X47020Y-534396D01*
X47527Y-533979D01*
X47843Y-533479D01*
X47907Y-532979D01*
X47780Y-532396D01*
X47337Y-531979D01*
X46893Y-531812D01*
X46323D01*
G01X46893D02*
X47273Y-531562D01*
X47590Y-531146D01*
X47717Y-530646D01*
X47590Y-530146D01*
X47273Y-529729D01*
X46703Y-529479D01*
X46133Y-529562D01*
X45563Y-529896D01*
G01X50347Y-530312D02*
X50727Y-529812D01*
X51170Y-529562D01*
X51677Y-529479D01*
X52310Y-529646D01*
X52753Y-530062D01*
X52880Y-530562D01*
X52817Y-531062D01*
X52563Y-531479D01*
X51297Y-532312D01*
X50727Y-532896D01*
X50347Y-533729D01*
X50220Y-534479D01*
X52880D01*
G01X56523D02*
X56650Y-533396D01*
X56840Y-532479D01*
X57093Y-531646D01*
X57410Y-530729D01*
X57917Y-529479D01*
X55383D01*
G01X60927Y-532812D02*
X62573D01*
G01X65647Y-530312D02*
X66027Y-529812D01*
X66470Y-529562D01*
X66977Y-529479D01*
X67610Y-529646D01*
X68053Y-530062D01*
X68180Y-530562D01*
X68117Y-531062D01*
X67863Y-531479D01*
X66597Y-532312D01*
X66027Y-532896D01*
X65647Y-533729D01*
X65520Y-534479D01*
X68180D01*
G01X70557Y-533479D02*
X70937Y-534062D01*
X71443Y-534396D01*
X72013Y-534479D01*
X72520Y-534396D01*
X73027Y-533979D01*
X73343Y-533479D01*
X73407Y-532979D01*
X73280Y-532396D01*
X72837Y-531979D01*
X72393Y-531812D01*
X71823D01*
G01X72393D02*
X72773Y-531562D01*
X73090Y-531146D01*
X73217Y-530646D01*
X73090Y-530146D01*
X72773Y-529729D01*
X72203Y-529479D01*
X71633Y-529562D01*
X71063Y-529896D01*
G01X77810Y-534479D02*
Y-529479D01*
X75467Y-533062D01*
X78633D01*
G01X80757Y-533729D02*
X81137Y-534146D01*
X81580Y-534396D01*
X82150Y-534479D01*
X82720Y-534312D01*
X83163Y-533979D01*
X83480Y-533396D01*
X83543Y-532729D01*
X83417Y-532062D01*
X83100Y-531646D01*
X82657Y-531312D01*
X82213Y-531229D01*
X81770Y-531312D01*
X81200Y-531646D01*
X81390Y-529479D01*
X83100D01*
G01X91147Y-534479D02*
Y-529479D01*
X93553D01*
G01X92667Y-531896D02*
X91147D01*
G01X95867Y-534479D02*
X97450Y-529479D01*
X99033Y-534479D01*
G01X98463Y-532729D02*
X96437D01*
G01X101220Y-534479D02*
X103880Y-529479D01*
G01X101220D02*
X103880Y-534479D01*
G01X107650Y-534646D02*
X107523Y-534562D01*
Y-534396D01*
X107650Y-534312D01*
X107777Y-534396D01*
Y-534562D01*
X107650Y-534646D01*
G01Y-532396D02*
X107523Y-532312D01*
Y-532146D01*
X107650Y-532062D01*
X107777Y-532146D01*
Y-532312D01*
X107650Y-532396D01*
G01X112433Y-536146D02*
X111800Y-535312D01*
X111483Y-534479D01*
Y-531146D01*
X111800Y-530312D01*
X112433Y-529479D01*
G01X117850D02*
X117343Y-529646D01*
X116963Y-530062D01*
X116710Y-530562D01*
X116520Y-531229D01*
X116457Y-531979D01*
X116520Y-532729D01*
X116710Y-533396D01*
X116963Y-533896D01*
X117343Y-534312D01*
X117850Y-534479D01*
X118357Y-534312D01*
X118737Y-533896D01*
X118990Y-533396D01*
X119180Y-532729D01*
X119243Y-531979D01*
X119180Y-531229D01*
X118990Y-530562D01*
X118737Y-530062D01*
X118357Y-529646D01*
X117850Y-529479D01*
G01X121557Y-533479D02*
X121937Y-534062D01*
X122443Y-534396D01*
X123013Y-534479D01*
X123520Y-534396D01*
X124027Y-533979D01*
X124343Y-533479D01*
X124407Y-532979D01*
X124280Y-532396D01*
X123837Y-531979D01*
X123393Y-531812D01*
X122823D01*
G01X123393D02*
X123773Y-531562D01*
X124090Y-531146D01*
X124217Y-530646D01*
X124090Y-530146D01*
X123773Y-529729D01*
X123203Y-529479D01*
X122633Y-529562D01*
X122063Y-529896D01*
G01X128367Y-536146D02*
X129000Y-535312D01*
X129317Y-534479D01*
Y-531146D01*
X129000Y-530312D01*
X128367Y-529479D01*
G01X131757Y-533479D02*
X132137Y-534062D01*
X132643Y-534396D01*
X133213Y-534479D01*
X133720Y-534396D01*
X134227Y-533979D01*
X134543Y-533479D01*
X134607Y-532979D01*
X134480Y-532396D01*
X134037Y-531979D01*
X133593Y-531812D01*
X133023D01*
G01X133593D02*
X133973Y-531562D01*
X134290Y-531146D01*
X134417Y-530646D01*
X134290Y-530146D01*
X133973Y-529729D01*
X133403Y-529479D01*
X132833Y-529562D01*
X132263Y-529896D01*
G01X137173Y-533896D02*
X137617Y-534312D01*
X138123Y-534479D01*
X138630Y-534312D01*
X139073Y-533812D01*
X139390Y-533062D01*
X139517Y-532312D01*
Y-531396D01*
X139390Y-530646D01*
X139073Y-529979D01*
X138693Y-529646D01*
X138250Y-529479D01*
X137743Y-529646D01*
X137363Y-529979D01*
X137110Y-530479D01*
X136983Y-531146D01*
X137110Y-531729D01*
X137427Y-532312D01*
X137807Y-532646D01*
X138250Y-532729D01*
X138757Y-532562D01*
X139137Y-532146D01*
X139517Y-531396D01*
G01X143223Y-534479D02*
X143350Y-533396D01*
X143540Y-532479D01*
X143793Y-531646D01*
X144110Y-530729D01*
X144617Y-529479D01*
X142083D01*
G01X147627Y-532812D02*
X149273D01*
G01X152157Y-533479D02*
X152537Y-534062D01*
X153043Y-534396D01*
X153613Y-534479D01*
X154120Y-534396D01*
X154627Y-533979D01*
X154943Y-533479D01*
X155007Y-532979D01*
X154880Y-532396D01*
X154437Y-531979D01*
X153993Y-531812D01*
X153423D01*
G01X153993D02*
X154373Y-531562D01*
X154690Y-531146D01*
X154817Y-530646D01*
X154690Y-530146D01*
X154373Y-529729D01*
X153803Y-529479D01*
X153233Y-529562D01*
X152663Y-529896D01*
G01X157447Y-532396D02*
X157890Y-531812D01*
X158270Y-531479D01*
X158777Y-531312D01*
X159220Y-531479D01*
X159537Y-531812D01*
X159790Y-532312D01*
X159853Y-532896D01*
X159790Y-533396D01*
X159537Y-533896D01*
X159157Y-534312D01*
X158713Y-534479D01*
X158207Y-534312D01*
X157763Y-533812D01*
X157510Y-533062D01*
X157447Y-532229D01*
X157573Y-531146D01*
X157763Y-530562D01*
X158080Y-529979D01*
X158523Y-529562D01*
X158967Y-529479D01*
X159410Y-529646D01*
X159727Y-530062D01*
G01X163750Y-534479D02*
Y-529479D01*
X162990Y-530479D01*
G01Y-534479D02*
X164510D01*
G01X169610D02*
Y-529479D01*
X167267Y-533062D01*
X170433D01*
G01X188650Y-464479D02*
Y-539479D01*
G01Y-514479D02*
X291650D01*
Y-489479D01*
G01X188650D02*
X291650D01*
G01Y-464479D02*
Y-539479D01*
G01X293650Y-464479D02*
Y-539479D01*
G01X299157Y-524479D02*
Y-519479D01*
X300423D01*
X300930Y-519729D01*
X301310Y-520062D01*
X301627Y-520562D01*
X301880Y-521146D01*
X301943Y-521979D01*
X301880Y-522812D01*
X301627Y-523396D01*
X301310Y-523896D01*
X300930Y-524229D01*
X300423Y-524479D01*
X299157D01*
G01X304067D02*
X305650Y-519479D01*
X307233Y-524479D01*
G01X306663Y-522729D02*
X304637D01*
G01X310750Y-519479D02*
Y-524479D01*
G01X309293Y-519479D02*
X312207D01*
G01X317117Y-524479D02*
X314583D01*
Y-519479D01*
X317117D01*
G01X316103Y-521896D02*
X314583D01*
G01X320950Y-524646D02*
X320823Y-524562D01*
Y-524396D01*
X320950Y-524312D01*
X321077Y-524396D01*
Y-524562D01*
X320950Y-524646D01*
G01Y-522396D02*
X320823Y-522312D01*
Y-522146D01*
X320950Y-522062D01*
X321077Y-522146D01*
Y-522312D01*
X320950Y-522396D01*
G01X299283Y-499479D02*
Y-494479D01*
X300803D01*
X301310Y-494729D01*
X301690Y-495312D01*
X301817Y-495979D01*
X301690Y-496646D01*
X301373Y-497146D01*
X300803Y-497396D01*
X299283D01*
G01X304510Y-499646D02*
X306790Y-494479D01*
G01X309293Y-499479D02*
Y-494479D01*
X312207Y-499479D01*
Y-494479D01*
G01X315850Y-499646D02*
X315723Y-499562D01*
Y-499396D01*
X315850Y-499312D01*
X315977Y-499396D01*
Y-499562D01*
X315850Y-499646D01*
G01Y-497396D02*
X315723Y-497312D01*
Y-497146D01*
X315850Y-497062D01*
X315977Y-497146D01*
Y-497312D01*
X315850Y-497396D01*
G01X293650Y-514479D02*
X493650D01*
G01X293650Y-489479D02*
X493650D01*
G01X299283Y-474479D02*
Y-469479D01*
X300803D01*
X301310Y-469729D01*
X301690Y-470312D01*
X301817Y-470979D01*
X301690Y-471646D01*
X301373Y-472146D01*
X300803Y-472396D01*
X299283D01*
G01X304383Y-474479D02*
Y-469479D01*
X305967D01*
X306473Y-469729D01*
X306790Y-470062D01*
X306917Y-470729D01*
X306790Y-471396D01*
X306410Y-471812D01*
X305967Y-472062D01*
X304383D01*
G01X305967D02*
X306917Y-474479D01*
G01X310750D02*
X310243Y-474396D01*
X309800Y-474062D01*
X309420Y-473562D01*
X309167Y-472979D01*
X309040Y-472312D01*
Y-471646D01*
X309167Y-470979D01*
X309420Y-470396D01*
X309800Y-469896D01*
X310243Y-469562D01*
X310750Y-469479D01*
X311257Y-469562D01*
X311700Y-469896D01*
X312080Y-470396D01*
X312333Y-470979D01*
X312460Y-471646D01*
Y-472312D01*
X312333Y-472979D01*
X312080Y-473562D01*
X311700Y-474062D01*
X311257Y-474396D01*
X310750Y-474479D01*
G01X314583Y-473479D02*
X314900Y-473979D01*
X315280Y-474312D01*
X315723Y-474479D01*
X316230Y-474312D01*
X316610Y-473979D01*
X316990Y-473479D01*
X317117Y-472812D01*
Y-469479D01*
G01X322217Y-474479D02*
X319683D01*
Y-469479D01*
X322217D01*
G01X321203Y-471896D02*
X319683D01*
G01X327443Y-469896D02*
X327063Y-469646D01*
X326620Y-469479D01*
X326113D01*
X325543Y-469729D01*
X325100Y-470146D01*
X324783Y-470646D01*
X324530Y-471479D01*
X324467Y-472229D01*
X324593Y-472979D01*
X324783Y-473479D01*
X325163Y-473979D01*
X325607Y-474312D01*
X326050Y-474479D01*
X326493D01*
X326937Y-474312D01*
X327317Y-474062D01*
X327633Y-473729D01*
G01X331150Y-469479D02*
Y-474479D01*
G01X329693Y-469479D02*
X332607D01*
G01X336250Y-474646D02*
X336123Y-474562D01*
Y-474396D01*
X336250Y-474312D01*
X336377Y-474396D01*
Y-474562D01*
X336250Y-474646D01*
G01Y-472396D02*
X336123Y-472312D01*
Y-472146D01*
X336250Y-472062D01*
X336377Y-472146D01*
Y-472312D01*
X336250Y-472396D01*
G01X408650Y-514479D02*
Y-539479D01*
G01X411283Y-516979D02*
Y-521979D01*
X413817D01*
G01X416890Y-516979D02*
X418410D01*
G01X417650D02*
Y-521979D01*
G01X416890D02*
X418410D01*
G01X423257Y-519312D02*
X423510Y-519062D01*
X423700Y-518646D01*
X423827Y-518062D01*
X423700Y-517562D01*
X423447Y-517229D01*
X423003Y-516979D01*
X421293D01*
Y-521979D01*
X423383D01*
X423827Y-521646D01*
X424080Y-521146D01*
X424207Y-520562D01*
X424080Y-519979D01*
X423700Y-519479D01*
X423257Y-519312D01*
X421293D01*
G01X427850Y-522146D02*
X427723Y-522062D01*
Y-521896D01*
X427850Y-521812D01*
X427977Y-521896D01*
Y-522062D01*
X427850Y-522146D01*
G01Y-519896D02*
X427723Y-519812D01*
Y-519646D01*
X427850Y-519562D01*
X427977Y-519646D01*
Y-519812D01*
X427850Y-519896D01*
G01X451650Y-514479D02*
Y-539479D01*
G01Y-489479D02*
Y-514479D01*
G01X456663Y-541646D02*
X456770Y-541521D01*
X456850Y-541312D01*
X456903Y-541021D01*
X456850Y-540771D01*
X456743Y-540604D01*
X456557Y-540479D01*
X455837D01*
Y-542979D01*
X456717D01*
X456903Y-542812D01*
X457010Y-542562D01*
X457063Y-542271D01*
X457010Y-541979D01*
X456850Y-541729D01*
X456663Y-541646D01*
X455837D01*
G01X459130Y-542979D02*
Y-541312D01*
G01Y-541604D02*
X459023Y-541437D01*
X458863Y-541354D01*
X458677Y-541312D01*
X458490Y-541396D01*
X458330Y-541562D01*
X458223Y-541812D01*
X458170Y-542146D01*
X458223Y-542479D01*
X458330Y-542729D01*
X458490Y-542896D01*
X458677Y-542979D01*
X458863Y-542937D01*
X459023Y-542812D01*
X459130Y-542646D01*
G01X460450Y-542687D02*
X460583Y-542854D01*
X460770Y-542979D01*
X460930D01*
X461090Y-542896D01*
X461197Y-542771D01*
X461250Y-542604D01*
X461223Y-542354D01*
X461117Y-542229D01*
X460637Y-541979D01*
X460530Y-541687D01*
X460583Y-541479D01*
X460690Y-541354D01*
X460850Y-541312D01*
X461010Y-541354D01*
X461170Y-541479D01*
G01X462650Y-541854D02*
X463503D01*
X463423Y-541562D01*
X463290Y-541396D01*
X463103Y-541312D01*
X462917Y-541354D01*
X462757Y-541479D01*
X462650Y-541771D01*
X462597Y-542021D01*
Y-542271D01*
X462650Y-542521D01*
X462783Y-542771D01*
X462943Y-542937D01*
X463130Y-542979D01*
X463317Y-542896D01*
X463503Y-542646D01*
G01X464770Y-542979D02*
Y-540479D01*
G01Y-541729D02*
X464903Y-541479D01*
X465063Y-541354D01*
X465223Y-541312D01*
X465463Y-541396D01*
X465623Y-541562D01*
X465730Y-541854D01*
Y-542187D01*
X465677Y-542521D01*
X465570Y-542771D01*
X465383Y-542937D01*
X465223Y-542979D01*
X465063Y-542937D01*
X464903Y-542812D01*
X464770Y-542604D01*
G01X467450Y-542979D02*
X467290Y-542937D01*
X467130Y-542771D01*
X467023Y-542479D01*
X466970Y-542146D01*
X467023Y-541812D01*
X467130Y-541521D01*
X467290Y-541354D01*
X467450Y-541312D01*
X467610Y-541354D01*
X467770Y-541521D01*
X467877Y-541812D01*
X467903Y-542146D01*
X467877Y-542479D01*
X467770Y-542771D01*
X467610Y-542937D01*
X467450Y-542979D01*
G01X470130D02*
Y-541312D01*
G01Y-541604D02*
X470023Y-541437D01*
X469863Y-541354D01*
X469677Y-541312D01*
X469490Y-541396D01*
X469330Y-541562D01*
X469223Y-541812D01*
X469170Y-542146D01*
X469223Y-542479D01*
X469330Y-542729D01*
X469490Y-542896D01*
X469677Y-542979D01*
X469863Y-542937D01*
X470023Y-542812D01*
X470130Y-542646D01*
G01X471477Y-542979D02*
Y-541312D01*
G01Y-541646D02*
X471610Y-541479D01*
X471743Y-541354D01*
X471930Y-541312D01*
X472063Y-541354D01*
X472223Y-541479D01*
G01X474530Y-540479D02*
Y-542979D01*
G01Y-542604D02*
X474423Y-542812D01*
X474263Y-542937D01*
X474077Y-542979D01*
X473863Y-542896D01*
X473703Y-542687D01*
X473597Y-542437D01*
X473570Y-542146D01*
X473597Y-541854D01*
X473703Y-541604D01*
X473863Y-541396D01*
X474077Y-541312D01*
X474263Y-541354D01*
X474397Y-541437D01*
X474530Y-541604D01*
G01X477917Y-542979D02*
Y-540479D01*
X478583D01*
X478797Y-540604D01*
X478930Y-540771D01*
X478983Y-541104D01*
X478930Y-541437D01*
X478770Y-541646D01*
X478583Y-541771D01*
X477917D01*
G01X478583D02*
X478983Y-542979D01*
G01X480250Y-541854D02*
X481103D01*
X481023Y-541562D01*
X480890Y-541396D01*
X480703Y-541312D01*
X480517Y-541354D01*
X480357Y-541479D01*
X480250Y-541771D01*
X480197Y-542021D01*
Y-542271D01*
X480250Y-542521D01*
X480383Y-542771D01*
X480543Y-542937D01*
X480730Y-542979D01*
X480917Y-542896D01*
X481103Y-542646D01*
G01X482370Y-541312D02*
X482850Y-542979D01*
X483330Y-541312D01*
G01X485050Y-543062D02*
X484997Y-543021D01*
Y-542937D01*
X485050Y-542896D01*
X485103Y-542937D01*
Y-543021D01*
X485050Y-543062D01*
G01X487250Y-542979D02*
X487437Y-542937D01*
X487650Y-542812D01*
X487783Y-542604D01*
X487837Y-542312D01*
X487783Y-542021D01*
X487623Y-541771D01*
X487383Y-541646D01*
X487117D01*
X486957Y-541562D01*
X486823Y-541354D01*
X486770Y-541062D01*
X486850Y-540771D01*
X487037Y-540562D01*
X487250Y-540479D01*
X487463Y-540562D01*
X487650Y-540771D01*
X487730Y-541062D01*
X487677Y-541354D01*
X487543Y-541562D01*
X487383Y-541646D01*
X487117D01*
X486877Y-541771D01*
X486717Y-542021D01*
X486663Y-542312D01*
X486717Y-542604D01*
X486850Y-542812D01*
X487063Y-542937D01*
X487250Y-542979D01*
G01X489663Y-541646D02*
X489770Y-541521D01*
X489850Y-541312D01*
X489903Y-541021D01*
X489850Y-540771D01*
X489743Y-540604D01*
X489557Y-540479D01*
X488837D01*
Y-542979D01*
X489717D01*
X489903Y-542812D01*
X490010Y-542562D01*
X490063Y-542271D01*
X490010Y-541979D01*
X489850Y-541729D01*
X489663Y-541646D01*
X488837D01*
G01X455550Y-516979D02*
Y-521979D01*
G01X454093Y-516979D02*
X457007D01*
G01X460650Y-521979D02*
X460270Y-521896D01*
X459890Y-521562D01*
X459637Y-520979D01*
X459510Y-520312D01*
X459637Y-519646D01*
X459890Y-519062D01*
X460270Y-518729D01*
X460650Y-518646D01*
X461030Y-518729D01*
X461410Y-519062D01*
X461663Y-519646D01*
X461727Y-520312D01*
X461663Y-520979D01*
X461410Y-521562D01*
X461030Y-521896D01*
X460650Y-521979D01*
G01X465750D02*
X465370Y-521896D01*
X464990Y-521562D01*
X464737Y-520979D01*
X464610Y-520312D01*
X464737Y-519646D01*
X464990Y-519062D01*
X465370Y-518729D01*
X465750Y-518646D01*
X466130Y-518729D01*
X466510Y-519062D01*
X466763Y-519646D01*
X466827Y-520312D01*
X466763Y-520979D01*
X466510Y-521562D01*
X466130Y-521896D01*
X465750Y-521979D01*
G01X470850D02*
Y-516979D01*
G01X475950Y-522146D02*
X475823Y-522062D01*
Y-521896D01*
X475950Y-521812D01*
X476077Y-521896D01*
Y-522062D01*
X475950Y-522146D01*
G01Y-519896D02*
X475823Y-519812D01*
Y-519646D01*
X475950Y-519562D01*
X476077Y-519646D01*
Y-519812D01*
X475950Y-519896D01*
G01X454283Y-496979D02*
Y-491979D01*
X455867D01*
X456373Y-492229D01*
X456690Y-492562D01*
X456817Y-493229D01*
X456690Y-493896D01*
X456310Y-494312D01*
X455867Y-494562D01*
X454283D01*
G01X455867D02*
X456817Y-496979D01*
G01X461917D02*
X459383D01*
Y-491979D01*
X461917D01*
G01X460903Y-494396D02*
X459383D01*
G01X464167Y-491979D02*
X465750Y-496979D01*
X467333Y-491979D01*
G01X470850Y-497146D02*
X470723Y-497062D01*
Y-496896D01*
X470850Y-496812D01*
X470977Y-496896D01*
Y-497062D01*
X470850Y-497146D01*
G01Y-494896D02*
X470723Y-494812D01*
Y-494646D01*
X470850Y-494562D01*
X470977Y-494646D01*
Y-494812D01*
X470850Y-494896D01*
G01X-984580Y-698988D02*
Y4193602D01*
X5868320D01*
Y-698988D01*
X-984580D01*
G01X7723Y-521204D02*
X7253Y-520889D01*
X6705Y-520679D01*
X6078D01*
X5373Y-520994D01*
X4825Y-521519D01*
X4433Y-522149D01*
X4120Y-523199D01*
X4042Y-524144D01*
X4198Y-525089D01*
X4433Y-525719D01*
X4903Y-526349D01*
X5452Y-526769D01*
X6000Y-526979D01*
X6548D01*
X7097Y-526769D01*
X7567Y-526454D01*
X7958Y-526034D01*
G01X11360Y-520679D02*
X13240D01*
G01X12300D02*
Y-526979D01*
G01X11360D02*
X13240D01*
G01X18600Y-520679D02*
Y-526979D01*
G01X16798Y-520679D02*
X20402D01*
G01X24900Y-526979D02*
Y-524144D01*
X23333Y-520679D01*
G01X26467D02*
X24900Y-524144D01*
G01X35777Y-525719D02*
X36247Y-526454D01*
X36873Y-526874D01*
X37578Y-526979D01*
X38205Y-526874D01*
X38832Y-526349D01*
X39223Y-525719D01*
X39302Y-525089D01*
X39145Y-524354D01*
X38597Y-523829D01*
X38048Y-523619D01*
X37343D01*
G01X38048D02*
X38518Y-523304D01*
X38910Y-522779D01*
X39067Y-522149D01*
X38910Y-521519D01*
X38518Y-520994D01*
X37813Y-520679D01*
X37108Y-520784D01*
X36403Y-521204D01*
G01X42077Y-525719D02*
X42547Y-526454D01*
X43173Y-526874D01*
X43878Y-526979D01*
X44505Y-526874D01*
X45132Y-526349D01*
X45523Y-525719D01*
X45602Y-525089D01*
X45445Y-524354D01*
X44897Y-523829D01*
X44348Y-523619D01*
X43643D01*
G01X44348D02*
X44818Y-523304D01*
X45210Y-522779D01*
X45367Y-522149D01*
X45210Y-521519D01*
X44818Y-520994D01*
X44113Y-520679D01*
X43408Y-520784D01*
X42703Y-521204D01*
G01X48377Y-525719D02*
X48847Y-526454D01*
X49473Y-526874D01*
X50178Y-526979D01*
X50805Y-526874D01*
X51432Y-526349D01*
X51823Y-525719D01*
X51902Y-525089D01*
X51745Y-524354D01*
X51197Y-523829D01*
X50648Y-523619D01*
X49943D01*
G01X50648D02*
X51118Y-523304D01*
X51510Y-522779D01*
X51667Y-522149D01*
X51510Y-521519D01*
X51118Y-520994D01*
X50413Y-520679D01*
X49708Y-520784D01*
X49003Y-521204D01*
G01X56243Y-526979D02*
X56400Y-525614D01*
X56635Y-524459D01*
X56948Y-523409D01*
X57340Y-522254D01*
X57967Y-520679D01*
X54833D01*
G01X62543Y-526979D02*
X62700Y-525614D01*
X62935Y-524459D01*
X63248Y-523409D01*
X63640Y-522254D01*
X64267Y-520679D01*
X61133D01*
G01X68843Y-528134D02*
X69157Y-526769D01*
G01X75300Y-520679D02*
Y-526979D01*
G01X73498Y-520679D02*
X77102D01*
G01X79642Y-526979D02*
X81600Y-520679D01*
X83558Y-526979D01*
G01X82853Y-524774D02*
X80347D01*
G01X86960Y-520679D02*
X88840D01*
G01X87900D02*
Y-526979D01*
G01X86960D02*
X88840D01*
G01X91850Y-520679D02*
X92947Y-526979D01*
X94200Y-520679D01*
X95453Y-526979D01*
X96550Y-520679D01*
G01X98542Y-526979D02*
X100500Y-520679D01*
X102458Y-526979D01*
G01X101753Y-524774D02*
X99247D01*
G01X104998Y-526979D02*
Y-520679D01*
X108602Y-526979D01*
Y-520679D01*
G01X119008Y-529079D02*
X118225Y-528029D01*
X117833Y-526979D01*
Y-522779D01*
X118225Y-521729D01*
X119008Y-520679D01*
G01X130433Y-526979D02*
Y-520679D01*
X132392D01*
X133018Y-520994D01*
X133410Y-521414D01*
X133567Y-522254D01*
X133410Y-523094D01*
X132940Y-523619D01*
X132392Y-523934D01*
X130433D01*
G01X132392D02*
X133567Y-526979D01*
G01X138300Y-527189D02*
X138143Y-527084D01*
Y-526874D01*
X138300Y-526769D01*
X138457Y-526874D01*
Y-527084D01*
X138300Y-527189D01*
G01X144600Y-526979D02*
X143973Y-526874D01*
X143425Y-526454D01*
X142955Y-525824D01*
X142642Y-525089D01*
X142485Y-524249D01*
Y-523409D01*
X142642Y-522569D01*
X142955Y-521834D01*
X143425Y-521204D01*
X143973Y-520784D01*
X144600Y-520679D01*
X145227Y-520784D01*
X145775Y-521204D01*
X146245Y-521834D01*
X146558Y-522569D01*
X146715Y-523409D01*
Y-524249D01*
X146558Y-525089D01*
X146245Y-525824D01*
X145775Y-526454D01*
X145227Y-526874D01*
X144600Y-526979D01*
G01X150900Y-527189D02*
X150743Y-527084D01*
Y-526874D01*
X150900Y-526769D01*
X151057Y-526874D01*
Y-527084D01*
X150900Y-527189D01*
G01X158923Y-521204D02*
X158453Y-520889D01*
X157905Y-520679D01*
X157278D01*
X156573Y-520994D01*
X156025Y-521519D01*
X155633Y-522149D01*
X155320Y-523199D01*
X155242Y-524144D01*
X155398Y-525089D01*
X155633Y-525719D01*
X156103Y-526349D01*
X156652Y-526769D01*
X157200Y-526979D01*
X157748D01*
X158297Y-526769D01*
X158767Y-526454D01*
X159158Y-526034D01*
G01X163500Y-527189D02*
X163343Y-527084D01*
Y-526874D01*
X163500Y-526769D01*
X163657Y-526874D01*
Y-527084D01*
X163500Y-527189D01*
G01X170192Y-529079D02*
X170975Y-528029D01*
X171367Y-526979D01*
Y-522779D01*
X170975Y-521729D01*
X170192Y-520679D01*
G01X6470Y-513829D02*
X8037D01*
Y-515719D01*
X7567Y-516349D01*
X7018Y-516769D01*
X6235Y-516979D01*
X5452Y-516769D01*
X4903Y-516349D01*
X4433Y-515719D01*
X4120Y-514984D01*
X3963Y-514144D01*
Y-513409D01*
X4120Y-512779D01*
X4433Y-512044D01*
X4903Y-511414D01*
X5373Y-510994D01*
X6000Y-510679D01*
X6548D01*
X7175Y-510889D01*
X7645Y-511309D01*
G01X10577Y-510679D02*
Y-515194D01*
X10890Y-516139D01*
X11517Y-516769D01*
X12300Y-516979D01*
X13083Y-516769D01*
X13710Y-516139D01*
X14023Y-515194D01*
Y-510679D01*
G01X17660D02*
X19540D01*
G01X18600D02*
Y-516979D01*
G01X17660D02*
X19540D01*
G01X23255Y-516139D02*
X23882Y-516664D01*
X24587Y-516979D01*
X25213D01*
X25840Y-516664D01*
X26310Y-516139D01*
X26545Y-515404D01*
X26388Y-514669D01*
X25997Y-514039D01*
X25292Y-513619D01*
X24352Y-513409D01*
X23803Y-512989D01*
X23568Y-512254D01*
X23725Y-511519D01*
X24117Y-510994D01*
X24665Y-510679D01*
X25213D01*
X25762Y-510889D01*
X26232Y-511414D01*
G01X29555Y-516979D02*
Y-510679D01*
G01X32845D02*
Y-516979D01*
G01Y-513829D02*
X29555D01*
G01X35542Y-516979D02*
X37500Y-510679D01*
X39458Y-516979D01*
G01X38753Y-514774D02*
X36247D01*
G01X41998Y-516979D02*
Y-510679D01*
X45602Y-516979D01*
Y-510679D01*
G01X54677Y-516979D02*
Y-510679D01*
X56243D01*
X56870Y-510994D01*
X57340Y-511414D01*
X57732Y-512044D01*
X58045Y-512779D01*
X58123Y-513829D01*
X58045Y-514879D01*
X57732Y-515614D01*
X57340Y-516244D01*
X56870Y-516664D01*
X56243Y-516979D01*
X54677D01*
G01X61760Y-510679D02*
X63640D01*
G01X62700D02*
Y-516979D01*
G01X61760D02*
X63640D01*
G01X67355Y-516139D02*
X67982Y-516664D01*
X68687Y-516979D01*
X69313D01*
X69940Y-516664D01*
X70410Y-516139D01*
X70645Y-515404D01*
X70488Y-514669D01*
X70097Y-514039D01*
X69392Y-513619D01*
X68452Y-513409D01*
X67903Y-512989D01*
X67668Y-512254D01*
X67825Y-511519D01*
X68217Y-510994D01*
X68765Y-510679D01*
X69313D01*
X69862Y-510889D01*
X70332Y-511414D01*
G01X75300Y-510679D02*
Y-516979D01*
G01X73498Y-510679D02*
X77102D01*
G01X81600Y-517189D02*
X81443Y-517084D01*
Y-516874D01*
X81600Y-516769D01*
X81757Y-516874D01*
Y-517084D01*
X81600Y-517189D01*
G01X87743Y-518134D02*
X88057Y-516769D01*
G01X94200Y-510679D02*
Y-516979D01*
G01X92398Y-510679D02*
X96002D01*
G01X98542Y-516979D02*
X100500Y-510679D01*
X102458Y-516979D01*
G01X101753Y-514774D02*
X99247D01*
G01X106800Y-516979D02*
X106173Y-516874D01*
X105625Y-516454D01*
X105155Y-515824D01*
X104842Y-515089D01*
X104685Y-514249D01*
Y-513409D01*
X104842Y-512569D01*
X105155Y-511834D01*
X105625Y-511204D01*
X106173Y-510784D01*
X106800Y-510679D01*
X107427Y-510784D01*
X107975Y-511204D01*
X108445Y-511834D01*
X108758Y-512569D01*
X108915Y-513409D01*
Y-514249D01*
X108758Y-515089D01*
X108445Y-515824D01*
X107975Y-516454D01*
X107427Y-516874D01*
X106800Y-516979D01*
G01X113100D02*
Y-514144D01*
X111533Y-510679D01*
G01X114667D02*
X113100Y-514144D01*
G01X117677Y-510679D02*
Y-515194D01*
X117990Y-516139D01*
X118617Y-516769D01*
X119400Y-516979D01*
X120183Y-516769D01*
X120810Y-516139D01*
X121123Y-515194D01*
Y-510679D01*
G01X123742Y-516979D02*
X125700Y-510679D01*
X127658Y-516979D01*
G01X126953Y-514774D02*
X124447D01*
G01X130198Y-516979D02*
Y-510679D01*
X133802Y-516979D01*
Y-510679D01*
G01X4198Y-506979D02*
Y-500679D01*
X7802Y-506979D01*
Y-500679D01*
G01X12300Y-506979D02*
X11673Y-506874D01*
X11125Y-506454D01*
X10655Y-505824D01*
X10342Y-505089D01*
X10185Y-504249D01*
Y-503409D01*
X10342Y-502569D01*
X10655Y-501834D01*
X11125Y-501204D01*
X11673Y-500784D01*
X12300Y-500679D01*
X12927Y-500784D01*
X13475Y-501204D01*
X13945Y-501834D01*
X14258Y-502569D01*
X14415Y-503409D01*
Y-504249D01*
X14258Y-505089D01*
X13945Y-505824D01*
X13475Y-506454D01*
X12927Y-506874D01*
X12300Y-506979D01*
G01X18600Y-507189D02*
X18443Y-507084D01*
Y-506874D01*
X18600Y-506769D01*
X18757Y-506874D01*
Y-507084D01*
X18600Y-507189D01*
G01X23412Y-501729D02*
X23882Y-501099D01*
X24430Y-500784D01*
X25057Y-500679D01*
X25840Y-500889D01*
X26388Y-501414D01*
X26545Y-502044D01*
X26467Y-502674D01*
X26153Y-503199D01*
X24587Y-504249D01*
X23882Y-504984D01*
X23412Y-506034D01*
X23255Y-506979D01*
X26545D01*
G01X31200D02*
Y-500679D01*
X30260Y-501939D01*
G01Y-506979D02*
X32140D01*
G01X37500D02*
Y-500679D01*
X36560Y-501939D01*
G01Y-506979D02*
X38440D01*
G01X43643Y-508134D02*
X43957Y-506769D01*
G01X47750Y-500679D02*
X48847Y-506979D01*
X50100Y-500679D01*
X51353Y-506979D01*
X52450Y-500679D01*
G01X57967Y-506979D02*
X54833D01*
Y-500679D01*
X57967D01*
G01X56713Y-503724D02*
X54833D01*
G01X60898Y-506979D02*
Y-500679D01*
X64502Y-506979D01*
Y-500679D01*
G01X67355Y-506979D02*
Y-500679D01*
G01X70645D02*
Y-506979D01*
G01Y-503829D02*
X67355D01*
G01X73577Y-500679D02*
Y-505194D01*
X73890Y-506139D01*
X74517Y-506769D01*
X75300Y-506979D01*
X76083Y-506769D01*
X76710Y-506139D01*
X77023Y-505194D01*
Y-500679D01*
G01X79642Y-506979D02*
X81600Y-500679D01*
X83558Y-506979D01*
G01X82853Y-504774D02*
X80347D01*
G01X92712Y-501729D02*
X93182Y-501099D01*
X93730Y-500784D01*
X94357Y-500679D01*
X95140Y-500889D01*
X95688Y-501414D01*
X95845Y-502044D01*
X95767Y-502674D01*
X95453Y-503199D01*
X93887Y-504249D01*
X93182Y-504984D01*
X92712Y-506034D01*
X92555Y-506979D01*
X95845D01*
G01X98698D02*
Y-500679D01*
X102302Y-506979D01*
Y-500679D01*
G01X105077Y-506979D02*
Y-500679D01*
X106643D01*
X107270Y-500994D01*
X107740Y-501414D01*
X108132Y-502044D01*
X108445Y-502779D01*
X108523Y-503829D01*
X108445Y-504879D01*
X108132Y-505614D01*
X107740Y-506244D01*
X107270Y-506664D01*
X106643Y-506979D01*
X105077D01*
G01X117833D02*
Y-500679D01*
X119792D01*
X120418Y-500994D01*
X120810Y-501414D01*
X120967Y-502254D01*
X120810Y-503094D01*
X120340Y-503619D01*
X119792Y-503934D01*
X117833D01*
G01X119792D02*
X120967Y-506979D01*
G01X123977D02*
Y-500679D01*
X125543D01*
X126170Y-500994D01*
X126640Y-501414D01*
X127032Y-502044D01*
X127345Y-502779D01*
X127423Y-503829D01*
X127345Y-504879D01*
X127032Y-505614D01*
X126640Y-506244D01*
X126170Y-506664D01*
X125543Y-506979D01*
X123977D01*
G01X132000Y-507189D02*
X131843Y-507084D01*
Y-506874D01*
X132000Y-506769D01*
X132157Y-506874D01*
Y-507084D01*
X132000Y-507189D01*
G01X28300Y-494279D02*
X25780Y-493862D01*
X23575Y-492196D01*
X21685Y-489696D01*
X20425Y-486779D01*
X19795Y-483446D01*
Y-480112D01*
X20425Y-476779D01*
X21685Y-473862D01*
X23575Y-471363D01*
X25780Y-469696D01*
X28300Y-469279D01*
X30820Y-469696D01*
X33025Y-471363D01*
X34915Y-473862D01*
X36175Y-476779D01*
X36805Y-480112D01*
Y-483446D01*
X36175Y-486779D01*
X34915Y-489696D01*
X33025Y-492196D01*
X30820Y-493862D01*
X28300Y-494279D01*
G01X30820Y-487612D02*
X34600Y-494279D01*
G01X48145Y-477613D02*
Y-489279D01*
X49405Y-492196D01*
X51295Y-493862D01*
X53500Y-494279D01*
X55705Y-493862D01*
X57595Y-492196D01*
X58855Y-489279D01*
G01Y-494279D02*
Y-477613D01*
G01X84370Y-494279D02*
Y-477613D01*
G01Y-480529D02*
X83110Y-478863D01*
X81220Y-478029D01*
X79015Y-477613D01*
X76810Y-478446D01*
X74920Y-480112D01*
X73660Y-482613D01*
X73030Y-485946D01*
X73660Y-489279D01*
X74920Y-491780D01*
X76810Y-493446D01*
X79015Y-494279D01*
X81220Y-493862D01*
X83110Y-492613D01*
X84370Y-490946D01*
G01X98545Y-494279D02*
Y-477613D01*
G01Y-481779D02*
X99805Y-479696D01*
X101695Y-478029D01*
X104215Y-477613D01*
X106420Y-478029D01*
X108310Y-479696D01*
X109255Y-482613D01*
Y-494279D01*
G01X129100Y-469279D02*
Y-494279D01*
G01X124690Y-477613D02*
X133510D01*
G01X159970Y-494279D02*
Y-477613D01*
G01Y-480529D02*
X158710Y-478863D01*
X156820Y-478029D01*
X154615Y-477613D01*
X152410Y-478446D01*
X150520Y-480112D01*
X149260Y-482613D01*
X148630Y-485946D01*
X149260Y-489279D01*
X150520Y-491780D01*
X152410Y-493446D01*
X154615Y-494279D01*
X156820Y-493862D01*
X158710Y-492613D01*
X159970Y-490946D01*
G01X199650Y-473979D02*
Y-481979D01*
X203650D01*
G01X211450D02*
Y-476646D01*
G01Y-477579D02*
X211050Y-477046D01*
X210450Y-476779D01*
X209750Y-476646D01*
X209050Y-476912D01*
X208450Y-477446D01*
X208050Y-478246D01*
X207850Y-479312D01*
X208050Y-480379D01*
X208450Y-481179D01*
X209050Y-481712D01*
X209750Y-481979D01*
X210450Y-481846D01*
X211050Y-481446D01*
X211450Y-480913D01*
G01X215550Y-484379D02*
X216150Y-484646D01*
X216950Y-484379D01*
X217450Y-483846D01*
X217850Y-483179D01*
X218450Y-481046D01*
X219750Y-476646D01*
G01X216550D02*
X218450Y-481046D01*
G01X224150Y-478379D02*
X227350D01*
X227050Y-477446D01*
X226550Y-476912D01*
X225850Y-476646D01*
X225150Y-476779D01*
X224550Y-477179D01*
X224150Y-478112D01*
X223950Y-478913D01*
Y-479712D01*
X224150Y-480512D01*
X224650Y-481312D01*
X225250Y-481846D01*
X225950Y-481979D01*
X226650Y-481712D01*
X227350Y-480913D01*
G01X232250Y-481979D02*
Y-476646D01*
G01Y-477712D02*
X232750Y-477179D01*
X233250Y-476779D01*
X233950Y-476646D01*
X234450Y-476779D01*
X235050Y-477179D01*
G01X223350Y-531979D02*
Y-523979D01*
X227950Y-531979D01*
Y-523979D01*
G01X233650Y-526646D02*
Y-531979D01*
G01Y-524512D02*
X233450Y-524379D01*
Y-524112D01*
X233650Y-523979D01*
X233850Y-524112D01*
Y-524379D01*
X233650Y-524512D01*
G01X239950Y-531979D02*
Y-526646D01*
G01Y-527979D02*
X240350Y-527312D01*
X240950Y-526779D01*
X241750Y-526646D01*
X242450Y-526779D01*
X243050Y-527312D01*
X243350Y-528246D01*
Y-531979D01*
G01X251450D02*
Y-526646D01*
G01Y-527579D02*
X251050Y-527046D01*
X250450Y-526779D01*
X249750Y-526646D01*
X249050Y-526912D01*
X248450Y-527446D01*
X248050Y-528246D01*
X247850Y-529312D01*
X248050Y-530379D01*
X248450Y-531179D01*
X249050Y-531712D01*
X249750Y-531979D01*
X250450Y-531846D01*
X251050Y-531446D01*
X251450Y-530913D01*
G01X224779Y-504436D02*
X226779D01*
Y-506836D01*
X226179Y-507636D01*
X225479Y-508169D01*
X224479Y-508436D01*
X223479Y-508169D01*
X222779Y-507636D01*
X222179Y-506836D01*
X221779Y-505903D01*
X221579Y-504836D01*
Y-503903D01*
X221779Y-503103D01*
X222179Y-502169D01*
X222779Y-501369D01*
X223379Y-500836D01*
X224179Y-500436D01*
X224879D01*
X225679Y-500703D01*
X226279Y-501236D01*
G01X229879Y-508436D02*
Y-500436D01*
X234479Y-508436D01*
Y-500436D01*
G01X237979Y-508436D02*
Y-500436D01*
X239979D01*
X240779Y-500836D01*
X241379Y-501369D01*
X241879Y-502169D01*
X242279Y-503103D01*
X242379Y-504436D01*
X242279Y-505769D01*
X241879Y-506703D01*
X241379Y-507503D01*
X240779Y-508036D01*
X239979Y-508436D01*
X237979D01*
G01X248179D02*
Y-500436D01*
X246979Y-502036D01*
G01Y-508436D02*
X249379D01*
G01X247879Y-483436D02*
Y-475436D01*
X244179Y-481169D01*
X249179D01*
G01X326250Y-525312D02*
X326850Y-524512D01*
X327550Y-524112D01*
X328350Y-523979D01*
X329350Y-524246D01*
X330050Y-524912D01*
X330250Y-525712D01*
X330150Y-526513D01*
X329750Y-527179D01*
X327750Y-528512D01*
X326850Y-529446D01*
X326250Y-530779D01*
X326050Y-531979D01*
X330250D01*
G01X336150Y-523979D02*
X335350Y-524246D01*
X334750Y-524912D01*
X334350Y-525712D01*
X334050Y-526779D01*
X333950Y-527979D01*
X334050Y-529179D01*
X334350Y-530246D01*
X334750Y-531046D01*
X335350Y-531712D01*
X336150Y-531979D01*
X336950Y-531712D01*
X337550Y-531046D01*
X337950Y-530246D01*
X338250Y-529179D01*
X338350Y-527979D01*
X338250Y-526779D01*
X337950Y-525712D01*
X337550Y-524912D01*
X336950Y-524246D01*
X336150Y-523979D01*
G01X342250Y-525312D02*
X342850Y-524512D01*
X343550Y-524112D01*
X344350Y-523979D01*
X345350Y-524246D01*
X346050Y-524912D01*
X346250Y-525712D01*
X346150Y-526513D01*
X345750Y-527179D01*
X343750Y-528512D01*
X342850Y-529446D01*
X342250Y-530779D01*
X342050Y-531979D01*
X346250D01*
G01X349950Y-530379D02*
X350550Y-531312D01*
X351350Y-531846D01*
X352250Y-531979D01*
X353050Y-531846D01*
X353850Y-531179D01*
X354350Y-530379D01*
X354450Y-529579D01*
X354250Y-528646D01*
X353550Y-527979D01*
X352850Y-527712D01*
X351950D01*
G01X352850D02*
X353450Y-527312D01*
X353950Y-526646D01*
X354150Y-525846D01*
X353950Y-525046D01*
X353450Y-524379D01*
X352550Y-523979D01*
X351650Y-524112D01*
X350750Y-524646D01*
G01X358350Y-532246D02*
X361950Y-523979D01*
G01X368150D02*
X367350Y-524246D01*
X366750Y-524912D01*
X366350Y-525712D01*
X366050Y-526779D01*
X365950Y-527979D01*
X366050Y-529179D01*
X366350Y-530246D01*
X366750Y-531046D01*
X367350Y-531712D01*
X368150Y-531979D01*
X368950Y-531712D01*
X369550Y-531046D01*
X369950Y-530246D01*
X370250Y-529179D01*
X370350Y-527979D01*
X370250Y-526779D01*
X369950Y-525712D01*
X369550Y-524912D01*
X368950Y-524246D01*
X368150Y-523979D01*
G01X373950Y-530379D02*
X374550Y-531312D01*
X375350Y-531846D01*
X376250Y-531979D01*
X377050Y-531846D01*
X377850Y-531179D01*
X378350Y-530379D01*
X378450Y-529579D01*
X378250Y-528646D01*
X377550Y-527979D01*
X376850Y-527712D01*
X375950D01*
G01X376850D02*
X377450Y-527312D01*
X377950Y-526646D01*
X378150Y-525846D01*
X377950Y-525046D01*
X377450Y-524379D01*
X376550Y-523979D01*
X375650Y-524112D01*
X374750Y-524646D01*
G01X382350Y-532246D02*
X385950Y-523979D01*
G01X390250Y-525312D02*
X390850Y-524512D01*
X391550Y-524112D01*
X392350Y-523979D01*
X393350Y-524246D01*
X394050Y-524912D01*
X394250Y-525712D01*
X394150Y-526513D01*
X393750Y-527179D01*
X391750Y-528512D01*
X390850Y-529446D01*
X390250Y-530779D01*
X390050Y-531979D01*
X394250D01*
G01X401350D02*
Y-523979D01*
X397650Y-529712D01*
X402650D01*
G01X325950Y-506979D02*
Y-498979D01*
X327950D01*
X328750Y-499379D01*
X329350Y-499912D01*
X329850Y-500712D01*
X330250Y-501646D01*
X330350Y-502979D01*
X330250Y-504312D01*
X329850Y-505246D01*
X329350Y-506046D01*
X328750Y-506579D01*
X327950Y-506979D01*
X325950D01*
G01X333650D02*
X336150Y-498979D01*
X338650Y-506979D01*
G01X337750Y-504179D02*
X334550D01*
G01X344150Y-498979D02*
X343350Y-499246D01*
X342750Y-499912D01*
X342350Y-500712D01*
X342050Y-501779D01*
X341950Y-502979D01*
X342050Y-504179D01*
X342350Y-505246D01*
X342750Y-506046D01*
X343350Y-506712D01*
X344150Y-506979D01*
X344950Y-506712D01*
X345550Y-506046D01*
X345950Y-505246D01*
X346250Y-504179D01*
X346350Y-502979D01*
X346250Y-501779D01*
X345950Y-500712D01*
X345550Y-499912D01*
X344950Y-499246D01*
X344150Y-498979D01*
G01X350250Y-506979D02*
Y-498979D01*
X354050D01*
G01X352650Y-502846D02*
X350250D01*
G01X360150Y-498979D02*
X359350Y-499246D01*
X358750Y-499912D01*
X358350Y-500712D01*
X358050Y-501779D01*
X357950Y-502979D01*
X358050Y-504179D01*
X358350Y-505246D01*
X358750Y-506046D01*
X359350Y-506712D01*
X360150Y-506979D01*
X360950Y-506712D01*
X361550Y-506046D01*
X361950Y-505246D01*
X362250Y-504179D01*
X362350Y-502979D01*
X362250Y-501779D01*
X361950Y-500712D01*
X361550Y-499912D01*
X360950Y-499246D01*
X360150Y-498979D01*
G01X368150D02*
Y-506979D01*
G01X365850Y-498979D02*
X370450D01*
G01X373550Y-506979D02*
Y-498979D01*
X376150Y-505646D01*
X378750Y-498979D01*
Y-506979D01*
G01X384950Y-502712D02*
X385350Y-502312D01*
X385650Y-501646D01*
X385850Y-500712D01*
X385650Y-499912D01*
X385250Y-499379D01*
X384550Y-498979D01*
X381850D01*
Y-506979D01*
X385150D01*
X385850Y-506446D01*
X386250Y-505646D01*
X386450Y-504712D01*
X386250Y-503779D01*
X385650Y-502979D01*
X384950Y-502712D01*
X381850D01*
G01X390950Y-498979D02*
X393350D01*
G01X392150D02*
Y-506979D01*
G01X390950D02*
X393350D01*
G01X398150Y-505379D02*
X398650Y-506179D01*
X399250Y-506712D01*
X399950Y-506979D01*
X400750Y-506712D01*
X401350Y-506179D01*
X401950Y-505379D01*
X402150Y-504312D01*
Y-498979D01*
G01X408150D02*
X407350Y-499246D01*
X406750Y-499912D01*
X406350Y-500712D01*
X406050Y-501779D01*
X405950Y-502979D01*
X406050Y-504179D01*
X406350Y-505246D01*
X406750Y-506046D01*
X407350Y-506712D01*
X408150Y-506979D01*
X408950Y-506712D01*
X409550Y-506046D01*
X409950Y-505246D01*
X410250Y-504179D01*
X410350Y-502979D01*
X410250Y-501779D01*
X409950Y-500712D01*
X409550Y-499912D01*
X408950Y-499246D01*
X408150Y-498979D01*
G01X343750Y-481979D02*
Y-473979D01*
X347550D01*
G01X346150Y-477846D02*
X343750D01*
G01X353650Y-473979D02*
X352850Y-474246D01*
X352250Y-474912D01*
X351850Y-475712D01*
X351550Y-476779D01*
X351450Y-477979D01*
X351550Y-479179D01*
X351850Y-480246D01*
X352250Y-481046D01*
X352850Y-481712D01*
X353650Y-481979D01*
X354450Y-481712D01*
X355050Y-481046D01*
X355450Y-480246D01*
X355750Y-479179D01*
X355850Y-477979D01*
X355750Y-476779D01*
X355450Y-475712D01*
X355050Y-474912D01*
X354450Y-474246D01*
X353650Y-473979D01*
G01X361650D02*
Y-481979D01*
G01X359350Y-473979D02*
X363950D01*
G01X366650Y-484646D02*
X372650D01*
G01X375050Y-481979D02*
Y-473979D01*
X377650Y-480646D01*
X380250Y-473979D01*
Y-481979D01*
G01X386450Y-477712D02*
X386850Y-477312D01*
X387150Y-476646D01*
X387350Y-475712D01*
X387150Y-474912D01*
X386750Y-474379D01*
X386050Y-473979D01*
X383350D01*
Y-481979D01*
X386650D01*
X387350Y-481446D01*
X387750Y-480646D01*
X387950Y-479712D01*
X387750Y-478779D01*
X387150Y-477979D01*
X386450Y-477712D01*
X383350D01*
G01X390650Y-484646D02*
X396650D01*
G01X403650Y-481979D02*
X399650D01*
Y-473979D01*
X403650D01*
G01X402050Y-477846D02*
X399650D01*
G01X407050Y-481979D02*
Y-473979D01*
X409650Y-480646D01*
X412250Y-473979D01*
Y-481979D01*
G01X417650D02*
X418350Y-481846D01*
X419150Y-481446D01*
X419650Y-480779D01*
X419850Y-479846D01*
X419650Y-478913D01*
X419050Y-478112D01*
X418150Y-477712D01*
X417150D01*
X416550Y-477446D01*
X416050Y-476779D01*
X415850Y-475846D01*
X416150Y-474912D01*
X416850Y-474246D01*
X417650Y-473979D01*
X418450Y-474246D01*
X419150Y-474912D01*
X419450Y-475846D01*
X419250Y-476779D01*
X418750Y-477446D01*
X418150Y-477712D01*
X417150D01*
X416250Y-478112D01*
X415650Y-478913D01*
X415450Y-479846D01*
X415650Y-480779D01*
X416150Y-481446D01*
X416950Y-481846D01*
X417650Y-481979D01*
G01X423950Y-481046D02*
X424650Y-481712D01*
X425450Y-481979D01*
X426250Y-481712D01*
X426950Y-480913D01*
X427450Y-479712D01*
X427650Y-478512D01*
Y-477046D01*
X427450Y-475846D01*
X426950Y-474779D01*
X426350Y-474246D01*
X425650Y-473979D01*
X424850Y-474246D01*
X424250Y-474779D01*
X423850Y-475579D01*
X423650Y-476646D01*
X423850Y-477579D01*
X424350Y-478512D01*
X424950Y-479046D01*
X425650Y-479179D01*
X426450Y-478913D01*
X427050Y-478246D01*
X427650Y-477046D01*
G01X433650Y-473979D02*
X432850Y-474246D01*
X432250Y-474912D01*
X431850Y-475712D01*
X431550Y-476779D01*
X431450Y-477979D01*
X431550Y-479179D01*
X431850Y-480246D01*
X432250Y-481046D01*
X432850Y-481712D01*
X433650Y-481979D01*
X434450Y-481712D01*
X435050Y-481046D01*
X435450Y-480246D01*
X435750Y-479179D01*
X435850Y-477979D01*
X435750Y-476779D01*
X435450Y-475712D01*
X435050Y-474912D01*
X434450Y-474246D01*
X433650Y-473979D01*
G01X439450Y-481979D02*
Y-473979D01*
G01X443250D02*
X439450Y-478913D01*
G01X443850Y-481979D02*
X441150Y-476646D01*
G01X414650Y-534979D02*
Y-526979D01*
X413450Y-528579D01*
G01Y-534979D02*
X415850D01*
G01X420750Y-531646D02*
X421450Y-530712D01*
X422050Y-530179D01*
X422850Y-529912D01*
X423550Y-530179D01*
X424050Y-530712D01*
X424450Y-531512D01*
X424550Y-532446D01*
X424450Y-533246D01*
X424050Y-534046D01*
X423450Y-534712D01*
X422750Y-534979D01*
X421950Y-534712D01*
X421250Y-533913D01*
X420850Y-532712D01*
X420750Y-531379D01*
X420950Y-529646D01*
X421250Y-528712D01*
X421750Y-527779D01*
X422450Y-527112D01*
X423150Y-526979D01*
X423850Y-527246D01*
X424350Y-527912D01*
G01X430650Y-535246D02*
X430450Y-535112D01*
Y-534846D01*
X430650Y-534712D01*
X430850Y-534846D01*
Y-535112D01*
X430650Y-535246D01*
G01X436750Y-531646D02*
X437450Y-530712D01*
X438050Y-530179D01*
X438850Y-529912D01*
X439550Y-530179D01*
X440050Y-530712D01*
X440450Y-531512D01*
X440550Y-532446D01*
X440450Y-533246D01*
X440050Y-534046D01*
X439450Y-534712D01*
X438750Y-534979D01*
X437950Y-534712D01*
X437250Y-533913D01*
X436850Y-532712D01*
X436750Y-531379D01*
X436950Y-529646D01*
X437250Y-528712D01*
X437750Y-527779D01*
X438450Y-527112D01*
X439150Y-526979D01*
X439850Y-527246D01*
X440350Y-527912D01*
G01X459650Y-534979D02*
Y-526979D01*
X458450Y-528579D01*
G01Y-534979D02*
X460850D01*
G01X467450D02*
X467650Y-533246D01*
X467950Y-531779D01*
X468350Y-530446D01*
X468850Y-528979D01*
X469650Y-526979D01*
X465650D01*
G01X475650Y-535246D02*
X475450Y-535112D01*
Y-534846D01*
X475650Y-534712D01*
X475850Y-534846D01*
Y-535112D01*
X475650Y-535246D01*
G01X481750Y-528312D02*
X482350Y-527512D01*
X483050Y-527112D01*
X483850Y-526979D01*
X484850Y-527246D01*
X485550Y-527912D01*
X485750Y-528712D01*
X485650Y-529513D01*
X485250Y-530179D01*
X483250Y-531512D01*
X482350Y-532446D01*
X481750Y-533779D01*
X481550Y-534979D01*
X485750D01*
G01X479650Y-508379D02*
X480150Y-509179D01*
X480750Y-509712D01*
X481450Y-509979D01*
X482250Y-509712D01*
X482850Y-509179D01*
X483450Y-508379D01*
X483650Y-507312D01*
Y-501979D01*
M02*
